(kicad_pcb
	(version 20260206)
	(generator "pcbnew")
	(generator_version "10.0")
	(general
		(thickness 1.6)
		(legacy_teardrops no)
	)
	(paper "A4")
	(layers
		(0 "F.Cu" signal "TOP")
		(4 "In1.Cu" signal "L2GND")
		(6 "In2.Cu" signal "L3")
		(8 "In3.Cu" signal "L4GND")
		(10 "In4.Cu" signal "L5GND")
		(12 "In5.Cu" signal "L6")
		(14 "In6.Cu" signal "L7GND")
		(2 "B.Cu" signal "BOTTOM")
		(9 "F.Adhes" user "F.Adhesive")
		(11 "B.Adhes" user "B.Adhesive")
		(13 "F.Paste" user "Package Geometry/Pastemask Top")
		(15 "B.Paste" user "Package Geometry/Pastemask Bottom")
		(5 "F.SilkS" user "Ref Des/Silkscreen Top")
		(7 "B.SilkS" user "Ref Des/Silkscreen Bottom")
		(1 "F.Mask" user "Board Geometry/Soldermask Top")
		(3 "B.Mask" user "Board Geometry/Soldermask Bottom")
		(17 "Dwgs.User" user "User.Drawings")
		(19 "Cmts.User" user "User.Comments")
		(21 "Eco1.User" user "User.Eco1")
		(23 "Eco2.User" user "User.Eco2")
		(25 "Edge.Cuts" user "Board Geometry/Outline")
		(27 "Margin" user)
		(31 "F.CrtYd" user "Package Geometry/Place Bound Top")
		(29 "B.CrtYd" user "Package Geometry/Place Bound Bottom")
		(35 "F.Fab" user "Ref Des/Assembly Top")
		(33 "B.Fab" user "Ref Des/Assembly Bottom")
	)
	(setup
		(pad_to_mask_clearance 0)
		(allow_soldermask_bridges_in_footprints no)
		(tenting
			(front yes)
			(back yes)
		)
		(covering
			(front no)
			(back no)
		)
		(plugging
			(front no)
			(back no)
		)
		(capping no)
		(filling no)
		(pcbplotparams
			(layerselection 0x00000000_00000000_55555555_5755f5ff)
			(plot_on_all_layers_selection 0x00000000_00000000_00000000_00000000)
			(disableapertmacros no)
			(usegerberextensions no)
			(usegerberattributes yes)
			(usegerberadvancedattributes yes)
			(creategerberjobfile yes)
			(dashed_line_dash_ratio 12)
			(dashed_line_gap_ratio 3)
			(svgprecision 4)
			(plotframeref no)
			(mode 1)
			(useauxorigin no)
			(pdf_front_fp_property_popups yes)
			(pdf_back_fp_property_popups yes)
			(pdf_metadata yes)
			(pdf_single_document no)
			(dxfpolygonmode yes)
			(dxfimperialunits yes)
			(dxfusepcbnewfont yes)
			(psnegative no)
			(psa4output no)
			(plot_black_and_white yes)
			(sketchpadsonfab no)
			(plotpadnumbers no)
			(hidednponfab no)
			(sketchdnponfab yes)
			(crossoutdnponfab yes)
			(subtractmaskfromsilk no)
			(outputformat 1)
			(mirror no)
			(drillshape 1)
			(scaleselection 1)
			(outputdirectory "")
		)
	)
	(footprint ""
		(layer "F.Cu")
		(at 20.447 -84.122006 90)
		(property "Reference" "PC27"
			(at 0 0 90)
			(layer "F.SilkS")
			(hide yes)
			(effects
				(font
					(size 1.27 1.27)
				)
			)
		)
		(property "Value" "SC22U6D3V5MX-5-GP"
			(at -0.0762 -6.1214 90)
			(unlocked yes)
			(layer "F.Fab")
			(hide yes)
			(effects
				(font
					(size 1.016 1.016)
					(thickness 0.1524)
				)
			)
		)
		(property "Device Type" "C805H56"
			(at -0.0762 -8.1534 90)
			(unlocked yes)
			(layer "F.Fab")
			(hide yes)
			(effects
				(font
					(size 1.016 1.016)
					(thickness 0.1524)
				)
			)
		)
		(duplicate_pad_numbers_are_jumpers no)
		(fp_line
			(start 0.635 0)
			(end -0.635 0)
			(stroke
				(width 0.508)
				(type default)
			)
			(layer "F.SilkS")
		)
		(fp_rect
			(start -0.9652 1.778)
			(end 0.9652 -1.778)
			(stroke
				(width 0)
				(type default)
			)
			(fill no)
			(layer "F.CrtYd")
		)
		(fp_poly
			(pts
				(xy -0.9652 -1.778) (xy 0.9652 -1.778) (xy 0.9652 1.778) (xy -0.9652 1.778)
			)
			(stroke
				(width 0)
				(type default)
			)
			(fill no)
			(layer "F.Fab")
		)
		(pad "1" smd rect
			(at 0 -0.9652 90)
			(size 1.397 1.143)
			(layers "F.Cu" "F.Mask" "F.Paste")
			(net "P3V3_PWR")
		)
		(pad "2" smd rect
			(at 0 0.9652 90)
			(size 1.397 1.143)
			(layers "F.Cu" "F.Mask" "F.Paste")
			(net "GND")
		)
	)
	(footprint ""
		(layer "F.Cu")
		(at 76.708 -76.327 -90)
		(property "Reference" "CN1"
			(at 0 0 270)
			(layer "F.SilkS")
			(hide yes)
			(effects
				(font
					(size 1.27 1.27)
				)
			)
		)
		(property "Value" "CLX-CON3-S2-GP"
			(at -5.103876 -0.705866 270)
			(unlocked yes)
			(layer "F.Fab")
			(hide yes)
			(effects
				(font
					(size 1.016 1.016)
					(thickness 0.1524)
				)
			)
		)
		(property "Device Type" "CH31032V2S6"
			(at -5.103876 -2.229866 270)
			(unlocked yes)
			(layer "F.Fab")
			(hide yes)
			(effects
				(font
					(size 1.016 1.016)
					(thickness 0.1524)
				)
			)
		)
		(duplicate_pad_numbers_are_jumpers no)
		(fp_line
			(start -3.9751 1.524)
			(end -3.9751 -1.524)
			(stroke
				(width 0.1524)
				(type default)
			)
			(layer "F.SilkS")
		)
		(fp_line
			(start 3.9751 1.524)
			(end -3.9751 1.524)
			(stroke
				(width 0.1524)
				(type default)
			)
			(layer "F.SilkS")
		)
		(fp_line
			(start -3.9751 -1.524)
			(end 3.9751 -1.524)
			(stroke
				(width 0.1524)
				(type default)
			)
			(layer "F.SilkS")
		)
		(fp_line
			(start 3.9751 -1.524)
			(end 3.9751 1.524)
			(stroke
				(width 0.1524)
				(type default)
			)
			(layer "F.SilkS")
		)
		(fp_line
			(start -4.1021 -1.651)
			(end -4.1021 -0.381)
			(stroke
				(width 0.4064)
				(type default)
			)
			(layer "F.SilkS")
		)
		(fp_line
			(start -2.8321 -1.651)
			(end -4.1021 -1.651)
			(stroke
				(width 0.4064)
				(type default)
			)
			(layer "F.SilkS")
		)
		(fp_circle
			(center -2.54 0)
			(end -2.54 -1.0668)
			(stroke
				(width 0.3048)
				(type default)
			)
			(fill no)
			(layer "F.SilkS")
		)
		(fp_circle
			(center 0 0)
			(end 0 -1.0668)
			(stroke
				(width 0.3048)
				(type default)
			)
			(fill no)
			(layer "F.SilkS")
		)
		(fp_circle
			(center 2.54 0)
			(end 2.54 -1.0668)
			(stroke
				(width 0.3048)
				(type default)
			)
			(fill no)
			(layer "F.SilkS")
		)
		(fp_rect
			(start -3.7211 1.27)
			(end 3.7211 -1.27)
			(stroke
				(width 0)
				(type default)
			)
			(fill no)
			(layer "F.CrtYd")
		)
		(fp_poly
			(pts
				(xy -4.2291 1.778) (xy -4.2291 -1.778) (xy 4.2291 -1.778) (xy 4.2291 1.778) (xy 0.00254 1.778) (xy 0.00254 1.27)
				(xy 3.7211 1.27) (xy 3.7211 -1.27) (xy -3.7211 -1.27) (xy -3.7211 1.27) (xy -0.00254 1.27) (xy -0.00254 1.778)
			)
			(stroke
				(width 0)
				(type default)
			)
			(fill no)
			(layer "F.CrtYd")
		)
		(fp_rect
			(start -4.2291 1.778)
			(end 4.2291 -1.778)
			(stroke
				(width 0)
				(type default)
			)
			(fill no)
			(layer "F.Fab")
		)
		(pad "1" thru_hole circle
			(at -2.54 0 270)
			(size 1.4224 1.4224)
			(drill 1.016)
			(layers "*.Cu" "*.Mask")
			(remove_unused_layers no)
			(net "GND")
			(clearance 0.1524)
			(thermal_gap 0.1524)
		)
		(pad "2" thru_hole circle
			(at 0 0 270)
			(size 1.4224 1.4224)
			(drill 1.016)
			(layers "*.Cu" "*.Mask")
			(remove_unused_layers no)
			(net "Z50_SSD_A1_SMB_CLK")
			(clearance 0.1524)
			(thermal_gap 0.1524)
		)
		(pad "3" thru_hole circle
			(at 2.54 0 270)
			(size 1.4224 1.4224)
			(drill 1.016)
			(layers "*.Cu" "*.Mask")
			(remove_unused_layers no)
			(net "Z50_SSD_A1_SMB_DATA")
			(clearance 0.1524)
			(thermal_gap 0.1524)
		)
	)
	(footprint ""
		(layer "F.Cu")
		(at 59.817 -35.179 -90)
		(property "Reference" "C32"
			(at 0 0 270)
			(layer "F.SilkS")
			(hide yes)
			(effects
				(font
					(size 1.27 1.27)
				)
			)
		)
		(property "Value" "SCD1U16V2KX-3GP"
			(at 1.1811 -2.7051 270)
			(unlocked yes)
			(layer "F.Fab")
			(hide yes)
			(effects
				(font
					(size 1.016 1.016)
					(thickness 0.1524)
				)
			)
		)
		(property "Device Type" "C402H22"
			(at 1.1811 -4.2291 270)
			(unlocked yes)
			(layer "F.Fab")
			(hide yes)
			(effects
				(font
					(size 1.016 1.016)
					(thickness 0.1524)
				)
			)
		)
		(duplicate_pad_numbers_are_jumpers no)
		(fp_rect
			(start -0.4318 0.9525)
			(end 0.4318 -0.9525)
			(stroke
				(width 0)
				(type default)
			)
			(fill no)
			(layer "F.CrtYd")
		)
		(fp_rect
			(start -0.4318 0.9525)
			(end 0.4318 -0.9525)
			(stroke
				(width 0)
				(type default)
			)
			(fill no)
			(layer "F.Fab")
		)
		(pad "1" smd custom
			(at 0 -0.4445 270)
			(size 0.1524 0.1524)
			(layers "F.Cu" "F.Mask" "F.Paste")
			(net "P3V3_PWR")
			(options
				(clearance outline)
				(anchor circle)
			)
			(primitives
				(gr_poly
					(pts
						(arc
							(start 0.3048 -0.2032)
							(mid 0.275042 -0.275042)
							(end 0.2032 -0.3048)
						)
						(arc
							(start -0.2032 -0.3048)
							(mid -0.275042 -0.275042)
							(end -0.3048 -0.2032)
						)
						(arc
							(start -0.3048 0.2032)
							(mid -0.275042 0.275042)
							(end -0.2032 0.3048)
						)
						(arc
							(start 0.2032 0.3048)
							(mid 0.275042 0.275042)
							(end 0.3048 0.2032)
						)
					)
					(width 0)
					(fill yes)
				)
			)
		)
		(pad "2" smd custom
			(at 0 0.4445 270)
			(size 0.1524 0.1524)
			(layers "F.Cu" "F.Mask" "F.Paste")
			(net "GND")
			(options
				(clearance outline)
				(anchor circle)
			)
			(primitives
				(gr_poly
					(pts
						(arc
							(start 0.3048 -0.2032)
							(mid 0.275042 -0.275042)
							(end 0.2032 -0.3048)
						)
						(arc
							(start -0.2032 -0.3048)
							(mid -0.275042 -0.275042)
							(end -0.3048 -0.2032)
						)
						(arc
							(start -0.3048 0.2032)
							(mid -0.275042 0.275042)
							(end -0.2032 0.3048)
						)
						(arc
							(start 0.2032 0.3048)
							(mid 0.275042 0.275042)
							(end 0.3048 0.2032)
						)
					)
					(width 0)
					(fill yes)
				)
			)
		)
	)
	(footprint ""
		(layer "F.Cu")
		(at 6.500114 -80.309974)
		(property "Reference" "H2"
			(at 0 0 0)
			(layer "F.SilkS")
			(hide yes)
			(effects
				(font
					(size 1.27 1.27)
				)
			)
		)
		(property "Value" "HOLE315R140-GP"
			(at 0 -7.5692 0)
			(unlocked yes)
			(layer "F.Fab")
			(hide yes)
			(effects
				(font
					(size 1.016 1.016)
					(thickness 0.1524)
				)
			)
		)
		(property "Device Type" "HOLE315R140"
			(at 0 -9.0932 0)
			(unlocked yes)
			(layer "F.Fab")
			(hide yes)
			(effects
				(font
					(size 1.016 1.016)
					(thickness 0.1524)
				)
			)
		)
		(duplicate_pad_numbers_are_jumpers no)
		(fp_poly
			(pts
				(arc
					(start 4.3053 0)
					(mid -4.3053 0)
					(end 4.3053 0)
				)
			)
			(stroke
				(width 0)
				(type default)
			)
			(fill no)
			(layer "F.CrtYd")
		)
		(fp_poly
			(pts
				(arc
					(start 4.3053 0)
					(mid -4.3053 0)
					(end 4.3053 0)
				)
			)
			(stroke
				(width 0)
				(type default)
			)
			(fill no)
			(layer "F.Fab")
		)
		(pad "1" thru_hole circle
			(at 0.00127 0.00127)
			(size 8.001 8.001)
			(drill 3.556)
			(layers "*.Cu" "*.Mask")
			(remove_unused_layers no)
			(net "GND")
			(clearance -1.7145)
			(thermal_gap 0.3048)
			(padstack
				(mode front_inner_back)
				(layer "Inner"
					(shape circle)
					(size 3.9624 3.9624)
					(clearance 0.3048)
				)
				(layer "B.Cu"
					(shape circle)
					(size 8.001 8.001)
					(clearance -1.7145)
				)
			)
		)
	)
	(footprint ""
		(layer "F.Cu")
		(at 65.786 -75.184 90)
		(property "Reference" "PC42"
			(at 0 0 90)
			(layer "F.SilkS")
			(hide yes)
			(effects
				(font
					(size 1.27 1.27)
				)
			)
		)
		(property "Value" "SC10U6D3V5KX-4GP"
			(at -0.0762 -6.1214 90)
			(unlocked yes)
			(layer "F.Fab")
			(hide yes)
			(effects
				(font
					(size 1.016 1.016)
					(thickness 0.1524)
				)
			)
		)
		(property "Device Type" "C805H58"
			(at -0.0762 -8.1534 90)
			(unlocked yes)
			(layer "F.Fab")
			(hide yes)
			(effects
				(font
					(size 1.016 1.016)
					(thickness 0.1524)
				)
			)
		)
		(duplicate_pad_numbers_are_jumpers no)
		(fp_line
			(start 0.635 0)
			(end -0.635 0)
			(stroke
				(width 0.508)
				(type default)
			)
			(layer "F.SilkS")
		)
		(fp_rect
			(start -0.9652 1.778)
			(end 0.9652 -1.778)
			(stroke
				(width 0)
				(type default)
			)
			(fill no)
			(layer "F.CrtYd")
		)
		(fp_poly
			(pts
				(xy -0.9652 -1.778) (xy 0.9652 -1.778) (xy 0.9652 1.778) (xy -0.9652 1.778)
			)
			(stroke
				(width 0)
				(type default)
			)
			(fill no)
			(layer "F.Fab")
		)
		(pad "1" smd rect
			(at 0 -0.9652 90)
			(size 1.397 1.143)
			(layers "F.Cu" "F.Mask" "F.Paste")
			(net "P3V3_PWR")
		)
		(pad "2" smd rect
			(at 0 0.9652 90)
			(size 1.397 1.143)
			(layers "F.Cu" "F.Mask" "F.Paste")
			(net "GND")
		)
	)
	(footprint ""
		(layer "F.Cu")
		(at 25.527 -86.535006)
		(property "Reference" "C7"
			(at 0 0 0)
			(layer "F.SilkS")
			(hide yes)
			(effects
				(font
					(size 1.27 1.27)
				)
			)
		)
		(property "Value" "SCD1U16V2KX-3GP"
			(at 1.1811 -2.7051 0)
			(unlocked yes)
			(layer "F.Fab")
			(hide yes)
			(effects
				(font
					(size 1.016 1.016)
					(thickness 0.1524)
				)
			)
		)
		(property "Device Type" "C402H22"
			(at 1.1811 -4.2291 0)
			(unlocked yes)
			(layer "F.Fab")
			(hide yes)
			(effects
				(font
					(size 1.016 1.016)
					(thickness 0.1524)
				)
			)
		)
		(duplicate_pad_numbers_are_jumpers no)
		(fp_rect
			(start -0.4318 0.9525)
			(end 0.4318 -0.9525)
			(stroke
				(width 0)
				(type default)
			)
			(fill no)
			(layer "F.CrtYd")
		)
		(fp_rect
			(start -0.4318 0.9525)
			(end 0.4318 -0.9525)
			(stroke
				(width 0)
				(type default)
			)
			(fill no)
			(layer "F.Fab")
		)
		(pad "1" smd custom
			(at 0 -0.4445)
			(size 0.1524 0.1524)
			(layers "F.Cu" "F.Mask" "F.Paste")
			(net "P3V3_DPB")
			(options
				(clearance outline)
				(anchor circle)
			)
			(primitives
				(gr_poly
					(pts
						(arc
							(start 0.3048 -0.2032)
							(mid 0.275042 -0.275042)
							(end 0.2032 -0.3048)
						)
						(arc
							(start -0.2032 -0.3048)
							(mid -0.275042 -0.275042)
							(end -0.3048 -0.2032)
						)
						(arc
							(start -0.3048 0.2032)
							(mid -0.275042 0.275042)
							(end -0.2032 0.3048)
						)
						(arc
							(start 0.2032 0.3048)
							(mid 0.275042 0.275042)
							(end 0.3048 0.2032)
						)
					)
					(width 0)
					(fill yes)
				)
			)
		)
		(pad "2" smd custom
			(at 0 0.4445)
			(size 0.1524 0.1524)
			(layers "F.Cu" "F.Mask" "F.Paste")
			(net "GND")
			(options
				(clearance outline)
				(anchor circle)
			)
			(primitives
				(gr_poly
					(pts
						(arc
							(start 0.3048 -0.2032)
							(mid 0.275042 -0.275042)
							(end 0.2032 -0.3048)
						)
						(arc
							(start -0.2032 -0.3048)
							(mid -0.275042 -0.275042)
							(end -0.3048 -0.2032)
						)
						(arc
							(start -0.3048 0.2032)
							(mid -0.275042 0.275042)
							(end -0.2032 0.3048)
						)
						(arc
							(start 0.2032 0.3048)
							(mid 0.275042 0.275042)
							(end 0.3048 0.2032)
						)
					)
					(width 0)
					(fill yes)
				)
			)
		)
	)
	(footprint ""
		(layer "F.Cu")
		(at 25.019 -81.534 90)
		(property "Reference" "R28"
			(at 0 0 90)
			(layer "F.SilkS")
			(hide yes)
			(effects
				(font
					(size 1.27 1.27)
				)
			)
		)
		(property "Value" "4K7R2F-GP"
			(at 0.064008 -3.993896 90)
			(unlocked yes)
			(layer "F.Fab")
			(hide yes)
			(effects
				(font
					(size 1.016 1.016)
					(thickness 0.1524)
				)
			)
		)
		(property "Device Type" "R402H16"
			(at 0.064008 -5.517896 90)
			(unlocked yes)
			(layer "F.Fab")
			(hide yes)
			(effects
				(font
					(size 1.016 1.016)
					(thickness 0.1524)
				)
			)
		)
		(duplicate_pad_numbers_are_jumpers no)
		(fp_line
			(start 0.508 -0.9398)
			(end -0.508 -0.9398)
			(stroke
				(width 0.1524)
				(type default)
			)
			(layer "F.SilkS")
		)
		(fp_line
			(start -0.508 -0.9398)
			(end -0.508 0.9398)
			(stroke
				(width 0.1524)
				(type default)
			)
			(layer "F.SilkS")
		)
		(fp_rect
			(start -0.508 0.9398)
			(end 0.508 -0.9398)
			(stroke
				(width 0)
				(type default)
			)
			(fill no)
			(layer "F.CrtYd")
		)
		(fp_rect
			(start -0.508 0.9398)
			(end 0.508 -0.9398)
			(stroke
				(width 0)
				(type default)
			)
			(fill no)
			(layer "F.Fab")
		)
		(pad "1" smd custom
			(at 0 -0.4445 90)
			(size 0.1397 0.1397)
			(layers "F.Cu" "F.Mask" "F.Paste")
			(net "P3V3_DPB")
			(options
				(clearance outline)
				(anchor circle)
			)
			(primitives
				(gr_poly
					(pts
						(arc
							(start -0.1778 -0.2794)
							(mid -0.249642 -0.249642)
							(end -0.2794 -0.1778)
						)
						(arc
							(start -0.2794 0.1778)
							(mid -0.249642 0.249642)
							(end -0.1778 0.2794)
						)
						(arc
							(start 0.1778 0.2794)
							(mid 0.249642 0.249642)
							(end 0.2794 0.1778)
						)
						(arc
							(start 0.2794 -0.1778)
							(mid 0.249642 -0.249642)
							(end 0.1778 -0.2794)
						)
					)
					(width 0)
					(fill yes)
				)
			)
		)
		(pad "2" smd custom
			(at 0 0.4445 90)
			(size 0.1397 0.1397)
			(layers "F.Cu" "F.Mask" "F.Paste")
			(net "Z50_SMB_SWITCH_ADDRESS_A1")
			(options
				(clearance outline)
				(anchor circle)
			)
			(primitives
				(gr_poly
					(pts
						(arc
							(start -0.1778 -0.2794)
							(mid -0.249642 -0.249642)
							(end -0.2794 -0.1778)
						)
						(arc
							(start -0.2794 0.1778)
							(mid -0.249642 0.249642)
							(end -0.1778 0.2794)
						)
						(arc
							(start 0.1778 0.2794)
							(mid 0.249642 0.249642)
							(end 0.2794 0.1778)
						)
						(arc
							(start 0.2794 -0.1778)
							(mid 0.249642 -0.249642)
							(end 0.1778 -0.2794)
						)
					)
					(width 0)
					(fill yes)
				)
			)
		)
	)
	(footprint ""
		(layer "F.Cu")
		(at 51.7144 -75.692)
		(property "Reference" "C267"
			(at 0 0 0)
			(layer "F.SilkS")
			(hide yes)
			(effects
				(font
					(size 1.27 1.27)
				)
			)
		)
		(property "Value" "SC100P50V2JN-3GP"
			(at 1.1811 -2.7051 0)
			(unlocked yes)
			(layer "F.Fab")
			(hide yes)
			(effects
				(font
					(size 1.016 1.016)
					(thickness 0.1524)
				)
			)
		)
		(property "Device Type" "C402H22"
			(at 1.1811 -4.2291 0)
			(unlocked yes)
			(layer "F.Fab")
			(hide yes)
			(effects
				(font
					(size 1.016 1.016)
					(thickness 0.1524)
				)
			)
		)
		(duplicate_pad_numbers_are_jumpers no)
		(fp_rect
			(start -0.4318 0.9525)
			(end 0.4318 -0.9525)
			(stroke
				(width 0)
				(type default)
			)
			(fill no)
			(layer "F.CrtYd")
		)
		(fp_rect
			(start -0.4318 0.9525)
			(end 0.4318 -0.9525)
			(stroke
				(width 0)
				(type default)
			)
			(fill no)
			(layer "F.Fab")
		)
		(pad "1" smd custom
			(at 0 -0.4445)
			(size 0.1524 0.1524)
			(layers "F.Cu" "F.Mask" "F.Paste")
			(net "P3V3_DEV_VFB")
			(options
				(clearance outline)
				(anchor circle)
			)
			(primitives
				(gr_poly
					(pts
						(arc
							(start 0.3048 -0.2032)
							(mid 0.275042 -0.275042)
							(end 0.2032 -0.3048)
						)
						(arc
							(start -0.2032 -0.3048)
							(mid -0.275042 -0.275042)
							(end -0.3048 -0.2032)
						)
						(arc
							(start -0.3048 0.2032)
							(mid -0.275042 0.275042)
							(end -0.2032 0.3048)
						)
						(arc
							(start 0.2032 0.3048)
							(mid 0.275042 0.275042)
							(end 0.3048 0.2032)
						)
					)
					(width 0)
					(fill yes)
				)
			)
		)
		(pad "2" smd custom
			(at 0 0.4445)
			(size 0.1524 0.1524)
			(layers "F.Cu" "F.Mask" "F.Paste")
			(net "P3V3_DEV_VFB_R")
			(options
				(clearance outline)
				(anchor circle)
			)
			(primitives
				(gr_poly
					(pts
						(arc
							(start 0.3048 -0.2032)
							(mid 0.275042 -0.275042)
							(end 0.2032 -0.3048)
						)
						(arc
							(start -0.2032 -0.3048)
							(mid -0.275042 -0.275042)
							(end -0.3048 -0.2032)
						)
						(arc
							(start -0.3048 0.2032)
							(mid -0.275042 0.275042)
							(end -0.2032 0.3048)
						)
						(arc
							(start 0.2032 0.3048)
							(mid 0.275042 0.275042)
							(end 0.3048 0.2032)
						)
					)
					(width 0)
					(fill yes)
				)
			)
		)
	)
	(footprint ""
		(layer "F.Cu")
		(at 63.246 -64.643 180)
		(property "Reference" "C12"
			(at 0 0 180)
			(layer "F.SilkS")
			(hide yes)
			(effects
				(font
					(size 1.27 1.27)
				)
			)
		)
		(property "Value" "SC1U6D3V2KX-9-GP"
			(at 1.1811 -2.7051 180)
			(unlocked yes)
			(layer "F.Fab")
			(hide yes)
			(effects
				(font
					(size 1.016 1.016)
					(thickness 0.1524)
				)
			)
		)
		(property "Device Type" "C402H22"
			(at 1.1811 -4.2291 180)
			(unlocked yes)
			(layer "F.Fab")
			(hide yes)
			(effects
				(font
					(size 1.016 1.016)
					(thickness 0.1524)
				)
			)
		)
		(duplicate_pad_numbers_are_jumpers no)
		(fp_rect
			(start -0.4318 0.9525)
			(end 0.4318 -0.9525)
			(stroke
				(width 0)
				(type default)
			)
			(fill no)
			(layer "F.CrtYd")
		)
		(fp_rect
			(start -0.4318 0.9525)
			(end 0.4318 -0.9525)
			(stroke
				(width 0)
				(type default)
			)
			(fill no)
			(layer "F.Fab")
		)
		(pad "1" smd custom
			(at 0 -0.4445 180)
			(size 0.1524 0.1524)
			(layers "F.Cu" "F.Mask" "F.Paste")
			(net "P3V3_PWR")
			(options
				(clearance outline)
				(anchor circle)
			)
			(primitives
				(gr_poly
					(pts
						(arc
							(start 0.3048 -0.2032)
							(mid 0.275042 -0.275042)
							(end 0.2032 -0.3048)
						)
						(arc
							(start -0.2032 -0.3048)
							(mid -0.275042 -0.275042)
							(end -0.3048 -0.2032)
						)
						(arc
							(start -0.3048 0.2032)
							(mid -0.275042 0.275042)
							(end -0.2032 0.3048)
						)
						(arc
							(start 0.2032 0.3048)
							(mid 0.275042 0.275042)
							(end 0.3048 0.2032)
						)
					)
					(width 0)
					(fill yes)
				)
			)
		)
		(pad "2" smd custom
			(at 0 0.4445 180)
			(size 0.1524 0.1524)
			(layers "F.Cu" "F.Mask" "F.Paste")
			(net "GND")
			(options
				(clearance outline)
				(anchor circle)
			)
			(primitives
				(gr_poly
					(pts
						(arc
							(start 0.3048 -0.2032)
							(mid 0.275042 -0.275042)
							(end 0.2032 -0.3048)
						)
						(arc
							(start -0.2032 -0.3048)
							(mid -0.275042 -0.275042)
							(end -0.3048 -0.2032)
						)
						(arc
							(start -0.3048 0.2032)
							(mid -0.275042 0.275042)
							(end -0.2032 0.3048)
						)
						(arc
							(start 0.2032 0.3048)
							(mid 0.275042 0.275042)
							(end 0.3048 0.2032)
						)
					)
					(width 0)
					(fill yes)
				)
			)
		)
	)
	(footprint ""
		(layer "F.Cu")
		(at 29.21 -78.74)
		(property "Reference" "R38"
			(at 0 0 0)
			(layer "F.SilkS")
			(hide yes)
			(effects
				(font
					(size 1.27 1.27)
				)
			)
		)
		(property "Value" "0R2J-2-GP"
			(at 0.064008 -3.993896 0)
			(unlocked yes)
			(layer "F.Fab")
			(hide yes)
			(effects
				(font
					(size 1.016 1.016)
					(thickness 0.1524)
				)
			)
		)
		(property "Device Type" "R402H16"
			(at 0.064008 -5.517896 0)
			(unlocked yes)
			(layer "F.Fab")
			(hide yes)
			(effects
				(font
					(size 1.016 1.016)
					(thickness 0.1524)
				)
			)
		)
		(duplicate_pad_numbers_are_jumpers no)
		(fp_line
			(start -0.508 -0.9398)
			(end -0.508 0.9398)
			(stroke
				(width 0.1524)
				(type default)
			)
			(layer "F.SilkS")
		)
		(fp_line
			(start 0.508 -0.9398)
			(end -0.508 -0.9398)
			(stroke
				(width 0.1524)
				(type default)
			)
			(layer "F.SilkS")
		)
		(fp_rect
			(start -0.508 0.9398)
			(end 0.508 -0.9398)
			(stroke
				(width 0)
				(type default)
			)
			(fill no)
			(layer "F.CrtYd")
		)
		(fp_rect
			(start -0.508 0.9398)
			(end 0.508 -0.9398)
			(stroke
				(width 0)
				(type default)
			)
			(fill no)
			(layer "F.Fab")
		)
		(pad "1" smd custom
			(at 0 -0.4445)
			(size 0.1397 0.1397)
			(layers "F.Cu" "F.Mask" "F.Paste")
			(net "Z50_SSD_A1_SMB_DATA_R")
			(options
				(clearance outline)
				(anchor circle)
			)
			(primitives
				(gr_poly
					(pts
						(arc
							(start -0.1778 -0.2794)
							(mid -0.249642 -0.249642)
							(end -0.2794 -0.1778)
						)
						(arc
							(start -0.2794 0.1778)
							(mid -0.249642 0.249642)
							(end -0.1778 0.2794)
						)
						(arc
							(start 0.1778 0.2794)
							(mid 0.249642 0.249642)
							(end 0.2794 0.1778)
						)
						(arc
							(start 0.2794 -0.1778)
							(mid 0.249642 -0.249642)
							(end 0.1778 -0.2794)
						)
					)
					(width 0)
					(fill yes)
				)
			)
		)
		(pad "2" smd custom
			(at 0 0.4445)
			(size 0.1397 0.1397)
			(layers "F.Cu" "F.Mask" "F.Paste")
			(net "Z50_SSD_A1_SMB_DATA_LL")
			(options
				(clearance outline)
				(anchor circle)
			)
			(primitives
				(gr_poly
					(pts
						(arc
							(start -0.1778 -0.2794)
							(mid -0.249642 -0.249642)
							(end -0.2794 -0.1778)
						)
						(arc
							(start -0.2794 0.1778)
							(mid -0.249642 0.249642)
							(end -0.1778 0.2794)
						)
						(arc
							(start 0.1778 0.2794)
							(mid 0.249642 0.249642)
							(end 0.2794 0.1778)
						)
						(arc
							(start 0.2794 -0.1778)
							(mid 0.249642 -0.249642)
							(end 0.1778 -0.2794)
						)
					)
					(width 0)
					(fill yes)
				)
			)
		)
	)
	(footprint ""
		(layer "F.Cu")
		(at 53.594 -74.168 -90)
		(property "Reference" "PR27"
			(at 0 0 270)
			(layer "F.SilkS")
			(hide yes)
			(effects
				(font
					(size 1.27 1.27)
				)
			)
		)
		(property "Value" "10R3F-GP"
			(at -0.0254 -2.5146 270)
			(unlocked yes)
			(layer "F.Fab")
			(hide yes)
			(effects
				(font
					(size 1.016 1.016)
					(thickness 0.1524)
				)
			)
		)
		(property "Device Type" "R603H22"
			(at -0.0254 -4.0386 270)
			(unlocked yes)
			(layer "F.Fab")
			(hide yes)
			(effects
				(font
					(size 1.016 1.016)
					(thickness 0.1524)
				)
			)
		)
		(duplicate_pad_numbers_are_jumpers no)
		(fp_line
			(start -0.4826 0)
			(end -0.2032 0)
			(stroke
				(width 0.2032)
				(type default)
			)
			(layer "F.SilkS")
		)
		(fp_line
			(start 0.2032 0)
			(end 0.4826 0)
			(stroke
				(width 0.2032)
				(type default)
			)
			(layer "F.SilkS")
		)
		(fp_rect
			(start -0.5842 1.3335)
			(end 0.5842 -1.3335)
			(stroke
				(width 0)
				(type default)
			)
			(fill no)
			(layer "F.CrtYd")
		)
		(fp_rect
			(start -0.5842 1.3335)
			(end 0.5842 -1.3335)
			(stroke
				(width 0)
				(type default)
			)
			(fill no)
			(layer "F.Fab")
		)
		(pad "1" smd custom
			(at 0 -0.762 270)
			(size 0.2159 0.2159)
			(layers "F.Cu" "F.Mask" "F.Paste")
			(net "P3V3_PWR")
			(options
				(clearance outline)
				(anchor circle)
			)
			(primitives
				(gr_poly
					(pts
						(arc
							(start -0.3302 -0.4318)
							(mid -0.402042 -0.402042)
							(end -0.4318 -0.3302)
						)
						(arc
							(start -0.4318 0.3302)
							(mid -0.402042 0.402042)
							(end -0.3302 0.4318)
						)
						(arc
							(start 0.3302 0.4318)
							(mid 0.402042 0.402042)
							(end 0.4318 0.3302)
						)
						(arc
							(start 0.4318 -0.3302)
							(mid 0.402042 -0.402042)
							(end 0.3302 -0.4318)
						)
					)
					(width 0)
					(fill yes)
				)
			)
		)
		(pad "2" smd custom
			(at 0 0.762 270)
			(size 0.2159 0.2159)
			(layers "F.Cu" "F.Mask" "F.Paste")
			(net "P3V3_DEV_VFB_R")
			(options
				(clearance outline)
				(anchor circle)
			)
			(primitives
				(gr_poly
					(pts
						(arc
							(start -0.3302 -0.4318)
							(mid -0.402042 -0.402042)
							(end -0.4318 -0.3302)
						)
						(arc
							(start -0.4318 0.3302)
							(mid -0.402042 0.402042)
							(end -0.3302 0.4318)
						)
						(arc
							(start 0.3302 0.4318)
							(mid 0.402042 0.402042)
							(end 0.4318 0.3302)
						)
						(arc
							(start 0.4318 -0.3302)
							(mid 0.402042 -0.402042)
							(end 0.3302 -0.4318)
						)
					)
					(width 0)
					(fill yes)
				)
			)
		)
	)
	(footprint ""
		(layer "F.Cu")
		(at 17.526 -76.883006 -90)
		(property "Reference" "PC22"
			(at 0 0 270)
			(layer "F.SilkS")
			(hide yes)
			(effects
				(font
					(size 1.27 1.27)
				)
			)
		)
		(property "Value" "SCD01U25V2KX-3GP"
			(at 1.1811 -2.7051 270)
			(unlocked yes)
			(layer "F.Fab")
			(hide yes)
			(effects
				(font
					(size 1.016 1.016)
					(thickness 0.1524)
				)
			)
		)
		(property "Device Type" "C402H22"
			(at 1.1811 -4.2291 270)
			(unlocked yes)
			(layer "F.Fab")
			(hide yes)
			(effects
				(font
					(size 1.016 1.016)
					(thickness 0.1524)
				)
			)
		)
		(duplicate_pad_numbers_are_jumpers no)
		(fp_rect
			(start -0.4318 0.9525)
			(end 0.4318 -0.9525)
			(stroke
				(width 0)
				(type default)
			)
			(fill no)
			(layer "F.CrtYd")
		)
		(fp_rect
			(start -0.4318 0.9525)
			(end 0.4318 -0.9525)
			(stroke
				(width 0)
				(type default)
			)
			(fill no)
			(layer "F.Fab")
		)
		(pad "1" smd custom
			(at 0 -0.4445 270)
			(size 0.1524 0.1524)
			(layers "F.Cu" "F.Mask" "F.Paste")
			(net "P1V8_PWR")
			(options
				(clearance outline)
				(anchor circle)
			)
			(primitives
				(gr_poly
					(pts
						(arc
							(start 0.3048 -0.2032)
							(mid 0.275042 -0.275042)
							(end 0.2032 -0.3048)
						)
						(arc
							(start -0.2032 -0.3048)
							(mid -0.275042 -0.275042)
							(end -0.3048 -0.2032)
						)
						(arc
							(start -0.3048 0.2032)
							(mid -0.275042 0.275042)
							(end -0.2032 0.3048)
						)
						(arc
							(start 0.2032 0.3048)
							(mid 0.275042 0.275042)
							(end 0.3048 0.2032)
						)
					)
					(width 0)
					(fill yes)
				)
			)
		)
		(pad "2" smd custom
			(at 0 0.4445 270)
			(size 0.1524 0.1524)
			(layers "F.Cu" "F.Mask" "F.Paste")
			(net "P1V8_PWR_FB")
			(options
				(clearance outline)
				(anchor circle)
			)
			(primitives
				(gr_poly
					(pts
						(arc
							(start 0.3048 -0.2032)
							(mid 0.275042 -0.275042)
							(end 0.2032 -0.3048)
						)
						(arc
							(start -0.2032 -0.3048)
							(mid -0.275042 -0.275042)
							(end -0.3048 -0.2032)
						)
						(arc
							(start -0.3048 0.2032)
							(mid -0.275042 0.275042)
							(end -0.2032 0.3048)
						)
						(arc
							(start 0.2032 0.3048)
							(mid 0.275042 0.275042)
							(end 0.3048 0.2032)
						)
					)
					(width 0)
					(fill yes)
				)
			)
		)
	)
	(footprint ""
		(layer "F.Cu")
		(at 32.385 -78.74)
		(property "Reference" "R40"
			(at 0 0 0)
			(layer "F.SilkS")
			(hide yes)
			(effects
				(font
					(size 1.27 1.27)
				)
			)
		)
		(property "Value" "0R2J-2-GP"
			(at 0.064008 -3.993896 0)
			(unlocked yes)
			(layer "F.Fab")
			(hide yes)
			(effects
				(font
					(size 1.016 1.016)
					(thickness 0.1524)
				)
			)
		)
		(property "Device Type" "R402H16"
			(at 0.064008 -5.517896 0)
			(unlocked yes)
			(layer "F.Fab")
			(hide yes)
			(effects
				(font
					(size 1.016 1.016)
					(thickness 0.1524)
				)
			)
		)
		(duplicate_pad_numbers_are_jumpers no)
		(fp_line
			(start -0.508 -0.9398)
			(end -0.508 0.9398)
			(stroke
				(width 0.1524)
				(type default)
			)
			(layer "F.SilkS")
		)
		(fp_line
			(start 0.508 -0.9398)
			(end -0.508 -0.9398)
			(stroke
				(width 0.1524)
				(type default)
			)
			(layer "F.SilkS")
		)
		(fp_rect
			(start -0.508 0.9398)
			(end 0.508 -0.9398)
			(stroke
				(width 0)
				(type default)
			)
			(fill no)
			(layer "F.CrtYd")
		)
		(fp_rect
			(start -0.508 0.9398)
			(end 0.508 -0.9398)
			(stroke
				(width 0)
				(type default)
			)
			(fill no)
			(layer "F.Fab")
		)
		(pad "1" smd custom
			(at 0 -0.4445)
			(size 0.1397 0.1397)
			(layers "F.Cu" "F.Mask" "F.Paste")
			(net "Z50_SSD_B1_SMB_DATA_R")
			(options
				(clearance outline)
				(anchor circle)
			)
			(primitives
				(gr_poly
					(pts
						(arc
							(start -0.1778 -0.2794)
							(mid -0.249642 -0.249642)
							(end -0.2794 -0.1778)
						)
						(arc
							(start -0.2794 0.1778)
							(mid -0.249642 0.249642)
							(end -0.1778 0.2794)
						)
						(arc
							(start 0.1778 0.2794)
							(mid 0.249642 0.249642)
							(end 0.2794 0.1778)
						)
						(arc
							(start 0.2794 -0.1778)
							(mid 0.249642 -0.249642)
							(end 0.1778 -0.2794)
						)
					)
					(width 0)
					(fill yes)
				)
			)
		)
		(pad "2" smd custom
			(at 0 0.4445)
			(size 0.1397 0.1397)
			(layers "F.Cu" "F.Mask" "F.Paste")
			(net "Z50_SSD_B1_SMB_DATA_LL")
			(options
				(clearance outline)
				(anchor circle)
			)
			(primitives
				(gr_poly
					(pts
						(arc
							(start -0.1778 -0.2794)
							(mid -0.249642 -0.249642)
							(end -0.2794 -0.1778)
						)
						(arc
							(start -0.2794 0.1778)
							(mid -0.249642 0.249642)
							(end -0.1778 0.2794)
						)
						(arc
							(start 0.1778 0.2794)
							(mid 0.249642 0.249642)
							(end 0.2794 0.1778)
						)
						(arc
							(start 0.2794 -0.1778)
							(mid 0.249642 -0.249642)
							(end 0.1778 -0.2794)
						)
					)
					(width 0)
					(fill yes)
				)
			)
		)
	)
	(footprint ""
		(layer "F.Cu")
		(at 59.817 -17.018 -90)
		(property "Reference" "C21"
			(at 0 0 270)
			(layer "F.SilkS")
			(hide yes)
			(effects
				(font
					(size 1.27 1.27)
				)
			)
		)
		(property "Value" "SCD1U16V2KX-3GP"
			(at 1.1811 -2.7051 270)
			(unlocked yes)
			(layer "F.Fab")
			(hide yes)
			(effects
				(font
					(size 1.016 1.016)
					(thickness 0.1524)
				)
			)
		)
		(property "Device Type" "C402H22"
			(at 1.1811 -4.2291 270)
			(unlocked yes)
			(layer "F.Fab")
			(hide yes)
			(effects
				(font
					(size 1.016 1.016)
					(thickness 0.1524)
				)
			)
		)
		(duplicate_pad_numbers_are_jumpers no)
		(fp_rect
			(start -0.4318 0.9525)
			(end 0.4318 -0.9525)
			(stroke
				(width 0)
				(type default)
			)
			(fill no)
			(layer "F.CrtYd")
		)
		(fp_rect
			(start -0.4318 0.9525)
			(end 0.4318 -0.9525)
			(stroke
				(width 0)
				(type default)
			)
			(fill no)
			(layer "F.Fab")
		)
		(pad "1" smd custom
			(at 0 -0.4445 270)
			(size 0.1524 0.1524)
			(layers "F.Cu" "F.Mask" "F.Paste")
			(net "P3V3_PWR")
			(options
				(clearance outline)
				(anchor circle)
			)
			(primitives
				(gr_poly
					(pts
						(arc
							(start 0.3048 -0.2032)
							(mid 0.275042 -0.275042)
							(end 0.2032 -0.3048)
						)
						(arc
							(start -0.2032 -0.3048)
							(mid -0.275042 -0.275042)
							(end -0.3048 -0.2032)
						)
						(arc
							(start -0.3048 0.2032)
							(mid -0.275042 0.275042)
							(end -0.2032 0.3048)
						)
						(arc
							(start 0.2032 0.3048)
							(mid 0.275042 0.275042)
							(end 0.3048 0.2032)
						)
					)
					(width 0)
					(fill yes)
				)
			)
		)
		(pad "2" smd custom
			(at 0 0.4445 270)
			(size 0.1524 0.1524)
			(layers "F.Cu" "F.Mask" "F.Paste")
			(net "GND")
			(options
				(clearance outline)
				(anchor circle)
			)
			(primitives
				(gr_poly
					(pts
						(arc
							(start 0.3048 -0.2032)
							(mid 0.275042 -0.275042)
							(end 0.2032 -0.3048)
						)
						(arc
							(start -0.2032 -0.3048)
							(mid -0.275042 -0.275042)
							(end -0.3048 -0.2032)
						)
						(arc
							(start -0.3048 0.2032)
							(mid -0.275042 0.275042)
							(end -0.2032 0.3048)
						)
						(arc
							(start 0.2032 0.3048)
							(mid 0.275042 0.275042)
							(end 0.3048 0.2032)
						)
					)
					(width 0)
					(fill yes)
				)
			)
		)
	)
	(footprint ""
		(layer "F.Cu")
		(at 59.817 -19.05 -90)
		(property "Reference" "C22"
			(at 0 0 270)
			(layer "F.SilkS")
			(hide yes)
			(effects
				(font
					(size 1.27 1.27)
				)
			)
		)
		(property "Value" "SCD1U16V2KX-3GP"
			(at 1.1811 -2.7051 270)
			(unlocked yes)
			(layer "F.Fab")
			(hide yes)
			(effects
				(font
					(size 1.016 1.016)
					(thickness 0.1524)
				)
			)
		)
		(property "Device Type" "C402H22"
			(at 1.1811 -4.2291 270)
			(unlocked yes)
			(layer "F.Fab")
			(hide yes)
			(effects
				(font
					(size 1.016 1.016)
					(thickness 0.1524)
				)
			)
		)
		(duplicate_pad_numbers_are_jumpers no)
		(fp_rect
			(start -0.4318 0.9525)
			(end 0.4318 -0.9525)
			(stroke
				(width 0)
				(type default)
			)
			(fill no)
			(layer "F.CrtYd")
		)
		(fp_rect
			(start -0.4318 0.9525)
			(end 0.4318 -0.9525)
			(stroke
				(width 0)
				(type default)
			)
			(fill no)
			(layer "F.Fab")
		)
		(pad "1" smd custom
			(at 0 -0.4445 270)
			(size 0.1524 0.1524)
			(layers "F.Cu" "F.Mask" "F.Paste")
			(net "P3V3_PWR")
			(options
				(clearance outline)
				(anchor circle)
			)
			(primitives
				(gr_poly
					(pts
						(arc
							(start 0.3048 -0.2032)
							(mid 0.275042 -0.275042)
							(end 0.2032 -0.3048)
						)
						(arc
							(start -0.2032 -0.3048)
							(mid -0.275042 -0.275042)
							(end -0.3048 -0.2032)
						)
						(arc
							(start -0.3048 0.2032)
							(mid -0.275042 0.275042)
							(end -0.2032 0.3048)
						)
						(arc
							(start 0.2032 0.3048)
							(mid 0.275042 0.275042)
							(end 0.3048 0.2032)
						)
					)
					(width 0)
					(fill yes)
				)
			)
		)
		(pad "2" smd custom
			(at 0 0.4445 270)
			(size 0.1524 0.1524)
			(layers "F.Cu" "F.Mask" "F.Paste")
			(net "GND")
			(options
				(clearance outline)
				(anchor circle)
			)
			(primitives
				(gr_poly
					(pts
						(arc
							(start 0.3048 -0.2032)
							(mid 0.275042 -0.275042)
							(end 0.2032 -0.3048)
						)
						(arc
							(start -0.2032 -0.3048)
							(mid -0.275042 -0.275042)
							(end -0.3048 -0.2032)
						)
						(arc
							(start -0.3048 0.2032)
							(mid -0.275042 0.275042)
							(end -0.2032 0.3048)
						)
						(arc
							(start 0.2032 0.3048)
							(mid 0.275042 0.275042)
							(end 0.3048 0.2032)
						)
					)
					(width 0)
					(fill yes)
				)
			)
		)
	)
	(footprint ""
		(layer "F.Cu")
		(at 59.817 -34.163 -90)
		(property "Reference" "C33"
			(at 0 0 270)
			(layer "F.SilkS")
			(hide yes)
			(effects
				(font
					(size 1.27 1.27)
				)
			)
		)
		(property "Value" "SCD1U16V2KX-3GP"
			(at 1.1811 -2.7051 270)
			(unlocked yes)
			(layer "F.Fab")
			(hide yes)
			(effects
				(font
					(size 1.016 1.016)
					(thickness 0.1524)
				)
			)
		)
		(property "Device Type" "C402H22"
			(at 1.1811 -4.2291 270)
			(unlocked yes)
			(layer "F.Fab")
			(hide yes)
			(effects
				(font
					(size 1.016 1.016)
					(thickness 0.1524)
				)
			)
		)
		(duplicate_pad_numbers_are_jumpers no)
		(fp_rect
			(start -0.4318 0.9525)
			(end 0.4318 -0.9525)
			(stroke
				(width 0)
				(type default)
			)
			(fill no)
			(layer "F.CrtYd")
		)
		(fp_rect
			(start -0.4318 0.9525)
			(end 0.4318 -0.9525)
			(stroke
				(width 0)
				(type default)
			)
			(fill no)
			(layer "F.Fab")
		)
		(pad "1" smd custom
			(at 0 -0.4445 270)
			(size 0.1524 0.1524)
			(layers "F.Cu" "F.Mask" "F.Paste")
			(net "P3V3_PWR")
			(options
				(clearance outline)
				(anchor circle)
			)
			(primitives
				(gr_poly
					(pts
						(arc
							(start 0.3048 -0.2032)
							(mid 0.275042 -0.275042)
							(end 0.2032 -0.3048)
						)
						(arc
							(start -0.2032 -0.3048)
							(mid -0.275042 -0.275042)
							(end -0.3048 -0.2032)
						)
						(arc
							(start -0.3048 0.2032)
							(mid -0.275042 0.275042)
							(end -0.2032 0.3048)
						)
						(arc
							(start 0.2032 0.3048)
							(mid 0.275042 0.275042)
							(end 0.3048 0.2032)
						)
					)
					(width 0)
					(fill yes)
				)
			)
		)
		(pad "2" smd custom
			(at 0 0.4445 270)
			(size 0.1524 0.1524)
			(layers "F.Cu" "F.Mask" "F.Paste")
			(net "GND")
			(options
				(clearance outline)
				(anchor circle)
			)
			(primitives
				(gr_poly
					(pts
						(arc
							(start 0.3048 -0.2032)
							(mid 0.275042 -0.275042)
							(end 0.2032 -0.3048)
						)
						(arc
							(start -0.2032 -0.3048)
							(mid -0.275042 -0.275042)
							(end -0.3048 -0.2032)
						)
						(arc
							(start -0.3048 0.2032)
							(mid -0.275042 0.275042)
							(end -0.2032 0.3048)
						)
						(arc
							(start 0.2032 0.3048)
							(mid 0.275042 0.275042)
							(end 0.3048 0.2032)
						)
					)
					(width 0)
					(fill yes)
				)
			)
		)
	)
	(footprint ""
		(layer "F.Cu")
		(at 15.748 -86.154006)
		(property "Reference" "PR18"
			(at 0 0 0)
			(layer "F.SilkS")
			(hide yes)
			(effects
				(font
					(size 1.27 1.27)
				)
			)
		)
		(property "Value" "0R2J-2-GP"
			(at 0.064008 -3.993896 0)
			(unlocked yes)
			(layer "F.Fab")
			(hide yes)
			(effects
				(font
					(size 1.016 1.016)
					(thickness 0.1524)
				)
			)
		)
		(property "Device Type" "R402H16"
			(at 0.064008 -5.517896 0)
			(unlocked yes)
			(layer "F.Fab")
			(hide yes)
			(effects
				(font
					(size 1.016 1.016)
					(thickness 0.1524)
				)
			)
		)
		(duplicate_pad_numbers_are_jumpers no)
		(fp_line
			(start -0.508 -0.9398)
			(end -0.508 0.9398)
			(stroke
				(width 0.1524)
				(type default)
			)
			(layer "F.SilkS")
		)
		(fp_line
			(start 0.508 -0.9398)
			(end -0.508 -0.9398)
			(stroke
				(width 0.1524)
				(type default)
			)
			(layer "F.SilkS")
		)
		(fp_rect
			(start -0.508 0.9398)
			(end 0.508 -0.9398)
			(stroke
				(width 0)
				(type default)
			)
			(fill no)
			(layer "F.CrtYd")
		)
		(fp_rect
			(start -0.508 0.9398)
			(end 0.508 -0.9398)
			(stroke
				(width 0)
				(type default)
			)
			(fill no)
			(layer "F.Fab")
		)
		(pad "1" smd custom
			(at 0 -0.4445)
			(size 0.1397 0.1397)
			(layers "F.Cu" "F.Mask" "F.Paste")
			(net "P3V3_PWR")
			(options
				(clearance outline)
				(anchor circle)
			)
			(primitives
				(gr_poly
					(pts
						(arc
							(start -0.1778 -0.2794)
							(mid -0.249642 -0.249642)
							(end -0.2794 -0.1778)
						)
						(arc
							(start -0.2794 0.1778)
							(mid -0.249642 0.249642)
							(end -0.1778 0.2794)
						)
						(arc
							(start 0.1778 0.2794)
							(mid 0.249642 0.249642)
							(end 0.2794 0.1778)
						)
						(arc
							(start 0.2794 -0.1778)
							(mid 0.249642 -0.249642)
							(end 0.1778 -0.2794)
						)
					)
					(width 0)
					(fill yes)
				)
			)
		)
		(pad "2" smd custom
			(at 0 0.4445)
			(size 0.1397 0.1397)
			(layers "F.Cu" "F.Mask" "F.Paste")
			(net "P1V8_PWR_BIAS")
			(options
				(clearance outline)
				(anchor circle)
			)
			(primitives
				(gr_poly
					(pts
						(arc
							(start -0.1778 -0.2794)
							(mid -0.249642 -0.249642)
							(end -0.2794 -0.1778)
						)
						(arc
							(start -0.2794 0.1778)
							(mid -0.249642 0.249642)
							(end -0.1778 0.2794)
						)
						(arc
							(start 0.1778 0.2794)
							(mid 0.249642 0.249642)
							(end 0.2794 0.1778)
						)
						(arc
							(start 0.2794 -0.1778)
							(mid 0.249642 -0.249642)
							(end 0.1778 -0.2794)
						)
					)
					(width 0)
					(fill yes)
				)
			)
		)
	)
	(footprint ""
		(layer "F.Cu")
		(at 59.817 -18.034 -90)
		(property "Reference" "C20"
			(at 0 0 270)
			(layer "F.SilkS")
			(hide yes)
			(effects
				(font
					(size 1.27 1.27)
				)
			)
		)
		(property "Value" "SC1U6D3V2KX-9-GP"
			(at 1.1811 -2.7051 270)
			(unlocked yes)
			(layer "F.Fab")
			(hide yes)
			(effects
				(font
					(size 1.016 1.016)
					(thickness 0.1524)
				)
			)
		)
		(property "Device Type" "C402H22"
			(at 1.1811 -4.2291 270)
			(unlocked yes)
			(layer "F.Fab")
			(hide yes)
			(effects
				(font
					(size 1.016 1.016)
					(thickness 0.1524)
				)
			)
		)
		(duplicate_pad_numbers_are_jumpers no)
		(fp_rect
			(start -0.4318 0.9525)
			(end 0.4318 -0.9525)
			(stroke
				(width 0)
				(type default)
			)
			(fill no)
			(layer "F.CrtYd")
		)
		(fp_rect
			(start -0.4318 0.9525)
			(end 0.4318 -0.9525)
			(stroke
				(width 0)
				(type default)
			)
			(fill no)
			(layer "F.Fab")
		)
		(pad "1" smd custom
			(at 0 -0.4445 270)
			(size 0.1524 0.1524)
			(layers "F.Cu" "F.Mask" "F.Paste")
			(net "P3V3_PWR")
			(options
				(clearance outline)
				(anchor circle)
			)
			(primitives
				(gr_poly
					(pts
						(arc
							(start 0.3048 -0.2032)
							(mid 0.275042 -0.275042)
							(end 0.2032 -0.3048)
						)
						(arc
							(start -0.2032 -0.3048)
							(mid -0.275042 -0.275042)
							(end -0.3048 -0.2032)
						)
						(arc
							(start -0.3048 0.2032)
							(mid -0.275042 0.275042)
							(end -0.2032 0.3048)
						)
						(arc
							(start 0.2032 0.3048)
							(mid 0.275042 0.275042)
							(end 0.3048 0.2032)
						)
					)
					(width 0)
					(fill yes)
				)
			)
		)
		(pad "2" smd custom
			(at 0 0.4445 270)
			(size 0.1524 0.1524)
			(layers "F.Cu" "F.Mask" "F.Paste")
			(net "GND")
			(options
				(clearance outline)
				(anchor circle)
			)
			(primitives
				(gr_poly
					(pts
						(arc
							(start 0.3048 -0.2032)
							(mid 0.275042 -0.275042)
							(end 0.2032 -0.3048)
						)
						(arc
							(start -0.2032 -0.3048)
							(mid -0.275042 -0.275042)
							(end -0.3048 -0.2032)
						)
						(arc
							(start -0.3048 0.2032)
							(mid -0.275042 0.275042)
							(end -0.2032 0.3048)
						)
						(arc
							(start 0.2032 0.3048)
							(mid 0.275042 0.275042)
							(end 0.3048 0.2032)
						)
					)
					(width 0)
					(fill yes)
				)
			)
		)
	)
	(footprint ""
		(layer "F.Cu")
		(at 59.817 -46.609 -90)
		(property "Reference" "C2"
			(at 0 0 270)
			(layer "F.SilkS")
			(hide yes)
			(effects
				(font
					(size 1.27 1.27)
				)
			)
		)
		(property "Value" "SCD1U16V2KX-3GP"
			(at 1.1811 -2.7051 270)
			(unlocked yes)
			(layer "F.Fab")
			(hide yes)
			(effects
				(font
					(size 1.016 1.016)
					(thickness 0.1524)
				)
			)
		)
		(property "Device Type" "C402H22"
			(at 1.1811 -4.2291 270)
			(unlocked yes)
			(layer "F.Fab")
			(hide yes)
			(effects
				(font
					(size 1.016 1.016)
					(thickness 0.1524)
				)
			)
		)
		(duplicate_pad_numbers_are_jumpers no)
		(fp_rect
			(start -0.4318 0.9525)
			(end 0.4318 -0.9525)
			(stroke
				(width 0)
				(type default)
			)
			(fill no)
			(layer "F.CrtYd")
		)
		(fp_rect
			(start -0.4318 0.9525)
			(end 0.4318 -0.9525)
			(stroke
				(width 0)
				(type default)
			)
			(fill no)
			(layer "F.Fab")
		)
		(pad "1" smd custom
			(at 0 -0.4445 270)
			(size 0.1524 0.1524)
			(layers "F.Cu" "F.Mask" "F.Paste")
			(net "P3V3_PWR")
			(options
				(clearance outline)
				(anchor circle)
			)
			(primitives
				(gr_poly
					(pts
						(arc
							(start 0.3048 -0.2032)
							(mid 0.275042 -0.275042)
							(end 0.2032 -0.3048)
						)
						(arc
							(start -0.2032 -0.3048)
							(mid -0.275042 -0.275042)
							(end -0.3048 -0.2032)
						)
						(arc
							(start -0.3048 0.2032)
							(mid -0.275042 0.275042)
							(end -0.2032 0.3048)
						)
						(arc
							(start 0.2032 0.3048)
							(mid 0.275042 0.275042)
							(end 0.3048 0.2032)
						)
					)
					(width 0)
					(fill yes)
				)
			)
		)
		(pad "2" smd custom
			(at 0 0.4445 270)
			(size 0.1524 0.1524)
			(layers "F.Cu" "F.Mask" "F.Paste")
			(net "GND")
			(options
				(clearance outline)
				(anchor circle)
			)
			(primitives
				(gr_poly
					(pts
						(arc
							(start 0.3048 -0.2032)
							(mid 0.275042 -0.275042)
							(end 0.2032 -0.3048)
						)
						(arc
							(start -0.2032 -0.3048)
							(mid -0.275042 -0.275042)
							(end -0.3048 -0.2032)
						)
						(arc
							(start -0.3048 0.2032)
							(mid -0.275042 0.275042)
							(end -0.2032 0.3048)
						)
						(arc
							(start 0.2032 0.3048)
							(mid 0.275042 0.275042)
							(end 0.3048 0.2032)
						)
					)
					(width 0)
					(fill yes)
				)
			)
		)
	)
	(footprint ""
		(layer "F.Cu")
		(at 59.817 -33.02 -90)
		(property "Reference" "C34"
			(at 0 0 270)
			(layer "F.SilkS")
			(hide yes)
			(effects
				(font
					(size 1.27 1.27)
				)
			)
		)
		(property "Value" "SCD1U16V2KX-3GP"
			(at 1.1811 -2.7051 270)
			(unlocked yes)
			(layer "F.Fab")
			(hide yes)
			(effects
				(font
					(size 1.016 1.016)
					(thickness 0.1524)
				)
			)
		)
		(property "Device Type" "C402H22"
			(at 1.1811 -4.2291 270)
			(unlocked yes)
			(layer "F.Fab")
			(hide yes)
			(effects
				(font
					(size 1.016 1.016)
					(thickness 0.1524)
				)
			)
		)
		(duplicate_pad_numbers_are_jumpers no)
		(fp_rect
			(start -0.4318 0.9525)
			(end 0.4318 -0.9525)
			(stroke
				(width 0)
				(type default)
			)
			(fill no)
			(layer "F.CrtYd")
		)
		(fp_rect
			(start -0.4318 0.9525)
			(end 0.4318 -0.9525)
			(stroke
				(width 0)
				(type default)
			)
			(fill no)
			(layer "F.Fab")
		)
		(pad "1" smd custom
			(at 0 -0.4445 270)
			(size 0.1524 0.1524)
			(layers "F.Cu" "F.Mask" "F.Paste")
			(net "P3V3_PWR")
			(options
				(clearance outline)
				(anchor circle)
			)
			(primitives
				(gr_poly
					(pts
						(arc
							(start 0.3048 -0.2032)
							(mid 0.275042 -0.275042)
							(end 0.2032 -0.3048)
						)
						(arc
							(start -0.2032 -0.3048)
							(mid -0.275042 -0.275042)
							(end -0.3048 -0.2032)
						)
						(arc
							(start -0.3048 0.2032)
							(mid -0.275042 0.275042)
							(end -0.2032 0.3048)
						)
						(arc
							(start 0.2032 0.3048)
							(mid 0.275042 0.275042)
							(end 0.3048 0.2032)
						)
					)
					(width 0)
					(fill yes)
				)
			)
		)
		(pad "2" smd custom
			(at 0 0.4445 270)
			(size 0.1524 0.1524)
			(layers "F.Cu" "F.Mask" "F.Paste")
			(net "GND")
			(options
				(clearance outline)
				(anchor circle)
			)
			(primitives
				(gr_poly
					(pts
						(arc
							(start 0.3048 -0.2032)
							(mid 0.275042 -0.275042)
							(end 0.2032 -0.3048)
						)
						(arc
							(start -0.2032 -0.3048)
							(mid -0.275042 -0.275042)
							(end -0.3048 -0.2032)
						)
						(arc
							(start -0.3048 0.2032)
							(mid -0.275042 0.275042)
							(end -0.2032 0.3048)
						)
						(arc
							(start 0.2032 0.3048)
							(mid 0.275042 0.275042)
							(end 0.3048 0.2032)
						)
					)
					(width 0)
					(fill yes)
				)
			)
		)
	)
	(footprint ""
		(layer "F.Cu")
		(at 39.37 -84.582 180)
		(property "Reference" "PC33"
			(at 0 0 180)
			(layer "F.SilkS")
			(hide yes)
			(effects
				(font
					(size 1.27 1.27)
				)
			)
		)
		(property "Value" "SC10U16V5KX-1-GP"
			(at -0.0762 -6.1214 180)
			(unlocked yes)
			(layer "F.Fab")
			(hide yes)
			(effects
				(font
					(size 1.016 1.016)
					(thickness 0.1524)
				)
			)
		)
		(property "Device Type" "C805H54"
			(at -0.0762 -8.1534 180)
			(unlocked yes)
			(layer "F.Fab")
			(hide yes)
			(effects
				(font
					(size 1.016 1.016)
					(thickness 0.1524)
				)
			)
		)
		(duplicate_pad_numbers_are_jumpers no)
		(fp_line
			(start 0.635 0)
			(end -0.635 0)
			(stroke
				(width 0.508)
				(type default)
			)
			(layer "F.SilkS")
		)
		(fp_rect
			(start -0.9652 1.778)
			(end 0.9652 -1.778)
			(stroke
				(width 0)
				(type default)
			)
			(fill no)
			(layer "F.CrtYd")
		)
		(fp_poly
			(pts
				(xy -0.9652 -1.778) (xy 0.9652 -1.778) (xy 0.9652 1.778) (xy -0.9652 1.778)
			)
			(stroke
				(width 0)
				(type default)
			)
			(fill no)
			(layer "F.Fab")
		)
		(pad "1" smd rect
			(at 0 -0.9652 180)
			(size 1.397 1.143)
			(layers "F.Cu" "F.Mask" "F.Paste")
			(net "P3V3_DEV_VIN")
		)
		(pad "2" smd rect
			(at 0 0.9652 180)
			(size 1.397 1.143)
			(layers "F.Cu" "F.Mask" "F.Paste")
			(net "GND")
		)
	)
	(footprint ""
		(layer "F.Cu")
		(at 59.817 -59.563 -90)
		(property "Reference" "C18"
			(at 0 0 270)
			(layer "F.SilkS")
			(hide yes)
			(effects
				(font
					(size 1.27 1.27)
				)
			)
		)
		(property "Value" "SC1U6D3V2KX-9-GP"
			(at 1.1811 -2.7051 270)
			(unlocked yes)
			(layer "F.Fab")
			(hide yes)
			(effects
				(font
					(size 1.016 1.016)
					(thickness 0.1524)
				)
			)
		)
		(property "Device Type" "C402H22"
			(at 1.1811 -4.2291 270)
			(unlocked yes)
			(layer "F.Fab")
			(hide yes)
			(effects
				(font
					(size 1.016 1.016)
					(thickness 0.1524)
				)
			)
		)
		(duplicate_pad_numbers_are_jumpers no)
		(fp_rect
			(start -0.4318 0.9525)
			(end 0.4318 -0.9525)
			(stroke
				(width 0)
				(type default)
			)
			(fill no)
			(layer "F.CrtYd")
		)
		(fp_rect
			(start -0.4318 0.9525)
			(end 0.4318 -0.9525)
			(stroke
				(width 0)
				(type default)
			)
			(fill no)
			(layer "F.Fab")
		)
		(pad "1" smd custom
			(at 0 -0.4445 270)
			(size 0.1524 0.1524)
			(layers "F.Cu" "F.Mask" "F.Paste")
			(net "P3V3_PWR")
			(options
				(clearance outline)
				(anchor circle)
			)
			(primitives
				(gr_poly
					(pts
						(arc
							(start 0.3048 -0.2032)
							(mid 0.275042 -0.275042)
							(end 0.2032 -0.3048)
						)
						(arc
							(start -0.2032 -0.3048)
							(mid -0.275042 -0.275042)
							(end -0.3048 -0.2032)
						)
						(arc
							(start -0.3048 0.2032)
							(mid -0.275042 0.275042)
							(end -0.2032 0.3048)
						)
						(arc
							(start 0.2032 0.3048)
							(mid 0.275042 0.275042)
							(end 0.3048 0.2032)
						)
					)
					(width 0)
					(fill yes)
				)
			)
		)
		(pad "2" smd custom
			(at 0 0.4445 270)
			(size 0.1524 0.1524)
			(layers "F.Cu" "F.Mask" "F.Paste")
			(net "GND")
			(options
				(clearance outline)
				(anchor circle)
			)
			(primitives
				(gr_poly
					(pts
						(arc
							(start 0.3048 -0.2032)
							(mid 0.275042 -0.275042)
							(end 0.2032 -0.3048)
						)
						(arc
							(start -0.2032 -0.3048)
							(mid -0.275042 -0.275042)
							(end -0.3048 -0.2032)
						)
						(arc
							(start -0.3048 0.2032)
							(mid -0.275042 0.275042)
							(end -0.2032 0.3048)
						)
						(arc
							(start 0.2032 0.3048)
							(mid 0.275042 0.275042)
							(end 0.3048 0.2032)
						)
					)
					(width 0)
					(fill yes)
				)
			)
		)
	)
	(footprint ""
		(layer "F.Cu")
		(at 25.908 -78.74 90)
		(property "Reference" "C8"
			(at 0 0 90)
			(layer "F.SilkS")
			(hide yes)
			(effects
				(font
					(size 1.27 1.27)
				)
			)
		)
		(property "Value" "SCD1U16V2KX-3GP"
			(at 1.1811 -2.7051 90)
			(unlocked yes)
			(layer "F.Fab")
			(hide yes)
			(effects
				(font
					(size 1.016 1.016)
					(thickness 0.1524)
				)
			)
		)
		(property "Device Type" "C402H22"
			(at 1.1811 -4.2291 90)
			(unlocked yes)
			(layer "F.Fab")
			(hide yes)
			(effects
				(font
					(size 1.016 1.016)
					(thickness 0.1524)
				)
			)
		)
		(duplicate_pad_numbers_are_jumpers no)
		(fp_rect
			(start -0.4318 0.9525)
			(end 0.4318 -0.9525)
			(stroke
				(width 0)
				(type default)
			)
			(fill no)
			(layer "F.CrtYd")
		)
		(fp_rect
			(start -0.4318 0.9525)
			(end 0.4318 -0.9525)
			(stroke
				(width 0)
				(type default)
			)
			(fill no)
			(layer "F.Fab")
		)
		(pad "1" smd custom
			(at 0 -0.4445 90)
			(size 0.1524 0.1524)
			(layers "F.Cu" "F.Mask" "F.Paste")
			(net "P1V8_PWR")
			(options
				(clearance outline)
				(anchor circle)
			)
			(primitives
				(gr_poly
					(pts
						(arc
							(start 0.3048 -0.2032)
							(mid 0.275042 -0.275042)
							(end 0.2032 -0.3048)
						)
						(arc
							(start -0.2032 -0.3048)
							(mid -0.275042 -0.275042)
							(end -0.3048 -0.2032)
						)
						(arc
							(start -0.3048 0.2032)
							(mid -0.275042 0.275042)
							(end -0.2032 0.3048)
						)
						(arc
							(start 0.2032 0.3048)
							(mid 0.275042 0.275042)
							(end 0.3048 0.2032)
						)
					)
					(width 0)
					(fill yes)
				)
			)
		)
		(pad "2" smd custom
			(at 0 0.4445 90)
			(size 0.1524 0.1524)
			(layers "F.Cu" "F.Mask" "F.Paste")
			(net "GND")
			(options
				(clearance outline)
				(anchor circle)
			)
			(primitives
				(gr_poly
					(pts
						(arc
							(start 0.3048 -0.2032)
							(mid 0.275042 -0.275042)
							(end 0.2032 -0.3048)
						)
						(arc
							(start -0.2032 -0.3048)
							(mid -0.275042 -0.275042)
							(end -0.3048 -0.2032)
						)
						(arc
							(start -0.3048 0.2032)
							(mid -0.275042 0.275042)
							(end -0.2032 0.3048)
						)
						(arc
							(start 0.2032 0.3048)
							(mid 0.275042 0.275042)
							(end 0.3048 0.2032)
						)
					)
					(width 0)
					(fill yes)
				)
			)
		)
	)
	(footprint ""
		(layer "F.Cu")
		(at 16.51 -74.724006 -90)
		(property "Reference" "PR23"
			(at 0 0 270)
			(layer "F.SilkS")
			(hide yes)
			(effects
				(font
					(size 1.27 1.27)
				)
			)
		)
		(property "Value" "2K87R2F-1-GP"
			(at 0.064008 -3.993896 270)
			(unlocked yes)
			(layer "F.Fab")
			(hide yes)
			(effects
				(font
					(size 1.016 1.016)
					(thickness 0.1524)
				)
			)
		)
		(property "Device Type" "R402H16"
			(at 0.064008 -5.517896 270)
			(unlocked yes)
			(layer "F.Fab")
			(hide yes)
			(effects
				(font
					(size 1.016 1.016)
					(thickness 0.1524)
				)
			)
		)
		(duplicate_pad_numbers_are_jumpers no)
		(fp_line
			(start -0.508 -0.9398)
			(end -0.508 0.9398)
			(stroke
				(width 0.1524)
				(type default)
			)
			(layer "F.SilkS")
		)
		(fp_line
			(start 0.508 -0.9398)
			(end -0.508 -0.9398)
			(stroke
				(width 0.1524)
				(type default)
			)
			(layer "F.SilkS")
		)
		(fp_rect
			(start -0.508 0.9398)
			(end 0.508 -0.9398)
			(stroke
				(width 0)
				(type default)
			)
			(fill no)
			(layer "F.CrtYd")
		)
		(fp_rect
			(start -0.508 0.9398)
			(end 0.508 -0.9398)
			(stroke
				(width 0)
				(type default)
			)
			(fill no)
			(layer "F.Fab")
		)
		(pad "1" smd custom
			(at 0 -0.4445 270)
			(size 0.1397 0.1397)
			(layers "F.Cu" "F.Mask" "F.Paste")
			(net "P1V8_PWR_FB")
			(options
				(clearance outline)
				(anchor circle)
			)
			(primitives
				(gr_poly
					(pts
						(arc
							(start -0.1778 -0.2794)
							(mid -0.249642 -0.249642)
							(end -0.2794 -0.1778)
						)
						(arc
							(start -0.2794 0.1778)
							(mid -0.249642 0.249642)
							(end -0.1778 0.2794)
						)
						(arc
							(start 0.1778 0.2794)
							(mid 0.249642 0.249642)
							(end 0.2794 0.1778)
						)
						(arc
							(start 0.2794 -0.1778)
							(mid 0.249642 -0.249642)
							(end 0.1778 -0.2794)
						)
					)
					(width 0)
					(fill yes)
				)
			)
		)
		(pad "2" smd custom
			(at 0 0.4445 270)
			(size 0.1397 0.1397)
			(layers "F.Cu" "F.Mask" "F.Paste")
			(net "GND")
			(options
				(clearance outline)
				(anchor circle)
			)
			(primitives
				(gr_poly
					(pts
						(arc
							(start -0.1778 -0.2794)
							(mid -0.249642 -0.249642)
							(end -0.2794 -0.1778)
						)
						(arc
							(start -0.2794 0.1778)
							(mid -0.249642 0.249642)
							(end -0.1778 0.2794)
						)
						(arc
							(start 0.1778 0.2794)
							(mid 0.249642 0.249642)
							(end 0.2794 0.1778)
						)
						(arc
							(start 0.2794 -0.1778)
							(mid 0.249642 -0.249642)
							(end 0.1778 -0.2794)
						)
					)
					(width 0)
					(fill yes)
				)
			)
		)
	)
	(footprint ""
		(layer "F.Cu")
		(at 15.748 -84.122006 -90)
		(property "Reference" "PC26"
			(at 0 0 270)
			(layer "F.SilkS")
			(hide yes)
			(effects
				(font
					(size 1.27 1.27)
				)
			)
		)
		(property "Value" "SC10U6D3V5KX-4GP"
			(at -0.0762 -6.1214 270)
			(unlocked yes)
			(layer "F.Fab")
			(hide yes)
			(effects
				(font
					(size 1.016 1.016)
					(thickness 0.1524)
				)
			)
		)
		(property "Device Type" "C805H58"
			(at -0.0762 -8.1534 270)
			(unlocked yes)
			(layer "F.Fab")
			(hide yes)
			(effects
				(font
					(size 1.016 1.016)
					(thickness 0.1524)
				)
			)
		)
		(duplicate_pad_numbers_are_jumpers no)
		(fp_line
			(start 0.635 0)
			(end -0.635 0)
			(stroke
				(width 0.508)
				(type default)
			)
			(layer "F.SilkS")
		)
		(fp_rect
			(start -0.9652 1.778)
			(end 0.9652 -1.778)
			(stroke
				(width 0)
				(type default)
			)
			(fill no)
			(layer "F.CrtYd")
		)
		(fp_poly
			(pts
				(xy -0.9652 -1.778) (xy 0.9652 -1.778) (xy 0.9652 1.778) (xy -0.9652 1.778)
			)
			(stroke
				(width 0)
				(type default)
			)
			(fill no)
			(layer "F.Fab")
		)
		(pad "1" smd rect
			(at 0 -0.9652 270)
			(size 1.397 1.143)
			(layers "F.Cu" "F.Mask" "F.Paste")
			(net "P1V8_PWR_BIAS")
		)
		(pad "2" smd rect
			(at 0 0.9652 270)
			(size 1.397 1.143)
			(layers "F.Cu" "F.Mask" "F.Paste")
			(net "GND")
		)
	)
	(footprint ""
		(layer "F.Cu")
		(at 33.02 -74.549)
		(property "Reference" "C11"
			(at 0 0 0)
			(layer "F.SilkS")
			(hide yes)
			(effects
				(font
					(size 1.27 1.27)
				)
			)
		)
		(property "Value" "SCD1U16V2KX-3GP"
			(at 1.1811 -2.7051 0)
			(unlocked yes)
			(layer "F.Fab")
			(hide yes)
			(effects
				(font
					(size 1.016 1.016)
					(thickness 0.1524)
				)
			)
		)
		(property "Device Type" "C402H22"
			(at 1.1811 -4.2291 0)
			(unlocked yes)
			(layer "F.Fab")
			(hide yes)
			(effects
				(font
					(size 1.016 1.016)
					(thickness 0.1524)
				)
			)
		)
		(duplicate_pad_numbers_are_jumpers no)
		(fp_rect
			(start -0.4318 0.9525)
			(end 0.4318 -0.9525)
			(stroke
				(width 0)
				(type default)
			)
			(fill no)
			(layer "F.CrtYd")
		)
		(fp_rect
			(start -0.4318 0.9525)
			(end 0.4318 -0.9525)
			(stroke
				(width 0)
				(type default)
			)
			(fill no)
			(layer "F.Fab")
		)
		(pad "1" smd custom
			(at 0 -0.4445)
			(size 0.1524 0.1524)
			(layers "F.Cu" "F.Mask" "F.Paste")
			(net "P3V3_DPB")
			(options
				(clearance outline)
				(anchor circle)
			)
			(primitives
				(gr_poly
					(pts
						(arc
							(start 0.3048 -0.2032)
							(mid 0.275042 -0.275042)
							(end 0.2032 -0.3048)
						)
						(arc
							(start -0.2032 -0.3048)
							(mid -0.275042 -0.275042)
							(end -0.3048 -0.2032)
						)
						(arc
							(start -0.3048 0.2032)
							(mid -0.275042 0.275042)
							(end -0.2032 0.3048)
						)
						(arc
							(start 0.2032 0.3048)
							(mid 0.275042 0.275042)
							(end 0.3048 0.2032)
						)
					)
					(width 0)
					(fill yes)
				)
			)
		)
		(pad "2" smd custom
			(at 0 0.4445)
			(size 0.1524 0.1524)
			(layers "F.Cu" "F.Mask" "F.Paste")
			(net "GND")
			(options
				(clearance outline)
				(anchor circle)
			)
			(primitives
				(gr_poly
					(pts
						(arc
							(start 0.3048 -0.2032)
							(mid 0.275042 -0.275042)
							(end 0.2032 -0.3048)
						)
						(arc
							(start -0.2032 -0.3048)
							(mid -0.275042 -0.275042)
							(end -0.3048 -0.2032)
						)
						(arc
							(start -0.3048 0.2032)
							(mid -0.275042 0.275042)
							(end -0.2032 0.3048)
						)
						(arc
							(start 0.2032 0.3048)
							(mid 0.275042 0.275042)
							(end 0.3048 0.2032)
						)
					)
					(width 0)
					(fill yes)
				)
			)
		)
	)
	(footprint ""
		(layer "F.Cu")
		(at 30.226 -78.74)
		(property "Reference" "R39"
			(at 0 0 0)
			(layer "F.SilkS")
			(hide yes)
			(effects
				(font
					(size 1.27 1.27)
				)
			)
		)
		(property "Value" "0R2J-2-GP"
			(at 0.064008 -3.993896 0)
			(unlocked yes)
			(layer "F.Fab")
			(hide yes)
			(effects
				(font
					(size 1.016 1.016)
					(thickness 0.1524)
				)
			)
		)
		(property "Device Type" "R402H16"
			(at 0.064008 -5.517896 0)
			(unlocked yes)
			(layer "F.Fab")
			(hide yes)
			(effects
				(font
					(size 1.016 1.016)
					(thickness 0.1524)
				)
			)
		)
		(duplicate_pad_numbers_are_jumpers no)
		(fp_line
			(start -0.508 -0.9398)
			(end -0.508 0.9398)
			(stroke
				(width 0.1524)
				(type default)
			)
			(layer "F.SilkS")
		)
		(fp_line
			(start 0.508 -0.9398)
			(end -0.508 -0.9398)
			(stroke
				(width 0.1524)
				(type default)
			)
			(layer "F.SilkS")
		)
		(fp_rect
			(start -0.508 0.9398)
			(end 0.508 -0.9398)
			(stroke
				(width 0)
				(type default)
			)
			(fill no)
			(layer "F.CrtYd")
		)
		(fp_rect
			(start -0.508 0.9398)
			(end 0.508 -0.9398)
			(stroke
				(width 0)
				(type default)
			)
			(fill no)
			(layer "F.Fab")
		)
		(pad "1" smd custom
			(at 0 -0.4445)
			(size 0.1397 0.1397)
			(layers "F.Cu" "F.Mask" "F.Paste")
			(net "Z50_SSD_A1_SMB_CLK_R")
			(options
				(clearance outline)
				(anchor circle)
			)
			(primitives
				(gr_poly
					(pts
						(arc
							(start -0.1778 -0.2794)
							(mid -0.249642 -0.249642)
							(end -0.2794 -0.1778)
						)
						(arc
							(start -0.2794 0.1778)
							(mid -0.249642 0.249642)
							(end -0.1778 0.2794)
						)
						(arc
							(start 0.1778 0.2794)
							(mid 0.249642 0.249642)
							(end 0.2794 0.1778)
						)
						(arc
							(start 0.2794 -0.1778)
							(mid 0.249642 -0.249642)
							(end 0.1778 -0.2794)
						)
					)
					(width 0)
					(fill yes)
				)
			)
		)
		(pad "2" smd custom
			(at 0 0.4445)
			(size 0.1397 0.1397)
			(layers "F.Cu" "F.Mask" "F.Paste")
			(net "Z50_SSD_A1_SMB_CLK_LL")
			(options
				(clearance outline)
				(anchor circle)
			)
			(primitives
				(gr_poly
					(pts
						(arc
							(start -0.1778 -0.2794)
							(mid -0.249642 -0.249642)
							(end -0.2794 -0.1778)
						)
						(arc
							(start -0.2794 0.1778)
							(mid -0.249642 0.249642)
							(end -0.1778 0.2794)
						)
						(arc
							(start 0.1778 0.2794)
							(mid 0.249642 0.249642)
							(end 0.2794 0.1778)
						)
						(arc
							(start 0.2794 -0.1778)
							(mid 0.249642 -0.249642)
							(end 0.1778 -0.2794)
						)
					)
					(width 0)
					(fill yes)
				)
			)
		)
	)
	(footprint ""
		(layer "F.Cu")
		(at 27.813 -72.39)
		(property "Reference" "C9"
			(at 0 0 0)
			(layer "F.SilkS")
			(hide yes)
			(effects
				(font
					(size 1.27 1.27)
				)
			)
		)
		(property "Value" "SCD1U16V2KX-3GP"
			(at 1.1811 -2.7051 0)
			(unlocked yes)
			(layer "F.Fab")
			(hide yes)
			(effects
				(font
					(size 1.016 1.016)
					(thickness 0.1524)
				)
			)
		)
		(property "Device Type" "C402H22"
			(at 1.1811 -4.2291 0)
			(unlocked yes)
			(layer "F.Fab")
			(hide yes)
			(effects
				(font
					(size 1.016 1.016)
					(thickness 0.1524)
				)
			)
		)
		(duplicate_pad_numbers_are_jumpers no)
		(fp_rect
			(start -0.4318 0.9525)
			(end 0.4318 -0.9525)
			(stroke
				(width 0)
				(type default)
			)
			(fill no)
			(layer "F.CrtYd")
		)
		(fp_rect
			(start -0.4318 0.9525)
			(end 0.4318 -0.9525)
			(stroke
				(width 0)
				(type default)
			)
			(fill no)
			(layer "F.Fab")
		)
		(pad "1" smd custom
			(at 0 -0.4445)
			(size 0.1524 0.1524)
			(layers "F.Cu" "F.Mask" "F.Paste")
			(net "P1V8_PWR")
			(options
				(clearance outline)
				(anchor circle)
			)
			(primitives
				(gr_poly
					(pts
						(arc
							(start 0.3048 -0.2032)
							(mid 0.275042 -0.275042)
							(end 0.2032 -0.3048)
						)
						(arc
							(start -0.2032 -0.3048)
							(mid -0.275042 -0.275042)
							(end -0.3048 -0.2032)
						)
						(arc
							(start -0.3048 0.2032)
							(mid -0.275042 0.275042)
							(end -0.2032 0.3048)
						)
						(arc
							(start 0.2032 0.3048)
							(mid 0.275042 0.275042)
							(end 0.3048 0.2032)
						)
					)
					(width 0)
					(fill yes)
				)
			)
		)
		(pad "2" smd custom
			(at 0 0.4445)
			(size 0.1524 0.1524)
			(layers "F.Cu" "F.Mask" "F.Paste")
			(net "GND")
			(options
				(clearance outline)
				(anchor circle)
			)
			(primitives
				(gr_poly
					(pts
						(arc
							(start 0.3048 -0.2032)
							(mid 0.275042 -0.275042)
							(end 0.2032 -0.3048)
						)
						(arc
							(start -0.2032 -0.3048)
							(mid -0.275042 -0.275042)
							(end -0.3048 -0.2032)
						)
						(arc
							(start -0.3048 0.2032)
							(mid -0.275042 0.275042)
							(end -0.2032 0.3048)
						)
						(arc
							(start 0.2032 0.3048)
							(mid 0.275042 0.275042)
							(end 0.3048 0.2032)
						)
					)
					(width 0)
					(fill yes)
				)
			)
		)
	)
	(footprint ""
		(layer "F.Cu")
		(at 59.817 -30.988 -90)
		(property "Reference" "C38"
			(at 0 0 270)
			(layer "F.SilkS")
			(hide yes)
			(effects
				(font
					(size 1.27 1.27)
				)
			)
		)
		(property "Value" "SC1U6D3V2KX-9-GP"
			(at 1.1811 -2.7051 270)
			(unlocked yes)
			(layer "F.Fab")
			(hide yes)
			(effects
				(font
					(size 1.016 1.016)
					(thickness 0.1524)
				)
			)
		)
		(property "Device Type" "C402H22"
			(at 1.1811 -4.2291 270)
			(unlocked yes)
			(layer "F.Fab")
			(hide yes)
			(effects
				(font
					(size 1.016 1.016)
					(thickness 0.1524)
				)
			)
		)
		(duplicate_pad_numbers_are_jumpers no)
		(fp_rect
			(start -0.4318 0.9525)
			(end 0.4318 -0.9525)
			(stroke
				(width 0)
				(type default)
			)
			(fill no)
			(layer "F.CrtYd")
		)
		(fp_rect
			(start -0.4318 0.9525)
			(end 0.4318 -0.9525)
			(stroke
				(width 0)
				(type default)
			)
			(fill no)
			(layer "F.Fab")
		)
		(pad "1" smd custom
			(at 0 -0.4445 270)
			(size 0.1524 0.1524)
			(layers "F.Cu" "F.Mask" "F.Paste")
			(net "P3V3_PWR")
			(options
				(clearance outline)
				(anchor circle)
			)
			(primitives
				(gr_poly
					(pts
						(arc
							(start 0.3048 -0.2032)
							(mid 0.275042 -0.275042)
							(end 0.2032 -0.3048)
						)
						(arc
							(start -0.2032 -0.3048)
							(mid -0.275042 -0.275042)
							(end -0.3048 -0.2032)
						)
						(arc
							(start -0.3048 0.2032)
							(mid -0.275042 0.275042)
							(end -0.2032 0.3048)
						)
						(arc
							(start 0.2032 0.3048)
							(mid 0.275042 0.275042)
							(end 0.3048 0.2032)
						)
					)
					(width 0)
					(fill yes)
				)
			)
		)
		(pad "2" smd custom
			(at 0 0.4445 270)
			(size 0.1524 0.1524)
			(layers "F.Cu" "F.Mask" "F.Paste")
			(net "GND")
			(options
				(clearance outline)
				(anchor circle)
			)
			(primitives
				(gr_poly
					(pts
						(arc
							(start 0.3048 -0.2032)
							(mid 0.275042 -0.275042)
							(end 0.2032 -0.3048)
						)
						(arc
							(start -0.2032 -0.3048)
							(mid -0.275042 -0.275042)
							(end -0.3048 -0.2032)
						)
						(arc
							(start -0.3048 0.2032)
							(mid -0.275042 0.275042)
							(end -0.2032 0.3048)
						)
						(arc
							(start 0.2032 0.3048)
							(mid 0.275042 0.275042)
							(end 0.3048 0.2032)
						)
					)
					(width 0)
					(fill yes)
				)
			)
		)
	)
	(footprint ""
		(layer "F.Cu")
		(at 41.226994 -75.819)
		(property "Reference" "TP2"
			(at 0 0 0)
			(layer "F.SilkS")
			(hide yes)
			(effects
				(font
					(size 1.27 1.27)
				)
			)
		)
		(property "Value" "TPAD28-1-GP-U"
			(at 0.0508 -1.9304 0)
			(unlocked yes)
			(layer "F.Fab")
			(hide yes)
			(effects
				(font
					(size 1.016 1.016)
					(thickness 0.1524)
				)
			)
		)
		(property "Device Type" "TPAD28-1-U"
			(at 0.0508 -3.4544 0)
			(unlocked yes)
			(layer "F.Fab")
			(hide yes)
			(effects
				(font
					(size 1.016 1.016)
					(thickness 0.1524)
				)
			)
		)
		(duplicate_pad_numbers_are_jumpers no)
		(fp_poly
			(pts
				(arc
					(start 0.3556 0)
					(mid -0.3556 0)
					(end 0.3556 0)
				)
			)
			(stroke
				(width 0)
				(type default)
			)
			(fill no)
			(layer "F.CrtYd")
		)
		(fp_poly
			(pts
				(arc
					(start 0.9525 0)
					(mid -0.9525 0)
					(end 0.9525 0)
				)
			)
			(stroke
				(width 0)
				(type default)
			)
			(fill no)
			(layer "F.Fab")
		)
		(pad "1" smd circle
			(at 0 0)
			(size 0.7112 0.7112)
			(layers "F.Cu" "F.Mask" "F.Paste")
			(net "P3V3_DEV_PWRGD")
		)
	)
	(footprint ""
		(layer "F.Cu")
		(at 18.161 -80.185006)
		(property "Reference" "PU2"
			(at 0 0 0)
			(layer "F.SilkS")
			(hide yes)
			(effects
				(font
					(size 1.27 1.27)
				)
			)
		)
		(property "Value" "TPS74801DRCR-1-GP-U"
			(at -3.5306 1.3208 0)
			(unlocked yes)
			(layer "F.Fab")
			(hide yes)
			(effects
				(font
					(size 1.016 1.016)
					(thickness 0.1524)
				)
			)
		)
		(property "Device Type" "DFN10G3-G315175H40"
			(at -3.5306 -0.2032 0)
			(unlocked yes)
			(layer "F.Fab")
			(hide yes)
			(effects
				(font
					(size 1.016 1.016)
					(thickness 0.1524)
				)
			)
		)
		(duplicate_pad_numbers_are_jumpers no)
		(fp_line
			(start -2.3876 -2.5146)
			(end -2.3876 -1.7526)
			(stroke
				(width 0.1524)
				(type default)
			)
			(layer "F.SilkS")
		)
		(fp_line
			(start -2.3876 1.7526)
			(end -2.3876 2.5146)
			(stroke
				(width 0.1524)
				(type default)
			)
			(layer "F.SilkS")
		)
		(fp_line
			(start -2.3876 2.5146)
			(end -1.6256 2.5146)
			(stroke
				(width 0.1524)
				(type default)
			)
			(layer "F.SilkS")
		)
		(fp_line
			(start -1.6256 -2.5146)
			(end -2.3876 -2.5146)
			(stroke
				(width 0.1524)
				(type default)
			)
			(layer "F.SilkS")
		)
		(fp_line
			(start -0.9906 -2.794)
			(end -0.9906 -2.286)
			(stroke
				(width 0.1524)
				(type default)
			)
			(layer "F.SilkS")
		)
		(fp_line
			(start 0.9906 2.286)
			(end 0.9906 3.048)
			(stroke
				(width 0.1524)
				(type default)
			)
			(layer "F.SilkS")
		)
		(fp_line
			(start 1.6256 2.5146)
			(end 2.3876 2.5146)
			(stroke
				(width 0.1524)
				(type default)
			)
			(layer "F.SilkS")
		)
		(fp_line
			(start 2.3876 2.5146)
			(end 2.3876 1.7526)
			(stroke
				(width 0.1524)
				(type default)
			)
			(layer "F.SilkS")
		)
		(fp_poly
			(pts
				(xy 1.6256 -2.5146) (xy 2.3876 -2.5146) (xy 2.3876 -1.7526)
			)
			(stroke
				(width 0)
				(type default)
			)
			(fill yes)
			(layer "F.SilkS")
		)
		(fp_rect
			(start -1.4986 1.4986)
			(end 1.4986 -1.4986)
			(stroke
				(width 0)
				(type default)
			)
			(fill no)
			(layer "F.CrtYd")
		)
		(fp_poly
			(pts
				(xy -2.3876 2.5146) (xy -2.3876 0.00254) (xy -1.4986 0.00254) (xy -1.4986 1.4986) (xy 1.4986 1.4986)
				(xy 1.4986 -1.4986) (xy -1.4986 -1.4986) (xy -1.4986 -0.00254) (xy -2.3876 -0.00254) (xy -2.3876 -2.5146)
				(xy 2.3876 -2.5146) (xy 2.3876 2.5146)
			)
			(stroke
				(width 0)
				(type default)
			)
			(fill no)
			(layer "F.CrtYd")
		)
		(fp_rect
			(start -2.3876 2.5146)
			(end 2.3876 -2.5146)
			(stroke
				(width 0)
				(type default)
			)
			(fill no)
			(layer "F.Fab")
		)
		(pad "1" smd rect
			(at 0.99949 -1.5494)
			(size 0.3048 0.9144)
			(layers "F.Cu" "F.Mask" "F.Paste")
			(net "P3V3_PWR")
		)
		(pad "2" smd rect
			(at 0.50038 -1.5494)
			(size 0.3048 0.9144)
			(layers "F.Cu" "F.Mask" "F.Paste")
			(net "P3V3_PWR")
		)
		(pad "3" smd rect
			(at 0 -1.5494)
			(size 0.3048 0.9144)
			(layers "F.Cu" "F.Mask" "F.Paste")
			(net "P1V8_PWR_GD")
		)
		(pad "4" smd rect
			(at -0.50038 -1.5494)
			(size 0.3048 0.9144)
			(layers "F.Cu" "F.Mask" "F.Paste")
			(net "P1V8_PWR_BIAS")
		)
		(pad "5" smd rect
			(at -0.99949 -1.5494)
			(size 0.3048 0.9144)
			(layers "F.Cu" "F.Mask" "F.Paste")
			(net "P1V8_PWR_EN_R")
		)
		(pad "6" smd rect
			(at -0.99949 1.5494)
			(size 0.3048 0.9144)
			(layers "F.Cu" "F.Mask" "F.Paste")
			(net "GND")
		)
		(pad "7" smd rect
			(at -0.50038 1.5494)
			(size 0.3048 0.9144)
			(layers "F.Cu" "F.Mask" "F.Paste")
			(net "P1V8_PWR_SS_C")
		)
		(pad "8" smd rect
			(at 0 1.5494)
			(size 0.3048 0.9144)
			(layers "F.Cu" "F.Mask" "F.Paste")
			(net "P1V8_PWR_FB")
		)
		(pad "9" smd rect
			(at 0.50038 1.5494)
			(size 0.3048 0.9144)
			(layers "F.Cu" "F.Mask" "F.Paste")
			(net "P1V8_PWR")
		)
		(pad "10" smd rect
			(at 0.99949 1.5494)
			(size 0.3048 0.9144)
			(layers "F.Cu" "F.Mask" "F.Paste")
			(net "P1V8_PWR")
		)
		(pad "11" smd custom
			(at 0 0)
			(size 0.4318 0.4318)
			(layers "F.Cu" "F.Mask" "F.Paste")
			(net "GND")
			(options
				(clearance outline)
				(anchor circle)
			)
			(primitives
				(gr_poly
					(pts
						(xy -1.2446 0.8636) (xy -1.2446 0.3937) (xy -1.8796 0.3937) (xy -1.8796 0.1143) (xy -1.2446 0.1143)
						(xy -1.2446 -0.1143) (xy -1.8796 -0.1143) (xy -1.8796 -0.3937) (xy -1.2446 -0.3937) (xy -1.2446 -0.8636)
						(xy 1.2446 -0.8636) (xy 1.2446 -0.3937) (xy 1.8796 -0.3937) (xy 1.8796 -0.1143) (xy 1.2446 -0.1143)
						(xy 1.2446 0.1143) (xy 1.8796 0.1143) (xy 1.8796 0.3937) (xy 1.2446 0.3937) (xy 1.2446 0.8636)
					)
					(width 0)
					(fill yes)
				)
			)
		)
	)
	(footprint ""
		(layer "F.Cu")
		(at 75.692 -42.037 180)
		(property "Reference" "U5"
			(at 0 0 180)
			(layer "F.SilkS")
			(hide yes)
			(effects
				(font
					(size 1.27 1.27)
				)
			)
		)
		(property "Value" "74LVC1G32DC-1GP"
			(at -2.3368 -8.6868 180)
			(unlocked yes)
			(layer "F.Fab")
			(hide yes)
			(effects
				(font
					(size 1.016 1.016)
					(thickness 0.1524)
				)
			)
		)
		(property "Device Type" "SC70-5H44"
			(at -2.3114 -10.414 180)
			(unlocked yes)
			(layer "F.Fab")
			(hide yes)
			(effects
				(font
					(size 1.016 1.016)
					(thickness 0.1524)
				)
			)
		)
		(duplicate_pad_numbers_are_jumpers no)
		(fp_line
			(start 1.3843 -1.8034)
			(end 1.3843 -1.1176)
			(stroke
				(width 0.3302)
				(type default)
			)
			(layer "F.SilkS")
		)
		(fp_line
			(start 1.27 1.7018)
			(end -1.27 1.7018)
			(stroke
				(width 0.1524)
				(type default)
			)
			(layer "F.SilkS")
		)
		(fp_line
			(start 1.27 -1.7018)
			(end 1.27 1.7018)
			(stroke
				(width 0.1524)
				(type default)
			)
			(layer "F.SilkS")
		)
		(fp_line
			(start 0.6604 -1.8034)
			(end 1.3843 -1.8034)
			(stroke
				(width 0.3302)
				(type default)
			)
			(layer "F.SilkS")
		)
		(fp_line
			(start -1.27 1.7018)
			(end -1.27 -1.7018)
			(stroke
				(width 0.1524)
				(type default)
			)
			(layer "F.SilkS")
		)
		(fp_line
			(start -1.27 -1.7018)
			(end 1.27 -1.7018)
			(stroke
				(width 0.1524)
				(type default)
			)
			(layer "F.SilkS")
		)
		(fp_rect
			(start -1.524 1.9558)
			(end 1.524 -1.9558)
			(stroke
				(width 0)
				(type default)
			)
			(fill no)
			(layer "F.CrtYd")
		)
		(fp_poly
			(pts
				(xy -1.524 -1.9558) (xy 1.524 -1.9558) (xy 1.524 1.9558) (xy -1.524 1.9558)
			)
			(stroke
				(width 0)
				(type default)
			)
			(fill no)
			(layer "F.Fab")
		)
		(pad "1" smd rect
			(at 0.65024 -0.8255 180)
			(size 0.4064 1.2192)
			(layers "F.Cu" "F.Mask" "F.Paste")
			(net "Z50_SSD_A_PRSNT#")
		)
		(pad "2" smd rect
			(at 0 -0.8255 180)
			(size 0.4064 1.2192)
			(layers "F.Cu" "F.Mask" "F.Paste")
			(net "Z50_SSD_B_PRSNT#")
		)
		(pad "3" smd rect
			(at -0.65024 -0.8255 180)
			(size 0.4064 1.2192)
			(layers "F.Cu" "F.Mask" "F.Paste")
			(net "GND")
		)
		(pad "4" smd rect
			(at -0.65024 0.8255 180)
			(size 0.4064 1.2192)
			(layers "F.Cu" "F.Mask" "F.Paste")
			(net "Z50_SSD_M2_PRSNT#")
		)
		(pad "5" smd rect
			(at 0.65024 0.8255 180)
			(size 0.4064 1.2192)
			(layers "F.Cu" "F.Mask" "F.Paste")
			(net "P3V3_DPB")
		)
	)
	(footprint ""
		(layer "F.Cu")
		(at 14.732 -82.598006 -90)
		(property "Reference" "PC20"
			(at 0 0 270)
			(layer "F.SilkS")
			(hide yes)
			(effects
				(font
					(size 1.27 1.27)
				)
			)
		)
		(property "Value" "SCD01U25V2KX-3GP"
			(at 1.1811 -2.7051 270)
			(unlocked yes)
			(layer "F.Fab")
			(hide yes)
			(effects
				(font
					(size 1.016 1.016)
					(thickness 0.1524)
				)
			)
		)
		(property "Device Type" "C402H22"
			(at 1.1811 -4.2291 270)
			(unlocked yes)
			(layer "F.Fab")
			(hide yes)
			(effects
				(font
					(size 1.016 1.016)
					(thickness 0.1524)
				)
			)
		)
		(duplicate_pad_numbers_are_jumpers no)
		(fp_rect
			(start -0.4318 0.9525)
			(end 0.4318 -0.9525)
			(stroke
				(width 0)
				(type default)
			)
			(fill no)
			(layer "F.CrtYd")
		)
		(fp_rect
			(start -0.4318 0.9525)
			(end 0.4318 -0.9525)
			(stroke
				(width 0)
				(type default)
			)
			(fill no)
			(layer "F.Fab")
		)
		(pad "1" smd custom
			(at 0 -0.4445 270)
			(size 0.1524 0.1524)
			(layers "F.Cu" "F.Mask" "F.Paste")
			(net "P1V8_PWR_EN_R")
			(options
				(clearance outline)
				(anchor circle)
			)
			(primitives
				(gr_poly
					(pts
						(arc
							(start 0.3048 -0.2032)
							(mid 0.275042 -0.275042)
							(end 0.2032 -0.3048)
						)
						(arc
							(start -0.2032 -0.3048)
							(mid -0.275042 -0.275042)
							(end -0.3048 -0.2032)
						)
						(arc
							(start -0.3048 0.2032)
							(mid -0.275042 0.275042)
							(end -0.2032 0.3048)
						)
						(arc
							(start 0.2032 0.3048)
							(mid 0.275042 0.275042)
							(end 0.3048 0.2032)
						)
					)
					(width 0)
					(fill yes)
				)
			)
		)
		(pad "2" smd custom
			(at 0 0.4445 270)
			(size 0.1524 0.1524)
			(layers "F.Cu" "F.Mask" "F.Paste")
			(net "GND")
			(options
				(clearance outline)
				(anchor circle)
			)
			(primitives
				(gr_poly
					(pts
						(arc
							(start 0.3048 -0.2032)
							(mid 0.275042 -0.275042)
							(end 0.2032 -0.3048)
						)
						(arc
							(start -0.2032 -0.3048)
							(mid -0.275042 -0.275042)
							(end -0.3048 -0.2032)
						)
						(arc
							(start -0.3048 0.2032)
							(mid -0.275042 0.275042)
							(end -0.2032 0.3048)
						)
						(arc
							(start 0.2032 0.3048)
							(mid 0.275042 0.275042)
							(end 0.3048 0.2032)
						)
					)
					(width 0)
					(fill yes)
				)
			)
		)
	)
	(footprint ""
		(layer "F.Cu")
		(at 75.184 -35.941)
		(property "Reference" "R4"
			(at 0 0 0)
			(layer "F.SilkS")
			(hide yes)
			(effects
				(font
					(size 1.27 1.27)
				)
			)
		)
		(property "Value" "0R2J-2-GP"
			(at 0.064008 -3.993896 0)
			(unlocked yes)
			(layer "F.Fab")
			(hide yes)
			(effects
				(font
					(size 1.016 1.016)
					(thickness 0.1524)
				)
			)
		)
		(property "Device Type" "R402H16"
			(at 0.064008 -5.517896 0)
			(unlocked yes)
			(layer "F.Fab")
			(hide yes)
			(effects
				(font
					(size 1.016 1.016)
					(thickness 0.1524)
				)
			)
		)
		(duplicate_pad_numbers_are_jumpers no)
		(fp_line
			(start -0.508 -0.9398)
			(end -0.508 0.9398)
			(stroke
				(width 0.1524)
				(type default)
			)
			(layer "F.SilkS")
		)
		(fp_line
			(start 0.508 -0.9398)
			(end -0.508 -0.9398)
			(stroke
				(width 0.1524)
				(type default)
			)
			(layer "F.SilkS")
		)
		(fp_rect
			(start -0.508 0.9398)
			(end 0.508 -0.9398)
			(stroke
				(width 0)
				(type default)
			)
			(fill no)
			(layer "F.CrtYd")
		)
		(fp_rect
			(start -0.508 0.9398)
			(end 0.508 -0.9398)
			(stroke
				(width 0)
				(type default)
			)
			(fill no)
			(layer "F.Fab")
		)
		(pad "1" smd custom
			(at 0 -0.4445)
			(size 0.1397 0.1397)
			(layers "F.Cu" "F.Mask" "F.Paste")
			(net "Z50_SSD_B_PRESENT_R#")
			(options
				(clearance outline)
				(anchor circle)
			)
			(primitives
				(gr_poly
					(pts
						(arc
							(start -0.1778 -0.2794)
							(mid -0.249642 -0.249642)
							(end -0.2794 -0.1778)
						)
						(arc
							(start -0.2794 0.1778)
							(mid -0.249642 0.249642)
							(end -0.1778 0.2794)
						)
						(arc
							(start 0.1778 0.2794)
							(mid 0.249642 0.249642)
							(end 0.2794 0.1778)
						)
						(arc
							(start 0.2794 -0.1778)
							(mid 0.249642 -0.249642)
							(end 0.1778 -0.2794)
						)
					)
					(width 0)
					(fill yes)
				)
			)
		)
		(pad "2" smd custom
			(at 0 0.4445)
			(size 0.1397 0.1397)
			(layers "F.Cu" "F.Mask" "F.Paste")
			(net "Z50_SSD_B_PRSNT#")
			(options
				(clearance outline)
				(anchor circle)
			)
			(primitives
				(gr_poly
					(pts
						(arc
							(start -0.1778 -0.2794)
							(mid -0.249642 -0.249642)
							(end -0.2794 -0.1778)
						)
						(arc
							(start -0.2794 0.1778)
							(mid -0.249642 0.249642)
							(end -0.1778 0.2794)
						)
						(arc
							(start 0.1778 0.2794)
							(mid 0.249642 0.249642)
							(end 0.2794 0.1778)
						)
						(arc
							(start 0.2794 -0.1778)
							(mid 0.249642 -0.249642)
							(end 0.1778 -0.2794)
						)
					)
					(width 0)
					(fill yes)
				)
			)
		)
	)
	(footprint ""
		(layer "F.Cu")
		(at 44.782994 -76.2 180)
		(property "Reference" "PR32"
			(at 0 0 180)
			(layer "F.SilkS")
			(hide yes)
			(effects
				(font
					(size 1.27 1.27)
				)
			)
		)
		(property "Value" "866KR2F-GP"
			(at 0.064008 -3.993896 180)
			(unlocked yes)
			(layer "F.Fab")
			(hide yes)
			(effects
				(font
					(size 1.016 1.016)
					(thickness 0.1524)
				)
			)
		)
		(property "Device Type" "R402H16"
			(at 0.064008 -5.517896 180)
			(unlocked yes)
			(layer "F.Fab")
			(hide yes)
			(effects
				(font
					(size 1.016 1.016)
					(thickness 0.1524)
				)
			)
		)
		(duplicate_pad_numbers_are_jumpers no)
		(fp_line
			(start 0.508 -0.9398)
			(end -0.508 -0.9398)
			(stroke
				(width 0.1524)
				(type default)
			)
			(layer "F.SilkS")
		)
		(fp_line
			(start -0.508 -0.9398)
			(end -0.508 0.9398)
			(stroke
				(width 0.1524)
				(type default)
			)
			(layer "F.SilkS")
		)
		(fp_rect
			(start -0.508 0.9398)
			(end 0.508 -0.9398)
			(stroke
				(width 0)
				(type default)
			)
			(fill no)
			(layer "F.CrtYd")
		)
		(fp_rect
			(start -0.508 0.9398)
			(end 0.508 -0.9398)
			(stroke
				(width 0)
				(type default)
			)
			(fill no)
			(layer "F.Fab")
		)
		(pad "1" smd custom
			(at 0 -0.4445 180)
			(size 0.1397 0.1397)
			(layers "F.Cu" "F.Mask" "F.Paste")
			(net "P3V3_DEV_VREG")
			(options
				(clearance outline)
				(anchor circle)
			)
			(primitives
				(gr_poly
					(pts
						(arc
							(start -0.1778 -0.2794)
							(mid -0.249642 -0.249642)
							(end -0.2794 -0.1778)
						)
						(arc
							(start -0.2794 0.1778)
							(mid -0.249642 0.249642)
							(end -0.1778 0.2794)
						)
						(arc
							(start 0.1778 0.2794)
							(mid 0.249642 0.249642)
							(end 0.2794 0.1778)
						)
						(arc
							(start 0.2794 -0.1778)
							(mid 0.249642 -0.249642)
							(end 0.1778 -0.2794)
						)
					)
					(width 0)
					(fill yes)
				)
			)
		)
		(pad "2" smd custom
			(at 0 0.4445 180)
			(size 0.1397 0.1397)
			(layers "F.Cu" "F.Mask" "F.Paste")
			(net "P3V3_DEV_RF")
			(options
				(clearance outline)
				(anchor circle)
			)
			(primitives
				(gr_poly
					(pts
						(arc
							(start -0.1778 -0.2794)
							(mid -0.249642 -0.249642)
							(end -0.2794 -0.1778)
						)
						(arc
							(start -0.2794 0.1778)
							(mid -0.249642 0.249642)
							(end -0.1778 0.2794)
						)
						(arc
							(start 0.1778 0.2794)
							(mid 0.249642 0.249642)
							(end 0.2794 0.1778)
						)
						(arc
							(start 0.2794 -0.1778)
							(mid 0.249642 -0.249642)
							(end 0.1778 -0.2794)
						)
					)
					(width 0)
					(fill yes)
				)
			)
		)
	)
	(footprint ""
		(layer "F.Cu")
		(at 59.817 -58.547 -90)
		(property "Reference" "C19"
			(at 0 0 270)
			(layer "F.SilkS")
			(hide yes)
			(effects
				(font
					(size 1.27 1.27)
				)
			)
		)
		(property "Value" "SC1U6D3V2KX-9-GP"
			(at 1.1811 -2.7051 270)
			(unlocked yes)
			(layer "F.Fab")
			(hide yes)
			(effects
				(font
					(size 1.016 1.016)
					(thickness 0.1524)
				)
			)
		)
		(property "Device Type" "C402H22"
			(at 1.1811 -4.2291 270)
			(unlocked yes)
			(layer "F.Fab")
			(hide yes)
			(effects
				(font
					(size 1.016 1.016)
					(thickness 0.1524)
				)
			)
		)
		(duplicate_pad_numbers_are_jumpers no)
		(fp_rect
			(start -0.4318 0.9525)
			(end 0.4318 -0.9525)
			(stroke
				(width 0)
				(type default)
			)
			(fill no)
			(layer "F.CrtYd")
		)
		(fp_rect
			(start -0.4318 0.9525)
			(end 0.4318 -0.9525)
			(stroke
				(width 0)
				(type default)
			)
			(fill no)
			(layer "F.Fab")
		)
		(pad "1" smd custom
			(at 0 -0.4445 270)
			(size 0.1524 0.1524)
			(layers "F.Cu" "F.Mask" "F.Paste")
			(net "P3V3_PWR")
			(options
				(clearance outline)
				(anchor circle)
			)
			(primitives
				(gr_poly
					(pts
						(arc
							(start 0.3048 -0.2032)
							(mid 0.275042 -0.275042)
							(end 0.2032 -0.3048)
						)
						(arc
							(start -0.2032 -0.3048)
							(mid -0.275042 -0.275042)
							(end -0.3048 -0.2032)
						)
						(arc
							(start -0.3048 0.2032)
							(mid -0.275042 0.275042)
							(end -0.2032 0.3048)
						)
						(arc
							(start 0.2032 0.3048)
							(mid 0.275042 0.275042)
							(end 0.3048 0.2032)
						)
					)
					(width 0)
					(fill yes)
				)
			)
		)
		(pad "2" smd custom
			(at 0 0.4445 270)
			(size 0.1524 0.1524)
			(layers "F.Cu" "F.Mask" "F.Paste")
			(net "GND")
			(options
				(clearance outline)
				(anchor circle)
			)
			(primitives
				(gr_poly
					(pts
						(arc
							(start 0.3048 -0.2032)
							(mid 0.275042 -0.275042)
							(end 0.2032 -0.3048)
						)
						(arc
							(start -0.2032 -0.3048)
							(mid -0.275042 -0.275042)
							(end -0.3048 -0.2032)
						)
						(arc
							(start -0.3048 0.2032)
							(mid -0.275042 0.275042)
							(end -0.2032 0.3048)
						)
						(arc
							(start 0.2032 0.3048)
							(mid 0.275042 0.275042)
							(end 0.3048 0.2032)
						)
					)
					(width 0)
					(fill yes)
				)
			)
		)
	)
	(footprint ""
		(layer "F.Cu")
		(at 63.246 -83.185 180)
		(property "Reference" "PC45"
			(at 0 0 180)
			(layer "F.SilkS")
			(hide yes)
			(effects
				(font
					(size 1.27 1.27)
				)
			)
		)
		(property "Value" "ST150U6D3VDM-28-GP"
			(at 0 -9.6012 180)
			(unlocked yes)
			(layer "F.Fab")
			(hide yes)
			(effects
				(font
					(size 1.016 1.016)
					(thickness 0.1524)
				)
			)
		)
		(property "Device Type" "CT7343H83"
			(at 0 -11.1252 180)
			(unlocked yes)
			(layer "F.Fab")
			(hide yes)
			(effects
				(font
					(size 1.016 1.016)
					(thickness 0.1524)
				)
			)
		)
		(duplicate_pad_numbers_are_jumpers no)
		(fp_line
			(start 2.286 4.8768)
			(end -2.286 4.8768)
			(stroke
				(width 0.1524)
				(type default)
			)
			(layer "F.SilkS")
		)
		(fp_line
			(start 2.286 2.032)
			(end 2.286 4.8768)
			(stroke
				(width 0.1524)
				(type default)
			)
			(layer "F.SilkS")
		)
		(fp_line
			(start 2.286 -2.032)
			(end 2.286 -4.8768)
			(stroke
				(width 0.1524)
				(type default)
			)
			(layer "F.SilkS")
		)
		(fp_line
			(start 2.286 -4.8768)
			(end -2.286 -4.8768)
			(stroke
				(width 0.1524)
				(type default)
			)
			(layer "F.SilkS")
		)
		(fp_line
			(start 2.1082 -4.699)
			(end -2.1082 -4.699)
			(stroke
				(width 0.508)
				(type default)
			)
			(layer "F.SilkS")
		)
		(fp_line
			(start -2.286 4.8768)
			(end -2.286 2.032)
			(stroke
				(width 0.1524)
				(type default)
			)
			(layer "F.SilkS")
		)
		(fp_line
			(start -2.286 -4.8768)
			(end -2.286 -2.032)
			(stroke
				(width 0.1524)
				(type default)
			)
			(layer "F.SilkS")
		)
		(fp_rect
			(start -2.1463 3.6449)
			(end 2.1463 -3.6449)
			(stroke
				(width 0)
				(type default)
			)
			(fill no)
			(layer "F.CrtYd")
		)
		(fp_poly
			(pts
				(xy -2.54 4.953) (xy -2.54 4.2926) (xy -3.81 4.2926) (xy -3.81 -4.2926) (xy -2.54 -4.2926) (xy -2.54 -4.953)
				(xy 2.54 -4.953) (xy 2.54 -4.2926) (xy 3.81 -4.2926) (xy 3.81 -1.6256) (xy 2.1463 -1.6256) (xy 2.1463 -3.6449)
				(xy -2.1463 -3.6449) (xy -2.1463 3.6449) (xy 2.1463 3.6449) (xy 2.1463 -1.6129) (xy 3.81 -1.6129)
				(xy 3.81 4.2926) (xy 2.54 4.2926) (xy 2.54 4.953)
			)
			(stroke
				(width 0)
				(type default)
			)
			(fill no)
			(layer "F.CrtYd")
		)
		(fp_rect
			(start 2.54 4.2926)
			(end 3.81 -4.2926)
			(stroke
				(width 0)
				(type default)
			)
			(fill no)
			(layer "F.Fab")
		)
		(fp_rect
			(start -2.54 4.953)
			(end 2.54 -4.953)
			(stroke
				(width 0)
				(type default)
			)
			(fill no)
			(layer "F.Fab")
		)
		(fp_rect
			(start -3.81 4.2926)
			(end -2.54 -4.2926)
			(stroke
				(width 0)
				(type default)
			)
			(fill no)
			(layer "F.Fab")
		)
		(pad "1" smd rect
			(at 0 -3.1496 180)
			(size 2.413 2.286)
			(layers "F.Cu" "F.Mask" "F.Paste")
			(net "P3V3_PWR")
		)
		(pad "2" smd rect
			(at 0 3.1496 180)
			(size 2.413 2.286)
			(layers "F.Cu" "F.Mask" "F.Paste")
			(net "GND")
		)
		(zone
			(layer "F.Cu")
			(hatch none 0.5)
			(connect_pads
				(clearance 0)
			)
			(min_thickness 0.25)
			(keepout
				(tracks allowed)
				(vias not_allowed)
				(pads allowed)
				(copperpour not_allowed)
				(footprints allowed)
			)
			(placement
				(enabled no)
				(sheetname "")
			)
			(fill
				(thermal_gap 0.5)
				(thermal_bridge_width 0.5)
				(island_removal_mode 0)
			)
			(polygon
				(pts
					(xy 61.7347 -81.4959) (xy 61.7347 -78.5876) (xy 64.7573 -78.5876) (xy 64.7573 -81.4832) (xy 64.7573 -81.8134)
					(xy 61.7347 -81.8134)
				)
			)
		)
		(zone
			(layer "F.Cu")
			(hatch none 0.5)
			(connect_pads
				(clearance 0)
			)
			(min_thickness 0.25)
			(keepout
				(tracks allowed)
				(vias not_allowed)
				(pads allowed)
				(copperpour not_allowed)
				(footprints allowed)
			)
			(placement
				(enabled no)
				(sheetname "")
			)
			(fill
				(thermal_gap 0.5)
				(thermal_bridge_width 0.5)
				(island_removal_mode 0)
			)
			(polygon
				(pts
					(xy 64.7573 -87.7824) (xy 61.7347 -87.7824) (xy 61.7347 -84.8868) (xy 61.7347 -84.5566) (xy 64.7573 -84.5566)
					(xy 64.7573 -84.8868)
				)
			)
		)
	)
	(footprint ""
		(layer "F.Cu")
		(at 59.817 -32.004 -90)
		(property "Reference" "C37"
			(at 0 0 270)
			(layer "F.SilkS")
			(hide yes)
			(effects
				(font
					(size 1.27 1.27)
				)
			)
		)
		(property "Value" "SC1U6D3V2KX-9-GP"
			(at 1.1811 -2.7051 270)
			(unlocked yes)
			(layer "F.Fab")
			(hide yes)
			(effects
				(font
					(size 1.016 1.016)
					(thickness 0.1524)
				)
			)
		)
		(property "Device Type" "C402H22"
			(at 1.1811 -4.2291 270)
			(unlocked yes)
			(layer "F.Fab")
			(hide yes)
			(effects
				(font
					(size 1.016 1.016)
					(thickness 0.1524)
				)
			)
		)
		(duplicate_pad_numbers_are_jumpers no)
		(fp_rect
			(start -0.4318 0.9525)
			(end 0.4318 -0.9525)
			(stroke
				(width 0)
				(type default)
			)
			(fill no)
			(layer "F.CrtYd")
		)
		(fp_rect
			(start -0.4318 0.9525)
			(end 0.4318 -0.9525)
			(stroke
				(width 0)
				(type default)
			)
			(fill no)
			(layer "F.Fab")
		)
		(pad "1" smd custom
			(at 0 -0.4445 270)
			(size 0.1524 0.1524)
			(layers "F.Cu" "F.Mask" "F.Paste")
			(net "P3V3_PWR")
			(options
				(clearance outline)
				(anchor circle)
			)
			(primitives
				(gr_poly
					(pts
						(arc
							(start 0.3048 -0.2032)
							(mid 0.275042 -0.275042)
							(end 0.2032 -0.3048)
						)
						(arc
							(start -0.2032 -0.3048)
							(mid -0.275042 -0.275042)
							(end -0.3048 -0.2032)
						)
						(arc
							(start -0.3048 0.2032)
							(mid -0.275042 0.275042)
							(end -0.2032 0.3048)
						)
						(arc
							(start 0.2032 0.3048)
							(mid 0.275042 0.275042)
							(end 0.3048 0.2032)
						)
					)
					(width 0)
					(fill yes)
				)
			)
		)
		(pad "2" smd custom
			(at 0 0.4445 270)
			(size 0.1524 0.1524)
			(layers "F.Cu" "F.Mask" "F.Paste")
			(net "GND")
			(options
				(clearance outline)
				(anchor circle)
			)
			(primitives
				(gr_poly
					(pts
						(arc
							(start 0.3048 -0.2032)
							(mid 0.275042 -0.275042)
							(end 0.2032 -0.3048)
						)
						(arc
							(start -0.2032 -0.3048)
							(mid -0.275042 -0.275042)
							(end -0.3048 -0.2032)
						)
						(arc
							(start -0.3048 0.2032)
							(mid -0.275042 0.275042)
							(end -0.2032 0.3048)
						)
						(arc
							(start 0.2032 0.3048)
							(mid 0.275042 0.275042)
							(end 0.3048 0.2032)
						)
					)
					(width 0)
					(fill yes)
				)
			)
		)
	)
	(footprint ""
		(layer "F.Cu")
		(at 35.306 -80.264 180)
		(property "Reference" "PL2"
			(at 0 0 180)
			(layer "F.SilkS")
			(hide yes)
			(effects
				(font
					(size 1.27 1.27)
				)
			)
		)
		(property "Value" "BLM21PG220SN1DGP"
			(at 0.0254 -5.6896 180)
			(unlocked yes)
			(layer "F.Fab")
			(hide yes)
			(effects
				(font
					(size 1.016 1.016)
					(thickness 0.1524)
				)
			)
		)
		(property "Device Type" "L20125H42"
			(at 0.0254 -7.5946 180)
			(unlocked yes)
			(layer "F.Fab")
			(hide yes)
			(effects
				(font
					(size 1.016 1.016)
					(thickness 0.1524)
				)
			)
		)
		(duplicate_pad_numbers_are_jumpers no)
		(fp_line
			(start 0.9144 1.7018)
			(end 0.9144 -1.7018)
			(stroke
				(width 0.1524)
				(type default)
			)
			(layer "F.SilkS")
		)
		(fp_line
			(start 0.9144 -1.7018)
			(end -0.9144 -1.7018)
			(stroke
				(width 0.1524)
				(type default)
			)
			(layer "F.SilkS")
		)
		(fp_line
			(start -0.9144 1.7018)
			(end 0.9144 1.7018)
			(stroke
				(width 0.1524)
				(type default)
			)
			(layer "F.SilkS")
		)
		(fp_line
			(start -0.9144 -1.7018)
			(end -0.9144 1.7018)
			(stroke
				(width 0.1524)
				(type default)
			)
			(layer "F.SilkS")
		)
		(fp_rect
			(start -1.0033 1.778)
			(end 1.0033 -1.778)
			(stroke
				(width 0)
				(type default)
			)
			(fill no)
			(layer "F.CrtYd")
		)
		(fp_poly
			(pts
				(xy -1.0033 -1.778) (xy 1.0033 -1.778) (xy 1.0033 1.778) (xy -1.0033 1.778)
			)
			(stroke
				(width 0)
				(type default)
			)
			(fill no)
			(layer "F.Fab")
		)
		(pad "1" smd rect
			(at 0 -0.9652 180)
			(size 1.397 1.143)
			(layers "F.Cu" "F.Mask" "F.Paste")
			(net "P12V")
		)
		(pad "2" smd rect
			(at 0 0.9652 180)
			(size 1.397 1.143)
			(layers "F.Cu" "F.Mask" "F.Paste")
			(net "P3V3_DEV_VIN")
		)
	)
	(footprint ""
		(layer "F.Cu")
		(at 60.579 -40.259 90)
		(property "Reference" "U1"
			(at 0 0 90)
			(layer "F.SilkS")
			(hide yes)
			(effects
				(font
					(size 1.27 1.27)
				)
			)
		)
		(property "Value" "TMP75AIDGKR-GP"
			(at -0.1143 -9.1948 90)
			(unlocked yes)
			(layer "F.Fab")
			(hide yes)
			(effects
				(font
					(size 1.016 1.016)
					(thickness 0.1524)
				)
			)
		)
		(property "Device Type" "MSOP8-1H44"
			(at -0.1143 -10.795 90)
			(unlocked yes)
			(layer "F.Fab")
			(hide yes)
			(effects
				(font
					(size 1.016 1.016)
					(thickness 0.1524)
				)
			)
		)
		(duplicate_pad_numbers_are_jumpers no)
		(fp_line
			(start 1.0795 -1.016)
			(end -1.9558 -1.016)
			(stroke
				(width 0.1524)
				(type default)
			)
			(layer "F.SilkS")
		)
		(fp_line
			(start -1.9558 -1.016)
			(end -1.9558 1.016)
			(stroke
				(width 0.1524)
				(type default)
			)
			(layer "F.SilkS")
		)
		(fp_line
			(start -1.9558 -0.5461)
			(end -1.4478 -0.0381)
			(stroke
				(width 0.1524)
				(type default)
			)
			(layer "F.SilkS")
		)
		(fp_line
			(start -1.4478 -0.0381)
			(end -1.9558 0.4699)
			(stroke
				(width 0.1524)
				(type default)
			)
			(layer "F.SilkS")
		)
		(fp_line
			(start 1.0795 1.016)
			(end 1.0795 -1.016)
			(stroke
				(width 0.1524)
				(type default)
			)
			(layer "F.SilkS")
		)
		(fp_line
			(start -1.9558 1.016)
			(end 1.0795 1.016)
			(stroke
				(width 0.1524)
				(type default)
			)
			(layer "F.SilkS")
		)
		(fp_line
			(start -1.778 1.0922)
			(end -1.778 3.048)
			(stroke
				(width 0.508)
				(type default)
			)
			(layer "F.SilkS")
		)
		(fp_poly
			(pts
				(xy -1.1557 -1.016) (xy -1.1557 1.016) (xy 1.1557 1.016) (xy 1.1557 -1.016)
			)
			(stroke
				(width 0)
				(type default)
			)
			(fill yes)
			(layer "F.SilkS")
		)
		(fp_rect
			(start -1.4986 2.4511)
			(end 1.4986 -2.4511)
			(stroke
				(width 0)
				(type default)
			)
			(fill no)
			(layer "F.CrtYd")
		)
		(fp_poly
			(pts
				(xy -2.032 3.302) (xy -2.032 -3.302) (xy 2.032 -3.302) (xy 2.032 -2.1209) (xy 1.4986 -2.1209) (xy 1.4986 -2.4511)
				(xy -1.4986 -2.4511) (xy -1.4986 2.4511) (xy 1.4986 2.4511) (xy 1.4986 -2.1082) (xy 2.032 -2.1082)
				(xy 2.032 3.302)
			)
			(stroke
				(width 0)
				(type default)
			)
			(fill no)
			(layer "F.CrtYd")
		)
		(fp_rect
			(start -2.032 3.302)
			(end 2.032 -3.302)
			(stroke
				(width 0)
				(type default)
			)
			(fill no)
			(layer "F.Fab")
		)
		(pad "1" smd rect
			(at -0.97536 2.05486 90)
			(size 0.3556 1.524)
			(layers "F.Cu" "F.Mask" "F.Paste")
			(net "Z50_TEMP_1_DATA")
		)
		(pad "2" smd rect
			(at -0.32512 2.05486 90)
			(size 0.3556 1.524)
			(layers "F.Cu" "F.Mask" "F.Paste")
			(net "Z50_TEMP_1_CLK")
		)
		(pad "3" smd rect
			(at 0.32512 2.05486 90)
			(size 0.3556 1.524)
			(layers "F.Cu" "F.Mask" "F.Paste")
			(net "Z50_TEMP_1_ALERT#")
		)
		(pad "4" smd rect
			(at 0.97536 2.05486 90)
			(size 0.3556 1.524)
			(layers "F.Cu" "F.Mask" "F.Paste")
			(net "GND")
		)
		(pad "5" smd rect
			(at 0.97536 -2.05486 90)
			(size 0.3556 1.524)
			(layers "F.Cu" "F.Mask" "F.Paste")
			(net "Z50_TEMP_1_A2")
		)
		(pad "6" smd rect
			(at 0.32512 -2.05486 90)
			(size 0.3556 1.524)
			(layers "F.Cu" "F.Mask" "F.Paste")
			(net "Z50_TEMP_1_A1")
		)
		(pad "7" smd rect
			(at -0.32512 -2.05486 90)
			(size 0.3556 1.524)
			(layers "F.Cu" "F.Mask" "F.Paste")
			(net "Z50_TEMP_1_A0")
		)
		(pad "8" smd rect
			(at -0.97536 -2.05486 90)
			(size 0.3556 1.524)
			(layers "F.Cu" "F.Mask" "F.Paste")
			(net "P3V3_DPB")
		)
	)
	(footprint ""
		(layer "F.Cu")
		(at 35.306 -84.582 180)
		(property "Reference" "PC35"
			(at 0 0 180)
			(layer "F.SilkS")
			(hide yes)
			(effects
				(font
					(size 1.27 1.27)
				)
			)
		)
		(property "Value" "SC10U16V5KX-1-GP"
			(at -0.0762 -6.1214 180)
			(unlocked yes)
			(layer "F.Fab")
			(hide yes)
			(effects
				(font
					(size 1.016 1.016)
					(thickness 0.1524)
				)
			)
		)
		(property "Device Type" "C805H54"
			(at -0.0762 -8.1534 180)
			(unlocked yes)
			(layer "F.Fab")
			(hide yes)
			(effects
				(font
					(size 1.016 1.016)
					(thickness 0.1524)
				)
			)
		)
		(duplicate_pad_numbers_are_jumpers no)
		(fp_line
			(start 0.635 0)
			(end -0.635 0)
			(stroke
				(width 0.508)
				(type default)
			)
			(layer "F.SilkS")
		)
		(fp_rect
			(start -0.9652 1.778)
			(end 0.9652 -1.778)
			(stroke
				(width 0)
				(type default)
			)
			(fill no)
			(layer "F.CrtYd")
		)
		(fp_poly
			(pts
				(xy -0.9652 -1.778) (xy 0.9652 -1.778) (xy 0.9652 1.778) (xy -0.9652 1.778)
			)
			(stroke
				(width 0)
				(type default)
			)
			(fill no)
			(layer "F.Fab")
		)
		(pad "1" smd rect
			(at 0 -0.9652 180)
			(size 1.397 1.143)
			(layers "F.Cu" "F.Mask" "F.Paste")
			(net "P3V3_DEV_VIN")
		)
		(pad "2" smd rect
			(at 0 0.9652 180)
			(size 1.397 1.143)
			(layers "F.Cu" "F.Mask" "F.Paste")
			(net "GND")
		)
	)
	(footprint ""
		(layer "F.Cu")
		(at 29.21 -84.122006)
		(property "Reference" "U4"
			(at 0 0 0)
			(layer "F.SilkS")
			(hide yes)
			(effects
				(font
					(size 1.27 1.27)
				)
			)
		)
		(property "Value" "PCA9543APW-GP"
			(at 0.1016 -7.62 0)
			(unlocked yes)
			(layer "F.Fab")
			(hide yes)
			(effects
				(font
					(size 1.016 1.016)
					(thickness 0.1524)
				)
			)
		)
		(property "Device Type" "TSOIC14H44"
			(at 0.1016 -10.16 0)
			(unlocked yes)
			(layer "F.Fab")
			(hide yes)
			(effects
				(font
					(size 1.016 1.016)
					(thickness 0.1524)
				)
			)
		)
		(duplicate_pad_numbers_are_jumpers no)
		(fp_line
			(start -3.048 -1.778)
			(end -3.048 4.191)
			(stroke
				(width 0.2032)
				(type default)
			)
			(layer "F.SilkS")
		)
		(fp_line
			(start -3.048 -1.778)
			(end 2.159 -1.778)
			(stroke
				(width 0.2032)
				(type default)
			)
			(layer "F.SilkS")
		)
		(fp_line
			(start -3.048 4.191)
			(end -3.048 1.397)
			(stroke
				(width 0.508)
				(type default)
			)
			(layer "F.SilkS")
		)
		(fp_line
			(start -2.032 0)
			(end -3.048 -1.016)
			(stroke
				(width 0.2032)
				(type default)
			)
			(layer "F.SilkS")
		)
		(fp_line
			(start -2.032 0)
			(end -3.048 1.016)
			(stroke
				(width 0.2032)
				(type default)
			)
			(layer "F.SilkS")
		)
		(fp_line
			(start 2.159 -1.778)
			(end 2.159 1.778)
			(stroke
				(width 0.2032)
				(type default)
			)
			(layer "F.SilkS")
		)
		(fp_line
			(start 2.159 1.7526)
			(end -3.0734 1.7526)
			(stroke
				(width 0.2032)
				(type default)
			)
			(layer "F.SilkS")
		)
		(fp_line
			(start 2.159 1.778)
			(end 2.159 1.7526)
			(stroke
				(width 0.2032)
				(type default)
			)
			(layer "F.SilkS")
		)
		(fp_poly
			(pts
				(xy -2.2606 -1.8542) (xy 2.2606 -1.8542) (xy 2.2606 1.8542) (xy -2.2606 1.8542)
			)
			(stroke
				(width 0)
				(type default)
			)
			(fill yes)
			(layer "F.SilkS")
		)
		(fp_poly
			(pts
				(xy -3.048 -4.0894) (xy 3.048 -4.0894) (xy 3.048 4.0894) (xy -3.048 4.0894)
			)
			(stroke
				(width 0)
				(type default)
			)
			(fill no)
			(layer "F.CrtYd")
		)
		(fp_poly
			(pts
				(xy -3.048 -4.0894) (xy 3.048 -4.0894) (xy 3.048 4.0894) (xy -3.048 4.0894)
			)
			(stroke
				(width 0)
				(type default)
			)
			(fill no)
			(layer "F.Fab")
		)
		(pad "1" smd rect
			(at -1.94945 2.8194)
			(size 0.3556 1.524)
			(layers "F.Cu" "F.Mask" "F.Paste")
			(net "Z50_SMB_SWITCH_ADDRESS_A0")
		)
		(pad "2" smd rect
			(at -1.30048 2.8194)
			(size 0.3556 1.524)
			(layers "F.Cu" "F.Mask" "F.Paste")
			(net "Z50_SMB_SWITCH_ADDRESS_A1")
		)
		(pad "3" smd rect
			(at -0.65024 2.8194)
			(size 0.3556 1.524)
			(layers "F.Cu" "F.Mask" "F.Paste")
			(net "Z50_SMB_SWITCH_RESET#")
		)
		(pad "4" smd rect
			(at 0 2.8194)
			(size 0.3556 1.524)
			(layers "F.Cu" "F.Mask" "F.Paste")
			(net "Net_14")
		)
		(pad "5" smd rect
			(at 0.65024 2.8194)
			(size 0.3556 1.524)
			(layers "F.Cu" "F.Mask" "F.Paste")
			(net "Z50_SSD_A1_SMB_DATA_R")
		)
		(pad "6" smd rect
			(at 1.30048 2.8194)
			(size 0.3556 1.524)
			(layers "F.Cu" "F.Mask" "F.Paste")
			(net "Z50_SSD_A1_SMB_CLK_R")
		)
		(pad "7" smd rect
			(at 1.94945 2.8194)
			(size 0.3556 1.524)
			(layers "F.Cu" "F.Mask" "F.Paste")
			(net "GND")
		)
		(pad "8" smd rect
			(at 1.94945 -2.8194)
			(size 0.3556 1.524)
			(layers "F.Cu" "F.Mask" "F.Paste")
			(net "Net_13")
		)
		(pad "9" smd rect
			(at 1.30048 -2.8194)
			(size 0.3556 1.524)
			(layers "F.Cu" "F.Mask" "F.Paste")
			(net "Z50_SSD_B1_SMB_DATA_R")
		)
		(pad "10" smd rect
			(at 0.65024 -2.8194)
			(size 0.3556 1.524)
			(layers "F.Cu" "F.Mask" "F.Paste")
			(net "Z50_SSD_B1_SMB_CLK_R")
		)
		(pad "11" smd rect
			(at 0 -2.8194)
			(size 0.3556 1.524)
			(layers "F.Cu" "F.Mask" "F.Paste")
			(net "Net_12")
		)
		(pad "12" smd rect
			(at -0.65024 -2.8194)
			(size 0.3556 1.524)
			(layers "F.Cu" "F.Mask" "F.Paste")
			(net "Z50_SMB_CLK")
		)
		(pad "13" smd rect
			(at -1.30048 -2.8194)
			(size 0.3556 1.524)
			(layers "F.Cu" "F.Mask" "F.Paste")
			(net "Z50_SMB_DATA")
		)
		(pad "14" smd rect
			(at -1.94945 -2.8194)
			(size 0.3556 1.524)
			(layers "F.Cu" "F.Mask" "F.Paste")
			(net "P3V3_DPB")
		)
	)
	(footprint ""
		(layer "F.Cu")
		(at 24.13 -71.755)
		(property "Reference" "R56"
			(at 0 0 0)
			(layer "F.SilkS")
			(hide yes)
			(effects
				(font
					(size 1.27 1.27)
				)
			)
		)
		(property "Value" "33R2J-2-GP"
			(at 0.064008 -3.993896 0)
			(unlocked yes)
			(layer "F.Fab")
			(hide yes)
			(effects
				(font
					(size 1.016 1.016)
					(thickness 0.1524)
				)
			)
		)
		(property "Device Type" "R402H16"
			(at 0.064008 -5.517896 0)
			(unlocked yes)
			(layer "F.Fab")
			(hide yes)
			(effects
				(font
					(size 1.016 1.016)
					(thickness 0.1524)
				)
			)
		)
		(duplicate_pad_numbers_are_jumpers no)
		(fp_line
			(start -0.508 -0.9398)
			(end -0.508 0.9398)
			(stroke
				(width 0.1524)
				(type default)
			)
			(layer "F.SilkS")
		)
		(fp_line
			(start 0.508 -0.9398)
			(end -0.508 -0.9398)
			(stroke
				(width 0.1524)
				(type default)
			)
			(layer "F.SilkS")
		)
		(fp_rect
			(start -0.508 0.9398)
			(end 0.508 -0.9398)
			(stroke
				(width 0)
				(type default)
			)
			(fill no)
			(layer "F.CrtYd")
		)
		(fp_rect
			(start -0.508 0.9398)
			(end 0.508 -0.9398)
			(stroke
				(width 0)
				(type default)
			)
			(fill no)
			(layer "F.Fab")
		)
		(pad "1" smd custom
			(at 0 -0.4445)
			(size 0.1397 0.1397)
			(layers "F.Cu" "F.Mask" "F.Paste")
			(net "Z50_SSD_A1_SMB_CLK_LR")
			(options
				(clearance outline)
				(anchor circle)
			)
			(primitives
				(gr_poly
					(pts
						(arc
							(start -0.1778 -0.2794)
							(mid -0.249642 -0.249642)
							(end -0.2794 -0.1778)
						)
						(arc
							(start -0.2794 0.1778)
							(mid -0.249642 0.249642)
							(end -0.1778 0.2794)
						)
						(arc
							(start 0.1778 0.2794)
							(mid 0.249642 0.249642)
							(end 0.2794 0.1778)
						)
						(arc
							(start 0.2794 -0.1778)
							(mid 0.249642 -0.249642)
							(end 0.1778 -0.2794)
						)
					)
					(width 0)
					(fill yes)
				)
			)
		)
		(pad "2" smd custom
			(at 0 0.4445)
			(size 0.1397 0.1397)
			(layers "F.Cu" "F.Mask" "F.Paste")
			(net "Z50_SSD_A1_SMB_CLK")
			(options
				(clearance outline)
				(anchor circle)
			)
			(primitives
				(gr_poly
					(pts
						(arc
							(start -0.1778 -0.2794)
							(mid -0.249642 -0.249642)
							(end -0.2794 -0.1778)
						)
						(arc
							(start -0.2794 0.1778)
							(mid -0.249642 0.249642)
							(end -0.1778 0.2794)
						)
						(arc
							(start 0.1778 0.2794)
							(mid 0.249642 0.249642)
							(end 0.2794 0.1778)
						)
						(arc
							(start 0.2794 -0.1778)
							(mid 0.249642 -0.249642)
							(end 0.1778 -0.2794)
						)
					)
					(width 0)
					(fill yes)
				)
			)
		)
	)
	(footprint ""
		(layer "F.Cu")
		(at 59.817 -45.593 -90)
		(property "Reference" "C3"
			(at 0 0 270)
			(layer "F.SilkS")
			(hide yes)
			(effects
				(font
					(size 1.27 1.27)
				)
			)
		)
		(property "Value" "SCD1U16V2KX-3GP"
			(at 1.1811 -2.7051 270)
			(unlocked yes)
			(layer "F.Fab")
			(hide yes)
			(effects
				(font
					(size 1.016 1.016)
					(thickness 0.1524)
				)
			)
		)
		(property "Device Type" "C402H22"
			(at 1.1811 -4.2291 270)
			(unlocked yes)
			(layer "F.Fab")
			(hide yes)
			(effects
				(font
					(size 1.016 1.016)
					(thickness 0.1524)
				)
			)
		)
		(duplicate_pad_numbers_are_jumpers no)
		(fp_rect
			(start -0.4318 0.9525)
			(end 0.4318 -0.9525)
			(stroke
				(width 0)
				(type default)
			)
			(fill no)
			(layer "F.CrtYd")
		)
		(fp_rect
			(start -0.4318 0.9525)
			(end 0.4318 -0.9525)
			(stroke
				(width 0)
				(type default)
			)
			(fill no)
			(layer "F.Fab")
		)
		(pad "1" smd custom
			(at 0 -0.4445 270)
			(size 0.1524 0.1524)
			(layers "F.Cu" "F.Mask" "F.Paste")
			(net "P3V3_PWR")
			(options
				(clearance outline)
				(anchor circle)
			)
			(primitives
				(gr_poly
					(pts
						(arc
							(start 0.3048 -0.2032)
							(mid 0.275042 -0.275042)
							(end 0.2032 -0.3048)
						)
						(arc
							(start -0.2032 -0.3048)
							(mid -0.275042 -0.275042)
							(end -0.3048 -0.2032)
						)
						(arc
							(start -0.3048 0.2032)
							(mid -0.275042 0.275042)
							(end -0.2032 0.3048)
						)
						(arc
							(start 0.2032 0.3048)
							(mid 0.275042 0.275042)
							(end 0.3048 0.2032)
						)
					)
					(width 0)
					(fill yes)
				)
			)
		)
		(pad "2" smd custom
			(at 0 0.4445 270)
			(size 0.1524 0.1524)
			(layers "F.Cu" "F.Mask" "F.Paste")
			(net "GND")
			(options
				(clearance outline)
				(anchor circle)
			)
			(primitives
				(gr_poly
					(pts
						(arc
							(start 0.3048 -0.2032)
							(mid 0.275042 -0.275042)
							(end 0.2032 -0.3048)
						)
						(arc
							(start -0.2032 -0.3048)
							(mid -0.275042 -0.275042)
							(end -0.3048 -0.2032)
						)
						(arc
							(start -0.3048 0.2032)
							(mid -0.275042 0.275042)
							(end -0.2032 0.3048)
						)
						(arc
							(start 0.2032 0.3048)
							(mid 0.275042 0.275042)
							(end 0.3048 0.2032)
						)
					)
					(width 0)
					(fill yes)
				)
			)
		)
	)
	(footprint ""
		(layer "F.Cu")
		(at 39.37 -80.264)
		(property "Reference" "PC38"
			(at 0 0 0)
			(layer "F.SilkS")
			(hide yes)
			(effects
				(font
					(size 1.27 1.27)
				)
			)
		)
		(property "Value" "SC10U16V5KX-1-GP"
			(at -0.0762 -6.1214 0)
			(unlocked yes)
			(layer "F.Fab")
			(hide yes)
			(effects
				(font
					(size 1.016 1.016)
					(thickness 0.1524)
				)
			)
		)
		(property "Device Type" "C805H54"
			(at -0.0762 -8.1534 0)
			(unlocked yes)
			(layer "F.Fab")
			(hide yes)
			(effects
				(font
					(size 1.016 1.016)
					(thickness 0.1524)
				)
			)
		)
		(duplicate_pad_numbers_are_jumpers no)
		(fp_line
			(start 0.635 0)
			(end -0.635 0)
			(stroke
				(width 0.508)
				(type default)
			)
			(layer "F.SilkS")
		)
		(fp_rect
			(start -0.9652 1.778)
			(end 0.9652 -1.778)
			(stroke
				(width 0)
				(type default)
			)
			(fill no)
			(layer "F.CrtYd")
		)
		(fp_poly
			(pts
				(xy -0.9652 -1.778) (xy 0.9652 -1.778) (xy 0.9652 1.778) (xy -0.9652 1.778)
			)
			(stroke
				(width 0)
				(type default)
			)
			(fill no)
			(layer "F.Fab")
		)
		(pad "1" smd rect
			(at 0 -0.9652)
			(size 1.397 1.143)
			(layers "F.Cu" "F.Mask" "F.Paste")
			(net "P3V3_DEV_VIN")
		)
		(pad "2" smd rect
			(at 0 0.9652)
			(size 1.397 1.143)
			(layers "F.Cu" "F.Mask" "F.Paste")
			(net "GND")
		)
	)
	(footprint ""
		(layer "F.Cu")
		(at 63.246 -37.084 180)
		(property "Reference" "C31"
			(at 0 0 180)
			(layer "F.SilkS")
			(hide yes)
			(effects
				(font
					(size 1.27 1.27)
				)
			)
		)
		(property "Value" "SC1U6D3V2KX-9-GP"
			(at 1.1811 -2.7051 180)
			(unlocked yes)
			(layer "F.Fab")
			(hide yes)
			(effects
				(font
					(size 1.016 1.016)
					(thickness 0.1524)
				)
			)
		)
		(property "Device Type" "C402H22"
			(at 1.1811 -4.2291 180)
			(unlocked yes)
			(layer "F.Fab")
			(hide yes)
			(effects
				(font
					(size 1.016 1.016)
					(thickness 0.1524)
				)
			)
		)
		(duplicate_pad_numbers_are_jumpers no)
		(fp_rect
			(start -0.4318 0.9525)
			(end 0.4318 -0.9525)
			(stroke
				(width 0)
				(type default)
			)
			(fill no)
			(layer "F.CrtYd")
		)
		(fp_rect
			(start -0.4318 0.9525)
			(end 0.4318 -0.9525)
			(stroke
				(width 0)
				(type default)
			)
			(fill no)
			(layer "F.Fab")
		)
		(pad "1" smd custom
			(at 0 -0.4445 180)
			(size 0.1524 0.1524)
			(layers "F.Cu" "F.Mask" "F.Paste")
			(net "P3V3_PWR")
			(options
				(clearance outline)
				(anchor circle)
			)
			(primitives
				(gr_poly
					(pts
						(arc
							(start 0.3048 -0.2032)
							(mid 0.275042 -0.275042)
							(end 0.2032 -0.3048)
						)
						(arc
							(start -0.2032 -0.3048)
							(mid -0.275042 -0.275042)
							(end -0.3048 -0.2032)
						)
						(arc
							(start -0.3048 0.2032)
							(mid -0.275042 0.275042)
							(end -0.2032 0.3048)
						)
						(arc
							(start 0.2032 0.3048)
							(mid 0.275042 0.275042)
							(end 0.3048 0.2032)
						)
					)
					(width 0)
					(fill yes)
				)
			)
		)
		(pad "2" smd custom
			(at 0 0.4445 180)
			(size 0.1524 0.1524)
			(layers "F.Cu" "F.Mask" "F.Paste")
			(net "GND")
			(options
				(clearance outline)
				(anchor circle)
			)
			(primitives
				(gr_poly
					(pts
						(arc
							(start 0.3048 -0.2032)
							(mid 0.275042 -0.275042)
							(end 0.2032 -0.3048)
						)
						(arc
							(start -0.2032 -0.3048)
							(mid -0.275042 -0.275042)
							(end -0.3048 -0.2032)
						)
						(arc
							(start -0.3048 0.2032)
							(mid -0.275042 0.275042)
							(end -0.2032 0.3048)
						)
						(arc
							(start 0.2032 0.3048)
							(mid 0.275042 0.275042)
							(end 0.3048 0.2032)
						)
					)
					(width 0)
					(fill yes)
				)
			)
		)
	)
	(footprint ""
		(layer "F.Cu")
		(at 65.786 -77.216 90)
		(property "Reference" "PC39"
			(at 0 0 90)
			(layer "F.SilkS")
			(hide yes)
			(effects
				(font
					(size 1.27 1.27)
				)
			)
		)
		(property "Value" "SC10U6D3V5KX-4GP"
			(at -0.0762 -6.1214 90)
			(unlocked yes)
			(layer "F.Fab")
			(hide yes)
			(effects
				(font
					(size 1.016 1.016)
					(thickness 0.1524)
				)
			)
		)
		(property "Device Type" "C805H58"
			(at -0.0762 -8.1534 90)
			(unlocked yes)
			(layer "F.Fab")
			(hide yes)
			(effects
				(font
					(size 1.016 1.016)
					(thickness 0.1524)
				)
			)
		)
		(duplicate_pad_numbers_are_jumpers no)
		(fp_line
			(start 0.635 0)
			(end -0.635 0)
			(stroke
				(width 0.508)
				(type default)
			)
			(layer "F.SilkS")
		)
		(fp_rect
			(start -0.9652 1.778)
			(end 0.9652 -1.778)
			(stroke
				(width 0)
				(type default)
			)
			(fill no)
			(layer "F.CrtYd")
		)
		(fp_poly
			(pts
				(xy -0.9652 -1.778) (xy 0.9652 -1.778) (xy 0.9652 1.778) (xy -0.9652 1.778)
			)
			(stroke
				(width 0)
				(type default)
			)
			(fill no)
			(layer "F.Fab")
		)
		(pad "1" smd rect
			(at 0 -0.9652 90)
			(size 1.397 1.143)
			(layers "F.Cu" "F.Mask" "F.Paste")
			(net "P3V3_PWR")
		)
		(pad "2" smd rect
			(at 0 0.9652 90)
			(size 1.397 1.143)
			(layers "F.Cu" "F.Mask" "F.Paste")
			(net "GND")
		)
	)
	(footprint ""
		(layer "F.Cu")
		(at 59.817 -60.579 -90)
		(property "Reference" "C15"
			(at 0 0 270)
			(layer "F.SilkS")
			(hide yes)
			(effects
				(font
					(size 1.27 1.27)
				)
			)
		)
		(property "Value" "SCD1U16V2KX-3GP"
			(at 1.1811 -2.7051 270)
			(unlocked yes)
			(layer "F.Fab")
			(hide yes)
			(effects
				(font
					(size 1.016 1.016)
					(thickness 0.1524)
				)
			)
		)
		(property "Device Type" "C402H22"
			(at 1.1811 -4.2291 270)
			(unlocked yes)
			(layer "F.Fab")
			(hide yes)
			(effects
				(font
					(size 1.016 1.016)
					(thickness 0.1524)
				)
			)
		)
		(duplicate_pad_numbers_are_jumpers no)
		(fp_rect
			(start -0.4318 0.9525)
			(end 0.4318 -0.9525)
			(stroke
				(width 0)
				(type default)
			)
			(fill no)
			(layer "F.CrtYd")
		)
		(fp_rect
			(start -0.4318 0.9525)
			(end 0.4318 -0.9525)
			(stroke
				(width 0)
				(type default)
			)
			(fill no)
			(layer "F.Fab")
		)
		(pad "1" smd custom
			(at 0 -0.4445 270)
			(size 0.1524 0.1524)
			(layers "F.Cu" "F.Mask" "F.Paste")
			(net "P3V3_PWR")
			(options
				(clearance outline)
				(anchor circle)
			)
			(primitives
				(gr_poly
					(pts
						(arc
							(start 0.3048 -0.2032)
							(mid 0.275042 -0.275042)
							(end 0.2032 -0.3048)
						)
						(arc
							(start -0.2032 -0.3048)
							(mid -0.275042 -0.275042)
							(end -0.3048 -0.2032)
						)
						(arc
							(start -0.3048 0.2032)
							(mid -0.275042 0.275042)
							(end -0.2032 0.3048)
						)
						(arc
							(start 0.2032 0.3048)
							(mid 0.275042 0.275042)
							(end 0.3048 0.2032)
						)
					)
					(width 0)
					(fill yes)
				)
			)
		)
		(pad "2" smd custom
			(at 0 0.4445 270)
			(size 0.1524 0.1524)
			(layers "F.Cu" "F.Mask" "F.Paste")
			(net "GND")
			(options
				(clearance outline)
				(anchor circle)
			)
			(primitives
				(gr_poly
					(pts
						(arc
							(start 0.3048 -0.2032)
							(mid 0.275042 -0.275042)
							(end 0.2032 -0.3048)
						)
						(arc
							(start -0.2032 -0.3048)
							(mid -0.275042 -0.275042)
							(end -0.3048 -0.2032)
						)
						(arc
							(start -0.3048 0.2032)
							(mid -0.275042 0.275042)
							(end -0.2032 0.3048)
						)
						(arc
							(start 0.2032 0.3048)
							(mid 0.275042 0.275042)
							(end 0.3048 0.2032)
						)
					)
					(width 0)
					(fill yes)
				)
			)
		)
	)
	(footprint ""
		(layer "F.Cu")
		(at 49.227994 -76.073 -90)
		(property "Reference" "PR37"
			(at 0 0 270)
			(layer "F.SilkS")
			(hide yes)
			(effects
				(font
					(size 1.27 1.27)
				)
			)
		)
		(property "Value" "10KR2F-2-GP"
			(at 0.064008 -3.993896 270)
			(unlocked yes)
			(layer "F.Fab")
			(hide yes)
			(effects
				(font
					(size 1.016 1.016)
					(thickness 0.1524)
				)
			)
		)
		(property "Device Type" "R402H16"
			(at 0.064008 -5.517896 270)
			(unlocked yes)
			(layer "F.Fab")
			(hide yes)
			(effects
				(font
					(size 1.016 1.016)
					(thickness 0.1524)
				)
			)
		)
		(duplicate_pad_numbers_are_jumpers no)
		(fp_line
			(start -0.508 -0.9398)
			(end -0.508 0.9398)
			(stroke
				(width 0.1524)
				(type default)
			)
			(layer "F.SilkS")
		)
		(fp_line
			(start 0.508 -0.9398)
			(end -0.508 -0.9398)
			(stroke
				(width 0.1524)
				(type default)
			)
			(layer "F.SilkS")
		)
		(fp_rect
			(start -0.508 0.9398)
			(end 0.508 -0.9398)
			(stroke
				(width 0)
				(type default)
			)
			(fill no)
			(layer "F.CrtYd")
		)
		(fp_rect
			(start -0.508 0.9398)
			(end 0.508 -0.9398)
			(stroke
				(width 0)
				(type default)
			)
			(fill no)
			(layer "F.Fab")
		)
		(pad "1" smd custom
			(at 0 -0.4445 270)
			(size 0.1397 0.1397)
			(layers "F.Cu" "F.Mask" "F.Paste")
			(net "P3V3_DEV_VFB")
			(options
				(clearance outline)
				(anchor circle)
			)
			(primitives
				(gr_poly
					(pts
						(arc
							(start -0.1778 -0.2794)
							(mid -0.249642 -0.249642)
							(end -0.2794 -0.1778)
						)
						(arc
							(start -0.2794 0.1778)
							(mid -0.249642 0.249642)
							(end -0.1778 0.2794)
						)
						(arc
							(start 0.1778 0.2794)
							(mid 0.249642 0.249642)
							(end 0.2794 0.1778)
						)
						(arc
							(start 0.2794 -0.1778)
							(mid 0.249642 -0.249642)
							(end 0.1778 -0.2794)
						)
					)
					(width 0)
					(fill yes)
				)
			)
		)
		(pad "2" smd custom
			(at 0 0.4445 270)
			(size 0.1397 0.1397)
			(layers "F.Cu" "F.Mask" "F.Paste")
			(net "AGND_P3V3_DEV")
			(options
				(clearance outline)
				(anchor circle)
			)
			(primitives
				(gr_poly
					(pts
						(arc
							(start -0.1778 -0.2794)
							(mid -0.249642 -0.249642)
							(end -0.2794 -0.1778)
						)
						(arc
							(start -0.2794 0.1778)
							(mid -0.249642 0.249642)
							(end -0.1778 0.2794)
						)
						(arc
							(start 0.1778 0.2794)
							(mid 0.249642 0.249642)
							(end 0.2794 0.1778)
						)
						(arc
							(start 0.2794 -0.1778)
							(mid 0.249642 -0.249642)
							(end 0.1778 -0.2794)
						)
					)
					(width 0)
					(fill yes)
				)
			)
		)
	)
	(footprint ""
		(layer "F.Cu")
		(at 75.311 -62.23 -90)
		(property "Reference" "R46"
			(at 0 0 270)
			(layer "F.SilkS")
			(hide yes)
			(effects
				(font
					(size 1.27 1.27)
				)
			)
		)
		(property "Value" "47KR2F-GP"
			(at 0.064008 -3.993896 270)
			(unlocked yes)
			(layer "F.Fab")
			(hide yes)
			(effects
				(font
					(size 1.016 1.016)
					(thickness 0.1524)
				)
			)
		)
		(property "Device Type" "R402H16"
			(at 0.064008 -5.517896 270)
			(unlocked yes)
			(layer "F.Fab")
			(hide yes)
			(effects
				(font
					(size 1.016 1.016)
					(thickness 0.1524)
				)
			)
		)
		(duplicate_pad_numbers_are_jumpers no)
		(fp_line
			(start -0.508 -0.9398)
			(end -0.508 0.9398)
			(stroke
				(width 0.1524)
				(type default)
			)
			(layer "F.SilkS")
		)
		(fp_line
			(start 0.508 -0.9398)
			(end -0.508 -0.9398)
			(stroke
				(width 0.1524)
				(type default)
			)
			(layer "F.SilkS")
		)
		(fp_rect
			(start -0.508 0.9398)
			(end 0.508 -0.9398)
			(stroke
				(width 0)
				(type default)
			)
			(fill no)
			(layer "F.CrtYd")
		)
		(fp_rect
			(start -0.508 0.9398)
			(end 0.508 -0.9398)
			(stroke
				(width 0)
				(type default)
			)
			(fill no)
			(layer "F.Fab")
		)
		(pad "1" smd custom
			(at 0 -0.4445 270)
			(size 0.1397 0.1397)
			(layers "F.Cu" "F.Mask" "F.Paste")
			(net "Z50_SSD_A_PRSNT#")
			(options
				(clearance outline)
				(anchor circle)
			)
			(primitives
				(gr_poly
					(pts
						(arc
							(start -0.1778 -0.2794)
							(mid -0.249642 -0.249642)
							(end -0.2794 -0.1778)
						)
						(arc
							(start -0.2794 0.1778)
							(mid -0.249642 0.249642)
							(end -0.1778 0.2794)
						)
						(arc
							(start 0.1778 0.2794)
							(mid 0.249642 0.249642)
							(end 0.2794 0.1778)
						)
						(arc
							(start 0.2794 -0.1778)
							(mid 0.249642 -0.249642)
							(end 0.1778 -0.2794)
						)
					)
					(width 0)
					(fill yes)
				)
			)
		)
		(pad "2" smd custom
			(at 0 0.4445 270)
			(size 0.1397 0.1397)
			(layers "F.Cu" "F.Mask" "F.Paste")
			(net "GND")
			(options
				(clearance outline)
				(anchor circle)
			)
			(primitives
				(gr_poly
					(pts
						(arc
							(start -0.1778 -0.2794)
							(mid -0.249642 -0.249642)
							(end -0.2794 -0.1778)
						)
						(arc
							(start -0.2794 0.1778)
							(mid -0.249642 0.249642)
							(end -0.1778 0.2794)
						)
						(arc
							(start 0.1778 0.2794)
							(mid 0.249642 0.249642)
							(end 0.2794 0.1778)
						)
						(arc
							(start 0.2794 -0.1778)
							(mid 0.249642 -0.249642)
							(end 0.1778 -0.2794)
						)
					)
					(width 0)
					(fill yes)
				)
			)
		)
	)
	(footprint ""
		(layer "F.Cu")
		(at 52.275994 -77.216 -90)
		(property "Reference" "PR1"
			(at 0 0 270)
			(layer "F.SilkS")
			(hide yes)
			(effects
				(font
					(size 1.27 1.27)
				)
			)
		)
		(property "Value" "37K4R2F-1-GP"
			(at 0.064008 -3.993896 270)
			(unlocked yes)
			(layer "F.Fab")
			(hide yes)
			(effects
				(font
					(size 1.016 1.016)
					(thickness 0.1524)
				)
			)
		)
		(property "Device Type" "R402H16"
			(at 0.064008 -5.517896 270)
			(unlocked yes)
			(layer "F.Fab")
			(hide yes)
			(effects
				(font
					(size 1.016 1.016)
					(thickness 0.1524)
				)
			)
		)
		(duplicate_pad_numbers_are_jumpers no)
		(fp_line
			(start -0.508 -0.9398)
			(end -0.508 0.9398)
			(stroke
				(width 0.1524)
				(type default)
			)
			(layer "F.SilkS")
		)
		(fp_line
			(start 0.508 -0.9398)
			(end -0.508 -0.9398)
			(stroke
				(width 0.1524)
				(type default)
			)
			(layer "F.SilkS")
		)
		(fp_rect
			(start -0.508 0.9398)
			(end 0.508 -0.9398)
			(stroke
				(width 0)
				(type default)
			)
			(fill no)
			(layer "F.CrtYd")
		)
		(fp_rect
			(start -0.508 0.9398)
			(end 0.508 -0.9398)
			(stroke
				(width 0)
				(type default)
			)
			(fill no)
			(layer "F.Fab")
		)
		(pad "1" smd custom
			(at 0 -0.4445 270)
			(size 0.1397 0.1397)
			(layers "F.Cu" "F.Mask" "F.Paste")
			(net "P12V")
			(options
				(clearance outline)
				(anchor circle)
			)
			(primitives
				(gr_poly
					(pts
						(arc
							(start -0.1778 -0.2794)
							(mid -0.249642 -0.249642)
							(end -0.2794 -0.1778)
						)
						(arc
							(start -0.2794 0.1778)
							(mid -0.249642 0.249642)
							(end -0.1778 0.2794)
						)
						(arc
							(start 0.1778 0.2794)
							(mid 0.249642 0.249642)
							(end 0.2794 0.1778)
						)
						(arc
							(start 0.2794 -0.1778)
							(mid 0.249642 -0.249642)
							(end 0.1778 -0.2794)
						)
					)
					(width 0)
					(fill yes)
				)
			)
		)
		(pad "2" smd custom
			(at 0 0.4445 270)
			(size 0.1397 0.1397)
			(layers "F.Cu" "F.Mask" "F.Paste")
			(net "P3V3_DEV_EN")
			(options
				(clearance outline)
				(anchor circle)
			)
			(primitives
				(gr_poly
					(pts
						(arc
							(start -0.1778 -0.2794)
							(mid -0.249642 -0.249642)
							(end -0.2794 -0.1778)
						)
						(arc
							(start -0.2794 0.1778)
							(mid -0.249642 0.249642)
							(end -0.1778 0.2794)
						)
						(arc
							(start 0.1778 0.2794)
							(mid 0.249642 0.249642)
							(end 0.2794 0.1778)
						)
						(arc
							(start 0.2794 -0.1778)
							(mid 0.249642 -0.249642)
							(end 0.1778 -0.2794)
						)
					)
					(width 0)
					(fill yes)
				)
			)
		)
	)
	(footprint ""
		(layer "F.Cu")
		(at 25.019 -82.55 -90)
		(property "Reference" "R32"
			(at 0 0 270)
			(layer "F.SilkS")
			(hide yes)
			(effects
				(font
					(size 1.27 1.27)
				)
			)
		)
		(property "Value" "4K7R2F-GP"
			(at 0.064008 -3.993896 270)
			(unlocked yes)
			(layer "F.Fab")
			(hide yes)
			(effects
				(font
					(size 1.016 1.016)
					(thickness 0.1524)
				)
			)
		)
		(property "Device Type" "R402H16"
			(at 0.064008 -5.517896 270)
			(unlocked yes)
			(layer "F.Fab")
			(hide yes)
			(effects
				(font
					(size 1.016 1.016)
					(thickness 0.1524)
				)
			)
		)
		(duplicate_pad_numbers_are_jumpers no)
		(fp_line
			(start -0.508 -0.9398)
			(end -0.508 0.9398)
			(stroke
				(width 0.1524)
				(type default)
			)
			(layer "F.SilkS")
		)
		(fp_line
			(start 0.508 -0.9398)
			(end -0.508 -0.9398)
			(stroke
				(width 0.1524)
				(type default)
			)
			(layer "F.SilkS")
		)
		(fp_rect
			(start -0.508 0.9398)
			(end 0.508 -0.9398)
			(stroke
				(width 0)
				(type default)
			)
			(fill no)
			(layer "F.CrtYd")
		)
		(fp_rect
			(start -0.508 0.9398)
			(end 0.508 -0.9398)
			(stroke
				(width 0)
				(type default)
			)
			(fill no)
			(layer "F.Fab")
		)
		(pad "1" smd custom
			(at 0 -0.4445 270)
			(size 0.1397 0.1397)
			(layers "F.Cu" "F.Mask" "F.Paste")
			(net "Z50_SMB_SWITCH_RESET#")
			(options
				(clearance outline)
				(anchor circle)
			)
			(primitives
				(gr_poly
					(pts
						(arc
							(start -0.1778 -0.2794)
							(mid -0.249642 -0.249642)
							(end -0.2794 -0.1778)
						)
						(arc
							(start -0.2794 0.1778)
							(mid -0.249642 0.249642)
							(end -0.1778 0.2794)
						)
						(arc
							(start 0.1778 0.2794)
							(mid 0.249642 0.249642)
							(end 0.2794 0.1778)
						)
						(arc
							(start 0.2794 -0.1778)
							(mid 0.249642 -0.249642)
							(end 0.1778 -0.2794)
						)
					)
					(width 0)
					(fill yes)
				)
			)
		)
		(pad "2" smd custom
			(at 0 0.4445 270)
			(size 0.1397 0.1397)
			(layers "F.Cu" "F.Mask" "F.Paste")
			(net "P3V3_DPB")
			(options
				(clearance outline)
				(anchor circle)
			)
			(primitives
				(gr_poly
					(pts
						(arc
							(start -0.1778 -0.2794)
							(mid -0.249642 -0.249642)
							(end -0.2794 -0.1778)
						)
						(arc
							(start -0.2794 0.1778)
							(mid -0.249642 0.249642)
							(end -0.1778 0.2794)
						)
						(arc
							(start 0.1778 0.2794)
							(mid 0.249642 0.249642)
							(end 0.2794 0.1778)
						)
						(arc
							(start 0.2794 -0.1778)
							(mid 0.249642 -0.249642)
							(end 0.1778 -0.2794)
						)
					)
					(width 0)
					(fill yes)
				)
			)
		)
	)
	(footprint ""
		(layer "F.Cu")
		(at 75.184 -34.036)
		(property "Reference" "R47"
			(at 0 0 0)
			(layer "F.SilkS")
			(hide yes)
			(effects
				(font
					(size 1.27 1.27)
				)
			)
		)
		(property "Value" "47KR2F-GP"
			(at 0.064008 -3.993896 0)
			(unlocked yes)
			(layer "F.Fab")
			(hide yes)
			(effects
				(font
					(size 1.016 1.016)
					(thickness 0.1524)
				)
			)
		)
		(property "Device Type" "R402H16"
			(at 0.064008 -5.517896 0)
			(unlocked yes)
			(layer "F.Fab")
			(hide yes)
			(effects
				(font
					(size 1.016 1.016)
					(thickness 0.1524)
				)
			)
		)
		(duplicate_pad_numbers_are_jumpers no)
		(fp_line
			(start -0.508 -0.9398)
			(end -0.508 0.9398)
			(stroke
				(width 0.1524)
				(type default)
			)
			(layer "F.SilkS")
		)
		(fp_line
			(start 0.508 -0.9398)
			(end -0.508 -0.9398)
			(stroke
				(width 0.1524)
				(type default)
			)
			(layer "F.SilkS")
		)
		(fp_rect
			(start -0.508 0.9398)
			(end 0.508 -0.9398)
			(stroke
				(width 0)
				(type default)
			)
			(fill no)
			(layer "F.CrtYd")
		)
		(fp_rect
			(start -0.508 0.9398)
			(end 0.508 -0.9398)
			(stroke
				(width 0)
				(type default)
			)
			(fill no)
			(layer "F.Fab")
		)
		(pad "1" smd custom
			(at 0 -0.4445)
			(size 0.1397 0.1397)
			(layers "F.Cu" "F.Mask" "F.Paste")
			(net "Z50_SSD_B_PRSNT#")
			(options
				(clearance outline)
				(anchor circle)
			)
			(primitives
				(gr_poly
					(pts
						(arc
							(start -0.1778 -0.2794)
							(mid -0.249642 -0.249642)
							(end -0.2794 -0.1778)
						)
						(arc
							(start -0.2794 0.1778)
							(mid -0.249642 0.249642)
							(end -0.1778 0.2794)
						)
						(arc
							(start 0.1778 0.2794)
							(mid 0.249642 0.249642)
							(end 0.2794 0.1778)
						)
						(arc
							(start 0.2794 -0.1778)
							(mid 0.249642 -0.249642)
							(end 0.1778 -0.2794)
						)
					)
					(width 0)
					(fill yes)
				)
			)
		)
		(pad "2" smd custom
			(at 0 0.4445)
			(size 0.1397 0.1397)
			(layers "F.Cu" "F.Mask" "F.Paste")
			(net "GND")
			(options
				(clearance outline)
				(anchor circle)
			)
			(primitives
				(gr_poly
					(pts
						(arc
							(start -0.1778 -0.2794)
							(mid -0.249642 -0.249642)
							(end -0.2794 -0.1778)
						)
						(arc
							(start -0.2794 0.1778)
							(mid -0.249642 0.249642)
							(end -0.1778 0.2794)
						)
						(arc
							(start 0.1778 0.2794)
							(mid 0.249642 0.249642)
							(end 0.2794 0.1778)
						)
						(arc
							(start 0.2794 -0.1778)
							(mid 0.249642 -0.249642)
							(end 0.1778 -0.2794)
						)
					)
					(width 0)
					(fill yes)
				)
			)
		)
	)
	(footprint ""
		(layer "F.Cu")
		(at 17.526 -75.867006 -90)
		(property "Reference" "PR22"
			(at 0 0 270)
			(layer "F.SilkS")
			(hide yes)
			(effects
				(font
					(size 1.27 1.27)
				)
			)
		)
		(property "Value" "3K65R2F-1-GP"
			(at 0.064008 -3.993896 270)
			(unlocked yes)
			(layer "F.Fab")
			(hide yes)
			(effects
				(font
					(size 1.016 1.016)
					(thickness 0.1524)
				)
			)
		)
		(property "Device Type" "R402H16"
			(at 0.064008 -5.517896 270)
			(unlocked yes)
			(layer "F.Fab")
			(hide yes)
			(effects
				(font
					(size 1.016 1.016)
					(thickness 0.1524)
				)
			)
		)
		(duplicate_pad_numbers_are_jumpers no)
		(fp_line
			(start -0.508 -0.9398)
			(end -0.508 0.9398)
			(stroke
				(width 0.1524)
				(type default)
			)
			(layer "F.SilkS")
		)
		(fp_line
			(start 0.508 -0.9398)
			(end -0.508 -0.9398)
			(stroke
				(width 0.1524)
				(type default)
			)
			(layer "F.SilkS")
		)
		(fp_rect
			(start -0.508 0.9398)
			(end 0.508 -0.9398)
			(stroke
				(width 0)
				(type default)
			)
			(fill no)
			(layer "F.CrtYd")
		)
		(fp_rect
			(start -0.508 0.9398)
			(end 0.508 -0.9398)
			(stroke
				(width 0)
				(type default)
			)
			(fill no)
			(layer "F.Fab")
		)
		(pad "1" smd custom
			(at 0 -0.4445 270)
			(size 0.1397 0.1397)
			(layers "F.Cu" "F.Mask" "F.Paste")
			(net "P1V8_PWR")
			(options
				(clearance outline)
				(anchor circle)
			)
			(primitives
				(gr_poly
					(pts
						(arc
							(start -0.1778 -0.2794)
							(mid -0.249642 -0.249642)
							(end -0.2794 -0.1778)
						)
						(arc
							(start -0.2794 0.1778)
							(mid -0.249642 0.249642)
							(end -0.1778 0.2794)
						)
						(arc
							(start 0.1778 0.2794)
							(mid 0.249642 0.249642)
							(end 0.2794 0.1778)
						)
						(arc
							(start 0.2794 -0.1778)
							(mid 0.249642 -0.249642)
							(end 0.1778 -0.2794)
						)
					)
					(width 0)
					(fill yes)
				)
			)
		)
		(pad "2" smd custom
			(at 0 0.4445 270)
			(size 0.1397 0.1397)
			(layers "F.Cu" "F.Mask" "F.Paste")
			(net "P1V8_PWR_FB")
			(options
				(clearance outline)
				(anchor circle)
			)
			(primitives
				(gr_poly
					(pts
						(arc
							(start -0.1778 -0.2794)
							(mid -0.249642 -0.249642)
							(end -0.2794 -0.1778)
						)
						(arc
							(start -0.2794 0.1778)
							(mid -0.249642 0.249642)
							(end -0.1778 0.2794)
						)
						(arc
							(start 0.1778 0.2794)
							(mid 0.249642 0.249642)
							(end 0.2794 0.1778)
						)
						(arc
							(start 0.2794 -0.1778)
							(mid 0.249642 -0.249642)
							(end 0.1778 -0.2794)
						)
					)
					(width 0)
					(fill yes)
				)
			)
		)
	)
	(footprint ""
		(layer "F.Cu")
		(at 53.1114 -76.2508 -90)
		(property "Reference" "PC43"
			(at 0 0 270)
			(layer "F.SilkS")
			(hide yes)
			(effects
				(font
					(size 1.27 1.27)
				)
			)
		)
		(property "Value" "SC1KP50V2KX-1GP"
			(at 1.1811 -2.7051 270)
			(unlocked yes)
			(layer "F.Fab")
			(hide yes)
			(effects
				(font
					(size 1.016 1.016)
					(thickness 0.1524)
				)
			)
		)
		(property "Device Type" "C402H22"
			(at 1.1811 -4.2291 270)
			(unlocked yes)
			(layer "F.Fab")
			(hide yes)
			(effects
				(font
					(size 1.016 1.016)
					(thickness 0.1524)
				)
			)
		)
		(duplicate_pad_numbers_are_jumpers no)
		(fp_rect
			(start -0.4318 0.9525)
			(end 0.4318 -0.9525)
			(stroke
				(width 0)
				(type default)
			)
			(fill no)
			(layer "F.CrtYd")
		)
		(fp_rect
			(start -0.4318 0.9525)
			(end 0.4318 -0.9525)
			(stroke
				(width 0)
				(type default)
			)
			(fill no)
			(layer "F.Fab")
		)
		(pad "1" smd custom
			(at 0 -0.4445 270)
			(size 0.1524 0.1524)
			(layers "F.Cu" "F.Mask" "F.Paste")
			(net "P3V3_DEV_LL_R")
			(options
				(clearance outline)
				(anchor circle)
			)
			(primitives
				(gr_poly
					(pts
						(arc
							(start 0.3048 -0.2032)
							(mid 0.275042 -0.275042)
							(end 0.2032 -0.3048)
						)
						(arc
							(start -0.2032 -0.3048)
							(mid -0.275042 -0.275042)
							(end -0.3048 -0.2032)
						)
						(arc
							(start -0.3048 0.2032)
							(mid -0.275042 0.275042)
							(end -0.2032 0.3048)
						)
						(arc
							(start 0.2032 0.3048)
							(mid 0.275042 0.275042)
							(end 0.3048 0.2032)
						)
					)
					(width 0)
					(fill yes)
				)
			)
		)
		(pad "2" smd custom
			(at 0 0.4445 270)
			(size 0.1524 0.1524)
			(layers "F.Cu" "F.Mask" "F.Paste")
			(net "P3V3_DEV_VFB")
			(options
				(clearance outline)
				(anchor circle)
			)
			(primitives
				(gr_poly
					(pts
						(arc
							(start 0.3048 -0.2032)
							(mid 0.275042 -0.275042)
							(end 0.2032 -0.3048)
						)
						(arc
							(start -0.2032 -0.3048)
							(mid -0.275042 -0.275042)
							(end -0.3048 -0.2032)
						)
						(arc
							(start -0.3048 0.2032)
							(mid -0.275042 0.275042)
							(end -0.2032 0.3048)
						)
						(arc
							(start 0.2032 0.3048)
							(mid 0.275042 0.275042)
							(end 0.3048 0.2032)
						)
					)
					(width 0)
					(fill yes)
				)
			)
		)
	)
	(footprint ""
		(layer "F.Cu")
		(at 47.195994 -80.899 -90)
		(property "Reference" "PU1"
			(at 0 0 270)
			(layer "F.SilkS")
			(hide yes)
			(effects
				(font
					(size 1.27 1.27)
				)
			)
		)
		(property "Value" "TPS53319DQPR-GP"
			(at 4.7498 -5.6896 270)
			(unlocked yes)
			(layer "F.Fab")
			(hide yes)
			(effects
				(font
					(size 1.016 1.016)
					(thickness 0.1524)
				)
			)
		)
		(property "Device Type" "QFN22G6050-G6133H60"
			(at 4.7498 -7.2136 270)
			(unlocked yes)
			(layer "F.Fab")
			(hide yes)
			(effects
				(font
					(size 1.016 1.016)
					(thickness 0.1524)
				)
			)
		)
		(duplicate_pad_numbers_are_jumpers no)
		(fp_line
			(start -3.556 3.5179)
			(end -2.286 3.5179)
			(stroke
				(width 0.1524)
				(type default)
			)
			(layer "F.SilkS")
		)
		(fp_line
			(start 2.286 3.5179)
			(end 3.556 3.5179)
			(stroke
				(width 0.1524)
				(type default)
			)
			(layer "F.SilkS")
		)
		(fp_line
			(start 3.556 3.5179)
			(end 3.556 2.2479)
			(stroke
				(width 0.1524)
				(type default)
			)
			(layer "F.SilkS")
		)
		(fp_line
			(start -0.999998 3.262122)
			(end -0.999998 3.770122)
			(stroke
				(width 0.1524)
				(type default)
			)
			(layer "F.SilkS")
		)
		(fp_line
			(start 1.500124 3.262122)
			(end 1.500124 4.024122)
			(stroke
				(width 0.1524)
				(type default)
			)
			(layer "F.SilkS")
		)
		(fp_line
			(start -3.556 2.2479)
			(end -3.556 3.5179)
			(stroke
				(width 0.1524)
				(type default)
			)
			(layer "F.SilkS")
		)
		(fp_line
			(start -1.999996 -3.262122)
			(end -1.999996 -4.024122)
			(stroke
				(width 0.1524)
				(type default)
			)
			(layer "F.SilkS")
		)
		(fp_line
			(start 0.500126 -3.262122)
			(end 0.500126 -3.770122)
			(stroke
				(width 0.1524)
				(type default)
			)
			(layer "F.SilkS")
		)
		(fp_line
			(start -3.556 -3.5179)
			(end -3.556 -2.2479)
			(stroke
				(width 0.1524)
				(type default)
			)
			(layer "F.SilkS")
		)
		(fp_line
			(start -2.286 -3.5179)
			(end -3.556 -3.5179)
			(stroke
				(width 0.1524)
				(type default)
			)
			(layer "F.SilkS")
		)
		(fp_poly
			(pts
				(xy 3.556 -3.5179) (xy 2.5273 -3.5179) (xy 3.556 -2.4892)
			)
			(stroke
				(width 0)
				(type default)
			)
			(fill yes)
			(layer "F.SilkS")
		)
		(fp_rect
			(start -2.9972 2.5019)
			(end 2.9972 -2.5019)
			(stroke
				(width 0)
				(type default)
			)
			(fill no)
			(layer "F.CrtYd")
		)
		(fp_poly
			(pts
				(xy 3.556 -2.5019) (xy -2.9972 -2.5019) (xy -2.9972 2.5019) (xy 2.9972 2.5019) (xy 2.9972 -2.4892)
				(xy 3.556 -2.4892) (xy 3.556 3.5179) (xy -3.556 3.5179) (xy -3.556 -3.5179) (xy 3.556 -3.5179)
			)
			(stroke
				(width 0)
				(type default)
			)
			(fill no)
			(layer "F.CrtYd")
		)
		(fp_rect
			(start -3.556 3.5179)
			(end 3.556 -3.5179)
			(stroke
				(width 0)
				(type default)
			)
			(fill no)
			(layer "F.Fab")
		)
		(pad "1" smd rect
			(at 2.500122 -2.449322 270)
			(size 0.3048 1.1176)
			(layers "F.Cu" "F.Mask" "F.Paste")
			(net "P3V3_DEV_VFB")
		)
		(pad "2" smd rect
			(at 1.999996 -2.449322 270)
			(size 0.3048 1.1176)
			(layers "F.Cu" "F.Mask" "F.Paste")
			(net "P3V3_DEV_EN")
		)
		(pad "3" smd rect
			(at 1.500124 -2.449322 270)
			(size 0.3048 1.1176)
			(layers "F.Cu" "F.Mask" "F.Paste")
			(net "P3V3_DEV_PWRGD")
		)
		(pad "4" smd rect
			(at 0.999998 -2.449322 270)
			(size 0.3048 1.1176)
			(layers "F.Cu" "F.Mask" "F.Paste")
			(net "P3V3_DEV_VBST")
		)
		(pad "5" smd rect
			(at 0.500126 -2.449322 270)
			(size 0.3048 1.1176)
			(layers "F.Cu" "F.Mask" "F.Paste")
			(net "P3V3_DEV_ROVP")
		)
		(pad "6" smd rect
			(at 0 -2.449322 270)
			(size 0.3048 1.1176)
			(layers "F.Cu" "F.Mask" "F.Paste")
			(net "P3V3_DEV_LL")
		)
		(pad "7" smd rect
			(at -0.500126 -2.449322 270)
			(size 0.3048 1.1176)
			(layers "F.Cu" "F.Mask" "F.Paste")
			(net "P3V3_DEV_LL")
		)
		(pad "8" smd rect
			(at -0.999998 -2.449322 270)
			(size 0.3048 1.1176)
			(layers "F.Cu" "F.Mask" "F.Paste")
			(net "P3V3_DEV_LL")
		)
		(pad "9" smd rect
			(at -1.500124 -2.449322 270)
			(size 0.3048 1.1176)
			(layers "F.Cu" "F.Mask" "F.Paste")
			(net "P3V3_DEV_LL")
		)
		(pad "10" smd rect
			(at -1.999996 -2.449322 270)
			(size 0.3048 1.1176)
			(layers "F.Cu" "F.Mask" "F.Paste")
			(net "P3V3_DEV_LL")
		)
		(pad "11" smd rect
			(at -2.500122 -2.449322 270)
			(size 0.3048 1.1176)
			(layers "F.Cu" "F.Mask" "F.Paste")
			(net "P3V3_DEV_LL")
		)
		(pad "12" smd rect
			(at -2.500122 2.449322 270)
			(size 0.3048 1.1176)
			(layers "F.Cu" "F.Mask" "F.Paste")
			(net "P3V3_DEV_VIN")
		)
		(pad "13" smd rect
			(at -1.999996 2.449322 270)
			(size 0.3048 1.1176)
			(layers "F.Cu" "F.Mask" "F.Paste")
			(net "P3V3_DEV_VIN")
		)
		(pad "14" smd rect
			(at -1.500124 2.449322 270)
			(size 0.3048 1.1176)
			(layers "F.Cu" "F.Mask" "F.Paste")
			(net "P3V3_DEV_VIN")
		)
		(pad "15" smd rect
			(at -0.999998 2.449322 270)
			(size 0.3048 1.1176)
			(layers "F.Cu" "F.Mask" "F.Paste")
			(net "P3V3_DEV_VIN")
		)
		(pad "16" smd rect
			(at -0.500126 2.449322 270)
			(size 0.3048 1.1176)
			(layers "F.Cu" "F.Mask" "F.Paste")
			(net "P3V3_DEV_VIN")
		)
		(pad "17" smd rect
			(at 0 2.449322 270)
			(size 0.3048 1.1176)
			(layers "F.Cu" "F.Mask" "F.Paste")
			(net "P3V3_DEV_VIN")
		)
		(pad "18" smd rect
			(at 0.500126 2.449322 270)
			(size 0.3048 1.1176)
			(layers "F.Cu" "F.Mask" "F.Paste")
			(net "P3V3_DEV_VREG")
		)
		(pad "19" smd rect
			(at 0.999998 2.449322 270)
			(size 0.3048 1.1176)
			(layers "F.Cu" "F.Mask" "F.Paste")
			(net "P3V3_DEV_VDD")
		)
		(pad "20" smd rect
			(at 1.500124 2.449322 270)
			(size 0.3048 1.1176)
			(layers "F.Cu" "F.Mask" "F.Paste")
			(net "P3V3_DEV_MODE")
		)
		(pad "21" smd rect
			(at 1.999996 2.449322 270)
			(size 0.3048 1.1176)
			(layers "F.Cu" "F.Mask" "F.Paste")
			(net "P3V3_DEV_TRIP")
		)
		(pad "22" smd rect
			(at 2.500122 2.449322 270)
			(size 0.3048 1.1176)
			(layers "F.Cu" "F.Mask" "F.Paste")
			(net "P3V3_DEV_RF")
		)
		(pad "23" smd custom
			(at 0 0 270)
			(size 0.83185 0.83185)
			(layers "F.Cu" "F.Mask" "F.Paste")
			(net "GND")
			(options
				(clearance outline)
				(anchor circle)
			)
			(primitives
				(gr_poly
					(pts
						(xy -2.7813 1.6637) (xy -2.7813 1.2954) (xy -3.048 1.2954) (xy -3.048 0.9525) (xy -2.7813 0.9525)
						(xy -2.7813 -0.9525) (xy -3.048 -0.9525) (xy -3.048 -1.2954) (xy -2.7813 -1.2954) (xy -2.7813 -1.6637)
						(xy 2.7813 -1.6637) (xy 2.7813 -1.2954) (xy 3.048 -1.2954) (xy 3.048 -0.9525) (xy 2.7813 -0.9525)
						(xy 2.7813 0.9525) (xy 3.048 0.9525) (xy 3.048 1.2954) (xy 2.7813 1.2954) (xy 2.7813 1.6637)
					)
					(width 0)
					(fill yes)
				)
			)
		)
	)
	(footprint ""
		(layer "F.Cu")
		(at 20.447 -76.629006 90)
		(property "Reference" "PC25"
			(at 0 0 90)
			(layer "F.SilkS")
			(hide yes)
			(effects
				(font
					(size 1.27 1.27)
				)
			)
		)
		(property "Value" "SC22U6D3V5MX-5-GP"
			(at -0.0762 -6.1214 90)
			(unlocked yes)
			(layer "F.Fab")
			(hide yes)
			(effects
				(font
					(size 1.016 1.016)
					(thickness 0.1524)
				)
			)
		)
		(property "Device Type" "C805H56"
			(at -0.0762 -8.1534 90)
			(unlocked yes)
			(layer "F.Fab")
			(hide yes)
			(effects
				(font
					(size 1.016 1.016)
					(thickness 0.1524)
				)
			)
		)
		(duplicate_pad_numbers_are_jumpers no)
		(fp_line
			(start 0.635 0)
			(end -0.635 0)
			(stroke
				(width 0.508)
				(type default)
			)
			(layer "F.SilkS")
		)
		(fp_rect
			(start -0.9652 1.778)
			(end 0.9652 -1.778)
			(stroke
				(width 0)
				(type default)
			)
			(fill no)
			(layer "F.CrtYd")
		)
		(fp_poly
			(pts
				(xy -0.9652 -1.778) (xy 0.9652 -1.778) (xy 0.9652 1.778) (xy -0.9652 1.778)
			)
			(stroke
				(width 0)
				(type default)
			)
			(fill no)
			(layer "F.Fab")
		)
		(pad "1" smd rect
			(at 0 -0.9652 90)
			(size 1.397 1.143)
			(layers "F.Cu" "F.Mask" "F.Paste")
			(net "P1V8_PWR")
		)
		(pad "2" smd rect
			(at 0 0.9652 90)
			(size 1.397 1.143)
			(layers "F.Cu" "F.Mask" "F.Paste")
			(net "GND")
		)
	)
	(footprint ""
		(layer "F.Cu")
		(at 59.817 -62.738 -90)
		(property "Reference" "C13"
			(at 0 0 270)
			(layer "F.SilkS")
			(hide yes)
			(effects
				(font
					(size 1.27 1.27)
				)
			)
		)
		(property "Value" "SCD1U16V2KX-3GP"
			(at 1.1811 -2.7051 270)
			(unlocked yes)
			(layer "F.Fab")
			(hide yes)
			(effects
				(font
					(size 1.016 1.016)
					(thickness 0.1524)
				)
			)
		)
		(property "Device Type" "C402H22"
			(at 1.1811 -4.2291 270)
			(unlocked yes)
			(layer "F.Fab")
			(hide yes)
			(effects
				(font
					(size 1.016 1.016)
					(thickness 0.1524)
				)
			)
		)
		(duplicate_pad_numbers_are_jumpers no)
		(fp_rect
			(start -0.4318 0.9525)
			(end 0.4318 -0.9525)
			(stroke
				(width 0)
				(type default)
			)
			(fill no)
			(layer "F.CrtYd")
		)
		(fp_rect
			(start -0.4318 0.9525)
			(end 0.4318 -0.9525)
			(stroke
				(width 0)
				(type default)
			)
			(fill no)
			(layer "F.Fab")
		)
		(pad "1" smd custom
			(at 0 -0.4445 270)
			(size 0.1524 0.1524)
			(layers "F.Cu" "F.Mask" "F.Paste")
			(net "P3V3_PWR")
			(options
				(clearance outline)
				(anchor circle)
			)
			(primitives
				(gr_poly
					(pts
						(arc
							(start 0.3048 -0.2032)
							(mid 0.275042 -0.275042)
							(end 0.2032 -0.3048)
						)
						(arc
							(start -0.2032 -0.3048)
							(mid -0.275042 -0.275042)
							(end -0.3048 -0.2032)
						)
						(arc
							(start -0.3048 0.2032)
							(mid -0.275042 0.275042)
							(end -0.2032 0.3048)
						)
						(arc
							(start 0.2032 0.3048)
							(mid 0.275042 0.275042)
							(end 0.3048 0.2032)
						)
					)
					(width 0)
					(fill yes)
				)
			)
		)
		(pad "2" smd custom
			(at 0 0.4445 270)
			(size 0.1524 0.1524)
			(layers "F.Cu" "F.Mask" "F.Paste")
			(net "GND")
			(options
				(clearance outline)
				(anchor circle)
			)
			(primitives
				(gr_poly
					(pts
						(arc
							(start 0.3048 -0.2032)
							(mid 0.275042 -0.275042)
							(end 0.2032 -0.3048)
						)
						(arc
							(start -0.2032 -0.3048)
							(mid -0.275042 -0.275042)
							(end -0.3048 -0.2032)
						)
						(arc
							(start -0.3048 0.2032)
							(mid -0.275042 0.275042)
							(end -0.2032 0.3048)
						)
						(arc
							(start 0.2032 0.3048)
							(mid 0.275042 0.275042)
							(end 0.3048 0.2032)
						)
					)
					(width 0)
					(fill yes)
				)
			)
		)
	)
	(footprint ""
		(layer "F.Cu")
		(at 26.162 -71.755)
		(property "Reference" "C10"
			(at 0 0 0)
			(layer "F.SilkS")
			(hide yes)
			(effects
				(font
					(size 1.27 1.27)
				)
			)
		)
		(property "Value" "SCD1U16V2KX-3GP"
			(at 1.1811 -2.7051 0)
			(unlocked yes)
			(layer "F.Fab")
			(hide yes)
			(effects
				(font
					(size 1.016 1.016)
					(thickness 0.1524)
				)
			)
		)
		(property "Device Type" "C402H22"
			(at 1.1811 -4.2291 0)
			(unlocked yes)
			(layer "F.Fab")
			(hide yes)
			(effects
				(font
					(size 1.016 1.016)
					(thickness 0.1524)
				)
			)
		)
		(duplicate_pad_numbers_are_jumpers no)
		(fp_rect
			(start -0.4318 0.9525)
			(end 0.4318 -0.9525)
			(stroke
				(width 0)
				(type default)
			)
			(fill no)
			(layer "F.CrtYd")
		)
		(fp_rect
			(start -0.4318 0.9525)
			(end 0.4318 -0.9525)
			(stroke
				(width 0)
				(type default)
			)
			(fill no)
			(layer "F.Fab")
		)
		(pad "1" smd custom
			(at 0 -0.4445)
			(size 0.1524 0.1524)
			(layers "F.Cu" "F.Mask" "F.Paste")
			(net "P3V3_DPB")
			(options
				(clearance outline)
				(anchor circle)
			)
			(primitives
				(gr_poly
					(pts
						(arc
							(start 0.3048 -0.2032)
							(mid 0.275042 -0.275042)
							(end 0.2032 -0.3048)
						)
						(arc
							(start -0.2032 -0.3048)
							(mid -0.275042 -0.275042)
							(end -0.3048 -0.2032)
						)
						(arc
							(start -0.3048 0.2032)
							(mid -0.275042 0.275042)
							(end -0.2032 0.3048)
						)
						(arc
							(start 0.2032 0.3048)
							(mid 0.275042 0.275042)
							(end 0.3048 0.2032)
						)
					)
					(width 0)
					(fill yes)
				)
			)
		)
		(pad "2" smd custom
			(at 0 0.4445)
			(size 0.1524 0.1524)
			(layers "F.Cu" "F.Mask" "F.Paste")
			(net "GND")
			(options
				(clearance outline)
				(anchor circle)
			)
			(primitives
				(gr_poly
					(pts
						(arc
							(start 0.3048 -0.2032)
							(mid 0.275042 -0.275042)
							(end 0.2032 -0.3048)
						)
						(arc
							(start -0.2032 -0.3048)
							(mid -0.275042 -0.275042)
							(end -0.3048 -0.2032)
						)
						(arc
							(start -0.3048 0.2032)
							(mid -0.275042 0.275042)
							(end -0.2032 0.3048)
						)
						(arc
							(start 0.2032 0.3048)
							(mid 0.275042 0.275042)
							(end 0.3048 0.2032)
						)
					)
					(width 0)
					(fill yes)
				)
			)
		)
	)
	(footprint ""
		(layer "F.Cu")
		(at 37.338 -84.582 180)
		(property "Reference" "PC34"
			(at 0 0 180)
			(layer "F.SilkS")
			(hide yes)
			(effects
				(font
					(size 1.27 1.27)
				)
			)
		)
		(property "Value" "SC10U16V5KX-1-GP"
			(at -0.0762 -6.1214 180)
			(unlocked yes)
			(layer "F.Fab")
			(hide yes)
			(effects
				(font
					(size 1.016 1.016)
					(thickness 0.1524)
				)
			)
		)
		(property "Device Type" "C805H54"
			(at -0.0762 -8.1534 180)
			(unlocked yes)
			(layer "F.Fab")
			(hide yes)
			(effects
				(font
					(size 1.016 1.016)
					(thickness 0.1524)
				)
			)
		)
		(duplicate_pad_numbers_are_jumpers no)
		(fp_line
			(start 0.635 0)
			(end -0.635 0)
			(stroke
				(width 0.508)
				(type default)
			)
			(layer "F.SilkS")
		)
		(fp_rect
			(start -0.9652 1.778)
			(end 0.9652 -1.778)
			(stroke
				(width 0)
				(type default)
			)
			(fill no)
			(layer "F.CrtYd")
		)
		(fp_poly
			(pts
				(xy -0.9652 -1.778) (xy 0.9652 -1.778) (xy 0.9652 1.778) (xy -0.9652 1.778)
			)
			(stroke
				(width 0)
				(type default)
			)
			(fill no)
			(layer "F.Fab")
		)
		(pad "1" smd rect
			(at 0 -0.9652 180)
			(size 1.397 1.143)
			(layers "F.Cu" "F.Mask" "F.Paste")
			(net "P3V3_DEV_VIN")
		)
		(pad "2" smd rect
			(at 0 0.9652 180)
			(size 1.397 1.143)
			(layers "F.Cu" "F.Mask" "F.Paste")
			(net "GND")
		)
	)
	(footprint ""
		(layer "F.Cu")
		(at 42.750994 -76.2)
		(property "Reference" "PR29"
			(at 0 0 0)
			(layer "F.SilkS")
			(hide yes)
			(effects
				(font
					(size 1.27 1.27)
				)
			)
		)
		(property "Value" "100KR2F-L1-GP"
			(at 0.064008 -3.993896 0)
			(unlocked yes)
			(layer "F.Fab")
			(hide yes)
			(effects
				(font
					(size 1.016 1.016)
					(thickness 0.1524)
				)
			)
		)
		(property "Device Type" "R402H16"
			(at 0.064008 -5.517896 0)
			(unlocked yes)
			(layer "F.Fab")
			(hide yes)
			(effects
				(font
					(size 1.016 1.016)
					(thickness 0.1524)
				)
			)
		)
		(duplicate_pad_numbers_are_jumpers no)
		(fp_line
			(start -0.508 -0.9398)
			(end -0.508 0.9398)
			(stroke
				(width 0.1524)
				(type default)
			)
			(layer "F.SilkS")
		)
		(fp_line
			(start 0.508 -0.9398)
			(end -0.508 -0.9398)
			(stroke
				(width 0.1524)
				(type default)
			)
			(layer "F.SilkS")
		)
		(fp_rect
			(start -0.508 0.9398)
			(end 0.508 -0.9398)
			(stroke
				(width 0)
				(type default)
			)
			(fill no)
			(layer "F.CrtYd")
		)
		(fp_rect
			(start -0.508 0.9398)
			(end 0.508 -0.9398)
			(stroke
				(width 0)
				(type default)
			)
			(fill no)
			(layer "F.Fab")
		)
		(pad "1" smd custom
			(at 0 -0.4445)
			(size 0.1397 0.1397)
			(layers "F.Cu" "F.Mask" "F.Paste")
			(net "P3V3_DEV_MODE")
			(options
				(clearance outline)
				(anchor circle)
			)
			(primitives
				(gr_poly
					(pts
						(arc
							(start -0.1778 -0.2794)
							(mid -0.249642 -0.249642)
							(end -0.2794 -0.1778)
						)
						(arc
							(start -0.2794 0.1778)
							(mid -0.249642 0.249642)
							(end -0.1778 0.2794)
						)
						(arc
							(start 0.1778 0.2794)
							(mid 0.249642 0.249642)
							(end 0.2794 0.1778)
						)
						(arc
							(start 0.2794 -0.1778)
							(mid 0.249642 -0.249642)
							(end 0.1778 -0.2794)
						)
					)
					(width 0)
					(fill yes)
				)
			)
		)
		(pad "2" smd custom
			(at 0 0.4445)
			(size 0.1397 0.1397)
			(layers "F.Cu" "F.Mask" "F.Paste")
			(net "P3V3_DEV_PWRGD")
			(options
				(clearance outline)
				(anchor circle)
			)
			(primitives
				(gr_poly
					(pts
						(arc
							(start -0.1778 -0.2794)
							(mid -0.249642 -0.249642)
							(end -0.2794 -0.1778)
						)
						(arc
							(start -0.2794 0.1778)
							(mid -0.249642 0.249642)
							(end -0.1778 0.2794)
						)
						(arc
							(start 0.1778 0.2794)
							(mid 0.249642 0.249642)
							(end 0.2794 0.1778)
						)
						(arc
							(start 0.2794 -0.1778)
							(mid 0.249642 -0.249642)
							(end 0.1778 -0.2794)
						)
					)
					(width 0)
					(fill yes)
				)
			)
		)
	)
	(footprint ""
		(layer "F.Cu")
		(at 25.019 -80.518 90)
		(property "Reference" "R31"
			(at 0 0 90)
			(layer "F.SilkS")
			(hide yes)
			(effects
				(font
					(size 1.27 1.27)
				)
			)
		)
		(property "Value" "4K7R2F-GP"
			(at 0.064008 -3.993896 90)
			(unlocked yes)
			(layer "F.Fab")
			(hide yes)
			(effects
				(font
					(size 1.016 1.016)
					(thickness 0.1524)
				)
			)
		)
		(property "Device Type" "R402H16"
			(at 0.064008 -5.517896 90)
			(unlocked yes)
			(layer "F.Fab")
			(hide yes)
			(effects
				(font
					(size 1.016 1.016)
					(thickness 0.1524)
				)
			)
		)
		(duplicate_pad_numbers_are_jumpers no)
		(fp_line
			(start 0.508 -0.9398)
			(end -0.508 -0.9398)
			(stroke
				(width 0.1524)
				(type default)
			)
			(layer "F.SilkS")
		)
		(fp_line
			(start -0.508 -0.9398)
			(end -0.508 0.9398)
			(stroke
				(width 0.1524)
				(type default)
			)
			(layer "F.SilkS")
		)
		(fp_rect
			(start -0.508 0.9398)
			(end 0.508 -0.9398)
			(stroke
				(width 0)
				(type default)
			)
			(fill no)
			(layer "F.CrtYd")
		)
		(fp_rect
			(start -0.508 0.9398)
			(end 0.508 -0.9398)
			(stroke
				(width 0)
				(type default)
			)
			(fill no)
			(layer "F.Fab")
		)
		(pad "1" smd custom
			(at 0 -0.4445 90)
			(size 0.1397 0.1397)
			(layers "F.Cu" "F.Mask" "F.Paste")
			(net "P3V3_DPB")
			(options
				(clearance outline)
				(anchor circle)
			)
			(primitives
				(gr_poly
					(pts
						(arc
							(start -0.1778 -0.2794)
							(mid -0.249642 -0.249642)
							(end -0.2794 -0.1778)
						)
						(arc
							(start -0.2794 0.1778)
							(mid -0.249642 0.249642)
							(end -0.1778 0.2794)
						)
						(arc
							(start 0.1778 0.2794)
							(mid 0.249642 0.249642)
							(end 0.2794 0.1778)
						)
						(arc
							(start 0.2794 -0.1778)
							(mid 0.249642 -0.249642)
							(end 0.1778 -0.2794)
						)
					)
					(width 0)
					(fill yes)
				)
			)
		)
		(pad "2" smd custom
			(at 0 0.4445 90)
			(size 0.1397 0.1397)
			(layers "F.Cu" "F.Mask" "F.Paste")
			(net "Z50_SMB_SWITCH_ADDRESS_A0")
			(options
				(clearance outline)
				(anchor circle)
			)
			(primitives
				(gr_poly
					(pts
						(arc
							(start -0.1778 -0.2794)
							(mid -0.249642 -0.249642)
							(end -0.2794 -0.1778)
						)
						(arc
							(start -0.2794 0.1778)
							(mid -0.249642 0.249642)
							(end -0.1778 0.2794)
						)
						(arc
							(start 0.1778 0.2794)
							(mid 0.249642 0.249642)
							(end 0.2794 0.1778)
						)
						(arc
							(start 0.2794 -0.1778)
							(mid 0.249642 -0.249642)
							(end 0.1778 -0.2794)
						)
					)
					(width 0)
					(fill yes)
				)
			)
		)
	)
	(footprint ""
		(layer "F.Cu")
		(at 73.66 -41.021)
		(property "Reference" "C42"
			(at 0 0 0)
			(layer "F.SilkS")
			(hide yes)
			(effects
				(font
					(size 1.27 1.27)
				)
			)
		)
		(property "Value" "SCD1U16V2KX-3GP"
			(at 1.1811 -2.7051 0)
			(unlocked yes)
			(layer "F.Fab")
			(hide yes)
			(effects
				(font
					(size 1.016 1.016)
					(thickness 0.1524)
				)
			)
		)
		(property "Device Type" "C402H22"
			(at 1.1811 -4.2291 0)
			(unlocked yes)
			(layer "F.Fab")
			(hide yes)
			(effects
				(font
					(size 1.016 1.016)
					(thickness 0.1524)
				)
			)
		)
		(duplicate_pad_numbers_are_jumpers no)
		(fp_rect
			(start -0.4318 0.9525)
			(end 0.4318 -0.9525)
			(stroke
				(width 0)
				(type default)
			)
			(fill no)
			(layer "F.CrtYd")
		)
		(fp_rect
			(start -0.4318 0.9525)
			(end 0.4318 -0.9525)
			(stroke
				(width 0)
				(type default)
			)
			(fill no)
			(layer "F.Fab")
		)
		(pad "1" smd custom
			(at 0 -0.4445)
			(size 0.1524 0.1524)
			(layers "F.Cu" "F.Mask" "F.Paste")
			(net "P3V3_DPB")
			(options
				(clearance outline)
				(anchor circle)
			)
			(primitives
				(gr_poly
					(pts
						(arc
							(start 0.3048 -0.2032)
							(mid 0.275042 -0.275042)
							(end 0.2032 -0.3048)
						)
						(arc
							(start -0.2032 -0.3048)
							(mid -0.275042 -0.275042)
							(end -0.3048 -0.2032)
						)
						(arc
							(start -0.3048 0.2032)
							(mid -0.275042 0.275042)
							(end -0.2032 0.3048)
						)
						(arc
							(start 0.2032 0.3048)
							(mid 0.275042 0.275042)
							(end 0.3048 0.2032)
						)
					)
					(width 0)
					(fill yes)
				)
			)
		)
		(pad "2" smd custom
			(at 0 0.4445)
			(size 0.1524 0.1524)
			(layers "F.Cu" "F.Mask" "F.Paste")
			(net "GND")
			(options
				(clearance outline)
				(anchor circle)
			)
			(primitives
				(gr_poly
					(pts
						(arc
							(start 0.3048 -0.2032)
							(mid 0.275042 -0.275042)
							(end 0.2032 -0.3048)
						)
						(arc
							(start -0.2032 -0.3048)
							(mid -0.275042 -0.275042)
							(end -0.3048 -0.2032)
						)
						(arc
							(start -0.3048 0.2032)
							(mid -0.275042 0.275042)
							(end -0.2032 0.3048)
						)
						(arc
							(start 0.2032 0.3048)
							(mid 0.275042 0.275042)
							(end 0.3048 0.2032)
						)
					)
					(width 0)
					(fill yes)
				)
			)
		)
	)
	(footprint ""
		(layer "F.Cu")
		(at 50.751994 -75.692)
		(property "Reference" "PR39"
			(at 0 0 0)
			(layer "F.SilkS")
			(hide yes)
			(effects
				(font
					(size 1.27 1.27)
				)
			)
		)
		(property "Value" "45K3R2F-L-GP"
			(at 0.064008 -3.993896 0)
			(unlocked yes)
			(layer "F.Fab")
			(hide yes)
			(effects
				(font
					(size 1.016 1.016)
					(thickness 0.1524)
				)
			)
		)
		(property "Device Type" "R402H16"
			(at 0.064008 -5.517896 0)
			(unlocked yes)
			(layer "F.Fab")
			(hide yes)
			(effects
				(font
					(size 1.016 1.016)
					(thickness 0.1524)
				)
			)
		)
		(duplicate_pad_numbers_are_jumpers no)
		(fp_line
			(start -0.508 -0.9398)
			(end -0.508 0.9398)
			(stroke
				(width 0.1524)
				(type default)
			)
			(layer "F.SilkS")
		)
		(fp_line
			(start 0.508 -0.9398)
			(end -0.508 -0.9398)
			(stroke
				(width 0.1524)
				(type default)
			)
			(layer "F.SilkS")
		)
		(fp_rect
			(start -0.508 0.9398)
			(end 0.508 -0.9398)
			(stroke
				(width 0)
				(type default)
			)
			(fill no)
			(layer "F.CrtYd")
		)
		(fp_rect
			(start -0.508 0.9398)
			(end 0.508 -0.9398)
			(stroke
				(width 0)
				(type default)
			)
			(fill no)
			(layer "F.Fab")
		)
		(pad "1" smd custom
			(at 0 -0.4445)
			(size 0.1397 0.1397)
			(layers "F.Cu" "F.Mask" "F.Paste")
			(net "P3V3_DEV_VFB")
			(options
				(clearance outline)
				(anchor circle)
			)
			(primitives
				(gr_poly
					(pts
						(arc
							(start -0.1778 -0.2794)
							(mid -0.249642 -0.249642)
							(end -0.2794 -0.1778)
						)
						(arc
							(start -0.2794 0.1778)
							(mid -0.249642 0.249642)
							(end -0.1778 0.2794)
						)
						(arc
							(start 0.1778 0.2794)
							(mid 0.249642 0.249642)
							(end 0.2794 0.1778)
						)
						(arc
							(start 0.2794 -0.1778)
							(mid 0.249642 -0.249642)
							(end 0.1778 -0.2794)
						)
					)
					(width 0)
					(fill yes)
				)
			)
		)
		(pad "2" smd custom
			(at 0 0.4445)
			(size 0.1397 0.1397)
			(layers "F.Cu" "F.Mask" "F.Paste")
			(net "P3V3_DEV_VFB_R")
			(options
				(clearance outline)
				(anchor circle)
			)
			(primitives
				(gr_poly
					(pts
						(arc
							(start -0.1778 -0.2794)
							(mid -0.249642 -0.249642)
							(end -0.2794 -0.1778)
						)
						(arc
							(start -0.2794 0.1778)
							(mid -0.249642 0.249642)
							(end -0.1778 0.2794)
						)
						(arc
							(start 0.1778 0.2794)
							(mid 0.249642 0.249642)
							(end 0.2794 0.1778)
						)
						(arc
							(start 0.2794 -0.1778)
							(mid 0.249642 -0.249642)
							(end 0.1778 -0.2794)
						)
					)
					(width 0)
					(fill yes)
				)
			)
		)
	)
	(footprint ""
		(layer "F.Cu")
		(at 75.311 -63.246 90)
		(property "Reference" "R2"
			(at 0 0 90)
			(layer "F.SilkS")
			(hide yes)
			(effects
				(font
					(size 1.27 1.27)
				)
			)
		)
		(property "Value" "0R2J-2-GP"
			(at 0.064008 -3.993896 90)
			(unlocked yes)
			(layer "F.Fab")
			(hide yes)
			(effects
				(font
					(size 1.016 1.016)
					(thickness 0.1524)
				)
			)
		)
		(property "Device Type" "R402H16"
			(at 0.064008 -5.517896 90)
			(unlocked yes)
			(layer "F.Fab")
			(hide yes)
			(effects
				(font
					(size 1.016 1.016)
					(thickness 0.1524)
				)
			)
		)
		(duplicate_pad_numbers_are_jumpers no)
		(fp_line
			(start 0.508 -0.9398)
			(end -0.508 -0.9398)
			(stroke
				(width 0.1524)
				(type default)
			)
			(layer "F.SilkS")
		)
		(fp_line
			(start -0.508 -0.9398)
			(end -0.508 0.9398)
			(stroke
				(width 0.1524)
				(type default)
			)
			(layer "F.SilkS")
		)
		(fp_rect
			(start -0.508 0.9398)
			(end 0.508 -0.9398)
			(stroke
				(width 0)
				(type default)
			)
			(fill no)
			(layer "F.CrtYd")
		)
		(fp_rect
			(start -0.508 0.9398)
			(end 0.508 -0.9398)
			(stroke
				(width 0)
				(type default)
			)
			(fill no)
			(layer "F.Fab")
		)
		(pad "1" smd custom
			(at 0 -0.4445 90)
			(size 0.1397 0.1397)
			(layers "F.Cu" "F.Mask" "F.Paste")
			(net "Z50_SSD_A_PRESENT_R#")
			(options
				(clearance outline)
				(anchor circle)
			)
			(primitives
				(gr_poly
					(pts
						(arc
							(start -0.1778 -0.2794)
							(mid -0.249642 -0.249642)
							(end -0.2794 -0.1778)
						)
						(arc
							(start -0.2794 0.1778)
							(mid -0.249642 0.249642)
							(end -0.1778 0.2794)
						)
						(arc
							(start 0.1778 0.2794)
							(mid 0.249642 0.249642)
							(end 0.2794 0.1778)
						)
						(arc
							(start 0.2794 -0.1778)
							(mid 0.249642 -0.249642)
							(end 0.1778 -0.2794)
						)
					)
					(width 0)
					(fill yes)
				)
			)
		)
		(pad "2" smd custom
			(at 0 0.4445 90)
			(size 0.1397 0.1397)
			(layers "F.Cu" "F.Mask" "F.Paste")
			(net "Z50_SSD_A_PRSNT#")
			(options
				(clearance outline)
				(anchor circle)
			)
			(primitives
				(gr_poly
					(pts
						(arc
							(start -0.1778 -0.2794)
							(mid -0.249642 -0.249642)
							(end -0.2794 -0.1778)
						)
						(arc
							(start -0.2794 0.1778)
							(mid -0.249642 0.249642)
							(end -0.1778 0.2794)
						)
						(arc
							(start 0.1778 0.2794)
							(mid 0.249642 0.249642)
							(end 0.2794 0.1778)
						)
						(arc
							(start 0.2794 -0.1778)
							(mid 0.249642 -0.249642)
							(end 0.1778 -0.2794)
						)
					)
					(width 0)
					(fill yes)
				)
			)
		)
	)
	(footprint ""
		(layer "F.Cu")
		(at 75.438 -30.734)
		(property "Reference" "C43"
			(at 0 0 0)
			(layer "F.SilkS")
			(hide yes)
			(effects
				(font
					(size 1.27 1.27)
				)
			)
		)
		(property "Value" "SC1U16V3KX-5GP"
			(at 0 -2.8194 0)
			(unlocked yes)
			(layer "F.Fab")
			(hide yes)
			(effects
				(font
					(size 1.016 1.016)
					(thickness 0.1524)
				)
			)
		)
		(property "Device Type" "C603H36"
			(at 0 -4.3434 0)
			(unlocked yes)
			(layer "F.Fab")
			(hide yes)
			(effects
				(font
					(size 1.016 1.016)
					(thickness 0.1524)
				)
			)
		)
		(duplicate_pad_numbers_are_jumpers no)
		(fp_line
			(start 0.508 0)
			(end -0.508 0)
			(stroke
				(width 0.2032)
				(type default)
			)
			(layer "F.SilkS")
		)
		(fp_rect
			(start -0.5842 1.3335)
			(end 0.5842 -1.3335)
			(stroke
				(width 0)
				(type default)
			)
			(fill no)
			(layer "F.CrtYd")
		)
		(fp_rect
			(start -0.5842 1.3335)
			(end 0.5842 -1.3335)
			(stroke
				(width 0)
				(type default)
			)
			(fill no)
			(layer "F.Fab")
		)
		(pad "1" smd custom
			(at 0 -0.762)
			(size 0.2159 0.2159)
			(layers "F.Cu" "F.Mask" "F.Paste")
			(net "P3V3_DPB")
			(options
				(clearance outline)
				(anchor circle)
			)
			(primitives
				(gr_poly
					(pts
						(arc
							(start -0.3302 -0.4318)
							(mid -0.402042 -0.402042)
							(end -0.4318 -0.3302)
						)
						(arc
							(start -0.4318 0.3302)
							(mid -0.402042 0.402042)
							(end -0.3302 0.4318)
						)
						(arc
							(start 0.3302 0.4318)
							(mid 0.402042 0.402042)
							(end 0.4318 0.3302)
						)
						(arc
							(start 0.4318 -0.3302)
							(mid 0.402042 -0.402042)
							(end 0.3302 -0.4318)
						)
					)
					(width 0)
					(fill yes)
				)
			)
		)
		(pad "2" smd custom
			(at 0 0.762)
			(size 0.2159 0.2159)
			(layers "F.Cu" "F.Mask" "F.Paste")
			(net "GND")
			(options
				(clearance outline)
				(anchor circle)
			)
			(primitives
				(gr_poly
					(pts
						(arc
							(start -0.3302 -0.4318)
							(mid -0.402042 -0.402042)
							(end -0.4318 -0.3302)
						)
						(arc
							(start -0.4318 0.3302)
							(mid -0.402042 0.402042)
							(end -0.3302 0.4318)
						)
						(arc
							(start 0.3302 0.4318)
							(mid 0.402042 0.402042)
							(end 0.4318 0.3302)
						)
						(arc
							(start 0.4318 -0.3302)
							(mid 0.402042 -0.402042)
							(end 0.3302 -0.4318)
						)
					)
					(width 0)
					(fill yes)
				)
			)
		)
	)
	(footprint ""
		(layer "F.Cu")
		(at 73.000108 -87.810086)
		(property "Reference" "H1"
			(at 0 0 0)
			(layer "F.SilkS")
			(hide yes)
			(effects
				(font
					(size 1.27 1.27)
				)
			)
		)
		(property "Value" "HOLE315R140-GP"
			(at 0 -7.5692 0)
			(unlocked yes)
			(layer "F.Fab")
			(hide yes)
			(effects
				(font
					(size 1.016 1.016)
					(thickness 0.1524)
				)
			)
		)
		(property "Device Type" "HOLE315R140"
			(at 0 -9.0932 0)
			(unlocked yes)
			(layer "F.Fab")
			(hide yes)
			(effects
				(font
					(size 1.016 1.016)
					(thickness 0.1524)
				)
			)
		)
		(duplicate_pad_numbers_are_jumpers no)
		(fp_poly
			(pts
				(arc
					(start 4.3053 0)
					(mid -4.3053 0)
					(end 4.3053 0)
				)
			)
			(stroke
				(width 0)
				(type default)
			)
			(fill no)
			(layer "F.CrtYd")
		)
		(fp_poly
			(pts
				(arc
					(start 4.3053 0)
					(mid -4.3053 0)
					(end 4.3053 0)
				)
			)
			(stroke
				(width 0)
				(type default)
			)
			(fill no)
			(layer "F.Fab")
		)
		(pad "1" thru_hole circle
			(at 0.00127 0.00127)
			(size 8.001 8.001)
			(drill 3.556)
			(layers "*.Cu" "*.Mask")
			(remove_unused_layers no)
			(net "GND")
			(clearance -1.7145)
			(thermal_gap 0.3048)
			(padstack
				(mode front_inner_back)
				(layer "Inner"
					(shape circle)
					(size 3.9624 3.9624)
					(clearance 0.3048)
				)
				(layer "B.Cu"
					(shape circle)
					(size 8.001 8.001)
					(clearance -1.7145)
				)
			)
		)
	)
	(footprint ""
		(layer "F.Cu")
		(at 20.447 -74.597006 90)
		(property "Reference" "PC24"
			(at 0 0 90)
			(layer "F.SilkS")
			(hide yes)
			(effects
				(font
					(size 1.27 1.27)
				)
			)
		)
		(property "Value" "SC22U6D3V5MX-5-GP"
			(at -0.0762 -6.1214 90)
			(unlocked yes)
			(layer "F.Fab")
			(hide yes)
			(effects
				(font
					(size 1.016 1.016)
					(thickness 0.1524)
				)
			)
		)
		(property "Device Type" "C805H56"
			(at -0.0762 -8.1534 90)
			(unlocked yes)
			(layer "F.Fab")
			(hide yes)
			(effects
				(font
					(size 1.016 1.016)
					(thickness 0.1524)
				)
			)
		)
		(duplicate_pad_numbers_are_jumpers no)
		(fp_line
			(start 0.635 0)
			(end -0.635 0)
			(stroke
				(width 0.508)
				(type default)
			)
			(layer "F.SilkS")
		)
		(fp_rect
			(start -0.9652 1.778)
			(end 0.9652 -1.778)
			(stroke
				(width 0)
				(type default)
			)
			(fill no)
			(layer "F.CrtYd")
		)
		(fp_poly
			(pts
				(xy -0.9652 -1.778) (xy 0.9652 -1.778) (xy 0.9652 1.778) (xy -0.9652 1.778)
			)
			(stroke
				(width 0)
				(type default)
			)
			(fill no)
			(layer "F.Fab")
		)
		(pad "1" smd rect
			(at 0 -0.9652 90)
			(size 1.397 1.143)
			(layers "F.Cu" "F.Mask" "F.Paste")
			(net "P1V8_PWR")
		)
		(pad "2" smd rect
			(at 0 0.9652 90)
			(size 1.397 1.143)
			(layers "F.Cu" "F.Mask" "F.Paste")
			(net "GND")
		)
	)
	(footprint ""
		(layer "F.Cu")
		(at 16.002 -76.629006)
		(property "Reference" "PC21"
			(at 0 0 0)
			(layer "F.SilkS")
			(hide yes)
			(effects
				(font
					(size 1.27 1.27)
				)
			)
		)
		(property "Value" "SC820P50V2KX-1GP"
			(at 1.1811 -2.7051 0)
			(unlocked yes)
			(layer "F.Fab")
			(hide yes)
			(effects
				(font
					(size 1.016 1.016)
					(thickness 0.1524)
				)
			)
		)
		(property "Device Type" "C402H22"
			(at 1.1811 -4.2291 0)
			(unlocked yes)
			(layer "F.Fab")
			(hide yes)
			(effects
				(font
					(size 1.016 1.016)
					(thickness 0.1524)
				)
			)
		)
		(duplicate_pad_numbers_are_jumpers no)
		(fp_rect
			(start -0.4318 0.9525)
			(end 0.4318 -0.9525)
			(stroke
				(width 0)
				(type default)
			)
			(fill no)
			(layer "F.CrtYd")
		)
		(fp_rect
			(start -0.4318 0.9525)
			(end 0.4318 -0.9525)
			(stroke
				(width 0)
				(type default)
			)
			(fill no)
			(layer "F.Fab")
		)
		(pad "1" smd custom
			(at 0 -0.4445)
			(size 0.1524 0.1524)
			(layers "F.Cu" "F.Mask" "F.Paste")
			(net "P1V8_PWR_SS_C")
			(options
				(clearance outline)
				(anchor circle)
			)
			(primitives
				(gr_poly
					(pts
						(arc
							(start 0.3048 -0.2032)
							(mid 0.275042 -0.275042)
							(end 0.2032 -0.3048)
						)
						(arc
							(start -0.2032 -0.3048)
							(mid -0.275042 -0.275042)
							(end -0.3048 -0.2032)
						)
						(arc
							(start -0.3048 0.2032)
							(mid -0.275042 0.275042)
							(end -0.2032 0.3048)
						)
						(arc
							(start 0.2032 0.3048)
							(mid 0.275042 0.275042)
							(end 0.3048 0.2032)
						)
					)
					(width 0)
					(fill yes)
				)
			)
		)
		(pad "2" smd custom
			(at 0 0.4445)
			(size 0.1524 0.1524)
			(layers "F.Cu" "F.Mask" "F.Paste")
			(net "GND")
			(options
				(clearance outline)
				(anchor circle)
			)
			(primitives
				(gr_poly
					(pts
						(arc
							(start 0.3048 -0.2032)
							(mid 0.275042 -0.275042)
							(end 0.2032 -0.3048)
						)
						(arc
							(start -0.2032 -0.3048)
							(mid -0.275042 -0.275042)
							(end -0.3048 -0.2032)
						)
						(arc
							(start -0.3048 0.2032)
							(mid -0.275042 0.275042)
							(end -0.2032 0.3048)
						)
						(arc
							(start 0.2032 0.3048)
							(mid 0.275042 0.275042)
							(end 0.3048 0.2032)
						)
					)
					(width 0)
					(fill yes)
				)
			)
		)
	)
	(footprint ""
		(layer "F.Cu")
		(at 18.161 -84.122006 180)
		(property "Reference" "PC28"
			(at 0 0 180)
			(layer "F.SilkS")
			(hide yes)
			(effects
				(font
					(size 1.27 1.27)
				)
			)
		)
		(property "Value" "SC1KP50V2KX-1GP"
			(at 1.1811 -2.7051 180)
			(unlocked yes)
			(layer "F.Fab")
			(hide yes)
			(effects
				(font
					(size 1.016 1.016)
					(thickness 0.1524)
				)
			)
		)
		(property "Device Type" "C402H22"
			(at 1.1811 -4.2291 180)
			(unlocked yes)
			(layer "F.Fab")
			(hide yes)
			(effects
				(font
					(size 1.016 1.016)
					(thickness 0.1524)
				)
			)
		)
		(duplicate_pad_numbers_are_jumpers no)
		(fp_rect
			(start -0.4318 0.9525)
			(end 0.4318 -0.9525)
			(stroke
				(width 0)
				(type default)
			)
			(fill no)
			(layer "F.CrtYd")
		)
		(fp_rect
			(start -0.4318 0.9525)
			(end 0.4318 -0.9525)
			(stroke
				(width 0)
				(type default)
			)
			(fill no)
			(layer "F.Fab")
		)
		(pad "1" smd custom
			(at 0 -0.4445 180)
			(size 0.1524 0.1524)
			(layers "F.Cu" "F.Mask" "F.Paste")
			(net "P1V8_PWR_GD")
			(options
				(clearance outline)
				(anchor circle)
			)
			(primitives
				(gr_poly
					(pts
						(arc
							(start 0.3048 -0.2032)
							(mid 0.275042 -0.275042)
							(end 0.2032 -0.3048)
						)
						(arc
							(start -0.2032 -0.3048)
							(mid -0.275042 -0.275042)
							(end -0.3048 -0.2032)
						)
						(arc
							(start -0.3048 0.2032)
							(mid -0.275042 0.275042)
							(end -0.2032 0.3048)
						)
						(arc
							(start 0.2032 0.3048)
							(mid 0.275042 0.275042)
							(end 0.3048 0.2032)
						)
					)
					(width 0)
					(fill yes)
				)
			)
		)
		(pad "2" smd custom
			(at 0 0.4445 180)
			(size 0.1524 0.1524)
			(layers "F.Cu" "F.Mask" "F.Paste")
			(net "GND")
			(options
				(clearance outline)
				(anchor circle)
			)
			(primitives
				(gr_poly
					(pts
						(arc
							(start 0.3048 -0.2032)
							(mid 0.275042 -0.275042)
							(end 0.2032 -0.3048)
						)
						(arc
							(start -0.2032 -0.3048)
							(mid -0.275042 -0.275042)
							(end -0.3048 -0.2032)
						)
						(arc
							(start -0.3048 0.2032)
							(mid -0.275042 0.275042)
							(end -0.2032 0.3048)
						)
						(arc
							(start 0.2032 0.3048)
							(mid 0.275042 0.275042)
							(end 0.3048 0.2032)
						)
					)
					(width 0)
					(fill yes)
				)
			)
		)
	)
	(footprint ""
		(layer "F.Cu")
		(at 41.91 -78.74 180)
		(property "Reference" "PC29"
			(at 0 0 180)
			(layer "F.SilkS")
			(hide yes)
			(effects
				(font
					(size 1.27 1.27)
				)
			)
		)
		(property "Value" "SC1U10V2KX-4-GP"
			(at 1.1811 -2.7051 180)
			(unlocked yes)
			(layer "F.Fab")
			(hide yes)
			(effects
				(font
					(size 1.016 1.016)
					(thickness 0.1524)
				)
			)
		)
		(property "Device Type" "C402H22"
			(at 1.1811 -4.2291 180)
			(unlocked yes)
			(layer "F.Fab")
			(hide yes)
			(effects
				(font
					(size 1.016 1.016)
					(thickness 0.1524)
				)
			)
		)
		(duplicate_pad_numbers_are_jumpers no)
		(fp_rect
			(start -0.4318 0.9525)
			(end 0.4318 -0.9525)
			(stroke
				(width 0)
				(type default)
			)
			(fill no)
			(layer "F.CrtYd")
		)
		(fp_rect
			(start -0.4318 0.9525)
			(end 0.4318 -0.9525)
			(stroke
				(width 0)
				(type default)
			)
			(fill no)
			(layer "F.Fab")
		)
		(pad "1" smd custom
			(at 0 -0.4445 180)
			(size 0.1524 0.1524)
			(layers "F.Cu" "F.Mask" "F.Paste")
			(net "GND")
			(options
				(clearance outline)
				(anchor circle)
			)
			(primitives
				(gr_poly
					(pts
						(arc
							(start 0.3048 -0.2032)
							(mid 0.275042 -0.275042)
							(end 0.2032 -0.3048)
						)
						(arc
							(start -0.2032 -0.3048)
							(mid -0.275042 -0.275042)
							(end -0.3048 -0.2032)
						)
						(arc
							(start -0.3048 0.2032)
							(mid -0.275042 0.275042)
							(end -0.2032 0.3048)
						)
						(arc
							(start 0.2032 0.3048)
							(mid 0.275042 0.275042)
							(end 0.3048 0.2032)
						)
					)
					(width 0)
					(fill yes)
				)
			)
		)
		(pad "2" smd custom
			(at 0 0.4445 180)
			(size 0.1524 0.1524)
			(layers "F.Cu" "F.Mask" "F.Paste")
			(net "P3V3_DEV_VREG")
			(options
				(clearance outline)
				(anchor circle)
			)
			(primitives
				(gr_poly
					(pts
						(arc
							(start 0.3048 -0.2032)
							(mid 0.275042 -0.275042)
							(end 0.2032 -0.3048)
						)
						(arc
							(start -0.2032 -0.3048)
							(mid -0.275042 -0.275042)
							(end -0.3048 -0.2032)
						)
						(arc
							(start -0.3048 0.2032)
							(mid -0.275042 0.275042)
							(end -0.2032 0.3048)
						)
						(arc
							(start 0.2032 0.3048)
							(mid 0.275042 0.275042)
							(end 0.3048 0.2032)
						)
					)
					(width 0)
					(fill yes)
				)
			)
		)
	)
	(footprint ""
		(layer "F.Cu")
		(at 65.532 -40.767 180)
		(property "Reference" "TP1"
			(at 0 0 180)
			(layer "F.SilkS")
			(hide yes)
			(effects
				(font
					(size 1.27 1.27)
				)
			)
		)
		(property "Value" "TPAD28-1-GP-U"
			(at 0.0508 -1.9304 180)
			(unlocked yes)
			(layer "F.Fab")
			(hide yes)
			(effects
				(font
					(size 1.016 1.016)
					(thickness 0.1524)
				)
			)
		)
		(property "Device Type" "TPAD28-1-U"
			(at 0.0508 -3.4544 180)
			(unlocked yes)
			(layer "F.Fab")
			(hide yes)
			(effects
				(font
					(size 1.016 1.016)
					(thickness 0.1524)
				)
			)
		)
		(duplicate_pad_numbers_are_jumpers no)
		(fp_poly
			(pts
				(arc
					(start -0.3556 0)
					(mid 0.3556 0)
					(end -0.3556 0)
				)
			)
			(stroke
				(width 0)
				(type default)
			)
			(fill no)
			(layer "F.CrtYd")
		)
		(fp_poly
			(pts
				(arc
					(start -0.9525 0)
					(mid 0.9525 0)
					(end -0.9525 0)
				)
			)
			(stroke
				(width 0)
				(type default)
			)
			(fill no)
			(layer "F.Fab")
		)
		(pad "1" smd circle
			(at 0 0 180)
			(size 0.7112 0.7112)
			(layers "F.Cu" "F.Mask" "F.Paste")
			(net "Z50_TEMP_1_ALERT#")
		)
	)
	(footprint ""
		(layer "F.Cu")
		(at 47.195994 -76.073 180)
		(property "Reference" "PG3"
			(at 0 0 180)
			(layer "F.SilkS")
			(hide yes)
			(effects
				(font
					(size 1.27 1.27)
				)
			)
		)
		(property "Value" "COPPER-CLOSE-GP-U"
			(at 0.0762 -2.8702 180)
			(unlocked yes)
			(layer "F.Fab")
			(hide yes)
			(effects
				(font
					(size 1.016 1.016)
					(thickness 0.1524)
				)
			)
		)
		(property "Device Type" "CON2C-U"
			(at 0.0762 -4.3942 180)
			(unlocked yes)
			(layer "F.Fab")
			(hide yes)
			(effects
				(font
					(size 1.016 1.016)
					(thickness 0.1524)
				)
			)
		)
		(duplicate_pad_numbers_are_jumpers no)
		(fp_rect
			(start -0.9398 0.9652)
			(end 0.9398 -0.9652)
			(stroke
				(width 0)
				(type default)
			)
			(fill no)
			(layer "F.CrtYd")
		)
		(fp_rect
			(start -0.9398 0.9652)
			(end 0.9398 -0.9652)
			(stroke
				(width 0)
				(type default)
			)
			(fill no)
			(layer "F.Fab")
		)
		(pad "1" smd custom
			(at 0 -0.5334 180)
			(size 0.17145 0.17145)
			(layers "F.Cu" "F.Mask" "F.Paste")
			(net "AGND_P3V3_DEV")
			(options
				(clearance outline)
				(anchor circle)
			)
			(primitives
				(gr_poly
					(pts
						(xy -0.127 0.3429) (xy -0.127 0.1651) (xy -0.635 -0.3429) (xy 0.635 -0.3429) (xy 0.127 0.1651)
						(xy 0.127 0.3429)
					)
					(width 0)
					(fill yes)
				)
			)
		)
		(pad "2" smd custom
			(at 0 0.5334 180)
			(size 0.17145 0.17145)
			(layers "F.Cu" "F.Mask" "F.Paste")
			(net "GND")
			(options
				(clearance outline)
				(anchor circle)
			)
			(primitives
				(gr_poly
					(pts
						(xy -0.635 0.3429) (xy -0.127 -0.1651) (xy -0.127 -0.3429) (xy 0.127 -0.3429) (xy 0.127 -0.1651)
						(xy 0.635 0.3429)
					)
					(width 0)
					(fill yes)
				)
			)
		)
	)
	(footprint ""
		(layer "F.Cu")
		(at 41.402 -84.582 180)
		(property "Reference" "PC32"
			(at 0 0 180)
			(layer "F.SilkS")
			(hide yes)
			(effects
				(font
					(size 1.27 1.27)
				)
			)
		)
		(property "Value" "SC10U16V5KX-1-GP"
			(at -0.0762 -6.1214 180)
			(unlocked yes)
			(layer "F.Fab")
			(hide yes)
			(effects
				(font
					(size 1.016 1.016)
					(thickness 0.1524)
				)
			)
		)
		(property "Device Type" "C805H54"
			(at -0.0762 -8.1534 180)
			(unlocked yes)
			(layer "F.Fab")
			(hide yes)
			(effects
				(font
					(size 1.016 1.016)
					(thickness 0.1524)
				)
			)
		)
		(duplicate_pad_numbers_are_jumpers no)
		(fp_line
			(start 0.635 0)
			(end -0.635 0)
			(stroke
				(width 0.508)
				(type default)
			)
			(layer "F.SilkS")
		)
		(fp_rect
			(start -0.9652 1.778)
			(end 0.9652 -1.778)
			(stroke
				(width 0)
				(type default)
			)
			(fill no)
			(layer "F.CrtYd")
		)
		(fp_poly
			(pts
				(xy -0.9652 -1.778) (xy 0.9652 -1.778) (xy 0.9652 1.778) (xy -0.9652 1.778)
			)
			(stroke
				(width 0)
				(type default)
			)
			(fill no)
			(layer "F.Fab")
		)
		(pad "1" smd rect
			(at 0 -0.9652 180)
			(size 1.397 1.143)
			(layers "F.Cu" "F.Mask" "F.Paste")
			(net "P3V3_DEV_VIN")
		)
		(pad "2" smd rect
			(at 0 0.9652 180)
			(size 1.397 1.143)
			(layers "F.Cu" "F.Mask" "F.Paste")
			(net "GND")
		)
	)
	(footprint ""
		(layer "F.Cu")
		(at 30.226 -71.628)
		(property "Reference" "R52"
			(at 0 0 0)
			(layer "F.SilkS")
			(hide yes)
			(effects
				(font
					(size 1.27 1.27)
				)
			)
		)
		(property "Value" "33R2J-2-GP"
			(at 0.064008 -3.993896 0)
			(unlocked yes)
			(layer "F.Fab")
			(hide yes)
			(effects
				(font
					(size 1.016 1.016)
					(thickness 0.1524)
				)
			)
		)
		(property "Device Type" "R402H16"
			(at 0.064008 -5.517896 0)
			(unlocked yes)
			(layer "F.Fab")
			(hide yes)
			(effects
				(font
					(size 1.016 1.016)
					(thickness 0.1524)
				)
			)
		)
		(duplicate_pad_numbers_are_jumpers no)
		(fp_line
			(start -0.508 -0.9398)
			(end -0.508 0.9398)
			(stroke
				(width 0.1524)
				(type default)
			)
			(layer "F.SilkS")
		)
		(fp_line
			(start 0.508 -0.9398)
			(end -0.508 -0.9398)
			(stroke
				(width 0.1524)
				(type default)
			)
			(layer "F.SilkS")
		)
		(fp_rect
			(start -0.508 0.9398)
			(end 0.508 -0.9398)
			(stroke
				(width 0)
				(type default)
			)
			(fill no)
			(layer "F.CrtYd")
		)
		(fp_rect
			(start -0.508 0.9398)
			(end 0.508 -0.9398)
			(stroke
				(width 0)
				(type default)
			)
			(fill no)
			(layer "F.Fab")
		)
		(pad "1" smd custom
			(at 0 -0.4445)
			(size 0.1397 0.1397)
			(layers "F.Cu" "F.Mask" "F.Paste")
			(net "Z50_SSD_B1_SMB_DATA_LR")
			(options
				(clearance outline)
				(anchor circle)
			)
			(primitives
				(gr_poly
					(pts
						(arc
							(start -0.1778 -0.2794)
							(mid -0.249642 -0.249642)
							(end -0.2794 -0.1778)
						)
						(arc
							(start -0.2794 0.1778)
							(mid -0.249642 0.249642)
							(end -0.1778 0.2794)
						)
						(arc
							(start 0.1778 0.2794)
							(mid 0.249642 0.249642)
							(end 0.2794 0.1778)
						)
						(arc
							(start 0.2794 -0.1778)
							(mid 0.249642 -0.249642)
							(end 0.1778 -0.2794)
						)
					)
					(width 0)
					(fill yes)
				)
			)
		)
		(pad "2" smd custom
			(at 0 0.4445)
			(size 0.1397 0.1397)
			(layers "F.Cu" "F.Mask" "F.Paste")
			(net "Z50_SSD_B1_SMB_DATA")
			(options
				(clearance outline)
				(anchor circle)
			)
			(primitives
				(gr_poly
					(pts
						(arc
							(start -0.1778 -0.2794)
							(mid -0.249642 -0.249642)
							(end -0.2794 -0.1778)
						)
						(arc
							(start -0.2794 0.1778)
							(mid -0.249642 0.249642)
							(end -0.1778 0.2794)
						)
						(arc
							(start 0.1778 0.2794)
							(mid 0.249642 0.249642)
							(end 0.2794 0.1778)
						)
						(arc
							(start 0.2794 -0.1778)
							(mid 0.249642 -0.249642)
							(end 0.1778 -0.2794)
						)
					)
					(width 0)
					(fill yes)
				)
			)
		)
	)
	(footprint ""
		(layer "F.Cu")
		(at 30.099 -74.93 -90)
		(property "Reference" "U6"
			(at 0 0 270)
			(layer "F.SilkS")
			(hide yes)
			(effects
				(font
					(size 1.27 1.27)
				)
			)
		)
		(property "Value" "TXS0102DCUR-1-GP"
			(at 0 -11.1252 270)
			(unlocked yes)
			(layer "F.Fab")
			(hide yes)
			(effects
				(font
					(size 1.016 1.016)
					(thickness 0.1524)
				)
			)
		)
		(property "Device Type" "SSOIC8-4H36"
			(at 0 -12.6492 270)
			(unlocked yes)
			(layer "F.Fab")
			(hide yes)
			(effects
				(font
					(size 1.016 1.016)
					(thickness 0.1524)
				)
			)
		)
		(duplicate_pad_numbers_are_jumpers no)
		(fp_line
			(start -1.2573 2.1844)
			(end -1.2573 -2.1844)
			(stroke
				(width 0.1524)
				(type default)
			)
			(layer "F.SilkS")
		)
		(fp_line
			(start 1.2573 2.1844)
			(end -1.2573 2.1844)
			(stroke
				(width 0.1524)
				(type default)
			)
			(layer "F.SilkS")
		)
		(fp_line
			(start -1.2954 0.4572)
			(end -1.2954 2.159)
			(stroke
				(width 0.4064)
				(type default)
			)
			(layer "F.SilkS")
		)
		(fp_line
			(start -1.2065 0.2667)
			(end -1.27 0.2667)
			(stroke
				(width 0.1524)
				(type default)
			)
			(layer "F.SilkS")
		)
		(fp_line
			(start -0.9017 -0.0381)
			(end -1.2065 0.2667)
			(stroke
				(width 0.1524)
				(type default)
			)
			(layer "F.SilkS")
		)
		(fp_line
			(start -1.2573 -0.3556)
			(end -1.2192 -0.3556)
			(stroke
				(width 0.1524)
				(type default)
			)
			(layer "F.SilkS")
		)
		(fp_line
			(start -1.2192 -0.3556)
			(end -0.9017 -0.0381)
			(stroke
				(width 0.1524)
				(type default)
			)
			(layer "F.SilkS")
		)
		(fp_line
			(start -1.2573 -2.1844)
			(end 1.2573 -2.1844)
			(stroke
				(width 0.1524)
				(type default)
			)
			(layer "F.SilkS")
		)
		(fp_line
			(start 1.2573 -2.1844)
			(end 1.2573 2.1844)
			(stroke
				(width 0.1524)
				(type default)
			)
			(layer "F.SilkS")
		)
		(fp_poly
			(pts
				(xy -1.5113 2.4384) (xy 1.5113 2.4384) (xy 1.5113 -2.4384) (xy -1.5113 -2.4384)
			)
			(stroke
				(width 0)
				(type default)
			)
			(fill no)
			(layer "F.CrtYd")
		)
		(fp_poly
			(pts
				(xy -1.5113 -2.4384) (xy 1.5113 -2.4384) (xy 1.5113 2.4384) (xy -1.5113 2.4384)
			)
			(stroke
				(width 0)
				(type default)
			)
			(fill no)
			(layer "F.Fab")
		)
		(pad "1" smd rect
			(at -0.75057 1.1684 270)
			(size 0.3048 1.524)
			(layers "F.Cu" "F.Mask" "F.Paste")
			(net "Z50_SSD_B1_SMB_CLK_LL")
		)
		(pad "2" smd rect
			(at -0.25019 1.1684 270)
			(size 0.3048 1.524)
			(layers "F.Cu" "F.Mask" "F.Paste")
			(net "GND")
		)
		(pad "3" smd rect
			(at 0.25019 1.1684 270)
			(size 0.3048 1.524)
			(layers "F.Cu" "F.Mask" "F.Paste")
			(net "P1V8_PWR")
		)
		(pad "4" smd rect
			(at 0.75057 1.1684 270)
			(size 0.3048 1.524)
			(layers "F.Cu" "F.Mask" "F.Paste")
			(net "Z50_SSD_B1_SMB_CLK_LR")
		)
		(pad "5" smd rect
			(at 0.75057 -1.1684 270)
			(size 0.3048 1.524)
			(layers "F.Cu" "F.Mask" "F.Paste")
			(net "Z50_SSD_B1_SMB_DATA_LR")
		)
		(pad "6" smd rect
			(at 0.25019 -1.1684 270)
			(size 0.3048 1.524)
			(layers "F.Cu" "F.Mask" "F.Paste")
			(net "SSD_B1_SMB_OE")
		)
		(pad "7" smd rect
			(at -0.25019 -1.1684 270)
			(size 0.3048 1.524)
			(layers "F.Cu" "F.Mask" "F.Paste")
			(net "P3V3_DPB")
		)
		(pad "8" smd rect
			(at -0.75057 -1.1684 270)
			(size 0.3048 1.524)
			(layers "F.Cu" "F.Mask" "F.Paste")
			(net "Z50_SSD_B1_SMB_DATA_LL")
		)
	)
	(footprint ""
		(layer "F.Cu")
		(at 49.784 -85.979 180)
		(property "Reference" "PC30"
			(at 0 0 180)
			(layer "F.SilkS")
			(hide yes)
			(effects
				(font
					(size 1.27 1.27)
				)
			)
		)
		(property "Value" "SC2K2P50V3KX-GP"
			(at 0 -2.8194 180)
			(unlocked yes)
			(layer "F.Fab")
			(hide yes)
			(effects
				(font
					(size 1.016 1.016)
					(thickness 0.1524)
				)
			)
		)
		(property "Device Type" "C603"
			(at 0 -4.3434 180)
			(unlocked yes)
			(layer "F.Fab")
			(hide yes)
			(effects
				(font
					(size 1.016 1.016)
					(thickness 0.1524)
				)
			)
		)
		(duplicate_pad_numbers_are_jumpers no)
		(fp_line
			(start 0.508 0)
			(end -0.508 0)
			(stroke
				(width 0.2032)
				(type default)
			)
			(layer "F.SilkS")
		)
		(fp_rect
			(start -0.5842 1.3335)
			(end 0.5842 -1.3335)
			(stroke
				(width 0)
				(type default)
			)
			(fill no)
			(layer "F.CrtYd")
		)
		(fp_rect
			(start -0.5842 1.3335)
			(end 0.5842 -1.3335)
			(stroke
				(width 0)
				(type default)
			)
			(fill no)
			(layer "F.Fab")
		)
		(pad "1" smd custom
			(at 0 -0.762 180)
			(size 0.2159 0.2159)
			(layers "F.Cu" "F.Mask" "F.Paste")
			(net "P3V3_DEV_LL")
			(options
				(clearance outline)
				(anchor circle)
			)
			(primitives
				(gr_poly
					(pts
						(arc
							(start -0.3302 -0.4318)
							(mid -0.402042 -0.402042)
							(end -0.4318 -0.3302)
						)
						(arc
							(start -0.4318 0.3302)
							(mid -0.402042 0.402042)
							(end -0.3302 0.4318)
						)
						(arc
							(start 0.3302 0.4318)
							(mid 0.402042 0.402042)
							(end 0.4318 0.3302)
						)
						(arc
							(start 0.4318 -0.3302)
							(mid 0.402042 -0.402042)
							(end 0.3302 -0.4318)
						)
					)
					(width 0)
					(fill yes)
				)
			)
		)
		(pad "2" smd custom
			(at 0 0.762 180)
			(size 0.2159 0.2159)
			(layers "F.Cu" "F.Mask" "F.Paste")
			(net "P3V3_DEV_SNB")
			(options
				(clearance outline)
				(anchor circle)
			)
			(primitives
				(gr_poly
					(pts
						(arc
							(start -0.3302 -0.4318)
							(mid -0.402042 -0.402042)
							(end -0.4318 -0.3302)
						)
						(arc
							(start -0.4318 0.3302)
							(mid -0.402042 0.402042)
							(end -0.3302 0.4318)
						)
						(arc
							(start 0.3302 0.4318)
							(mid 0.402042 0.402042)
							(end 0.4318 0.3302)
						)
						(arc
							(start 0.4318 -0.3302)
							(mid 0.402042 -0.402042)
							(end 0.3302 -0.4318)
						)
					)
					(width 0)
					(fill yes)
				)
			)
		)
	)
	(footprint ""
		(layer "F.Cu")
		(at 67.449954 -26.439876 -90)
		(property "Reference" "SSD_B1"
			(at 0 0 270)
			(layer "F.SilkS")
			(hide yes)
			(effects
				(font
					(size 1.27 1.27)
				)
			)
		)
		(property "Value" "SKT-MINI75P-11-GP"
			(at 12.6619 2.2733 270)
			(unlocked yes)
			(layer "F.Fab")
			(hide yes)
			(effects
				(font
					(size 1.016 1.016)
					(thickness 0.1524)
				)
			)
		)
		(property "Device Type" "MDT580M01001"
			(at 12.6619 0.7493 270)
			(unlocked yes)
			(layer "F.Fab")
			(hide yes)
			(effects
				(font
					(size 1.016 1.016)
					(thickness 0.1524)
				)
			)
		)
		(duplicate_pad_numbers_are_jumpers no)
		(fp_line
			(start -11.2522 3.302)
			(end -11.2522 -6.2992)
			(stroke
				(width 0.1524)
				(type default)
			)
			(layer "F.SilkS")
		)
		(fp_line
			(start 11.2522 3.302)
			(end -11.2522 3.302)
			(stroke
				(width 0.1524)
				(type default)
			)
			(layer "F.SilkS")
		)
		(fp_line
			(start -11.2522 -6.2992)
			(end 11.2522 -6.2992)
			(stroke
				(width 0.1524)
				(type default)
			)
			(layer "F.SilkS")
		)
		(fp_line
			(start 11.2522 -6.2992)
			(end 11.2522 3.302)
			(stroke
				(width 0.1524)
				(type default)
			)
			(layer "F.SilkS")
		)
		(fp_line
			(start -9.525 -6.3881)
			(end -9.017 -6.3881)
			(stroke
				(width 0.3302)
				(type default)
			)
			(layer "F.SilkS")
		)
		(fp_poly
			(pts
				(xy -9.273794 -6.315202) (xy -8.841994 -6.747002) (xy -9.705594 -6.747002)
			)
			(stroke
				(width 0)
				(type default)
			)
			(fill yes)
			(layer "F.SilkS")
		)
		(fp_rect
			(start -10.9982 2.8448)
			(end 10.9982 -5.6896)
			(stroke
				(width 0)
				(type default)
			)
			(fill no)
			(layer "F.CrtYd")
		)
		(fp_poly
			(pts
				(xy -11.5062 3.556) (xy -11.5062 -6.5532) (xy 11.5062 -6.5532) (xy 11.5062 -0.00635) (xy 10.9982 -0.00635)
				(xy 10.9982 -5.6896) (xy -10.9982 -5.6896) (xy -10.9982 2.8448) (xy 10.9982 2.8448) (xy 10.9982 0.00635)
				(xy 11.5062 0.00635) (xy 11.5062 3.556)
			)
			(stroke
				(width 0)
				(type default)
			)
			(fill no)
			(layer "F.CrtYd")
		)
		(fp_rect
			(start -11.5062 3.556)
			(end 11.5062 -6.5532)
			(stroke
				(width 0)
				(type default)
			)
			(fill no)
			(layer "F.Fab")
		)
		(pad "" np_thru_hole circle
			(at -9.99998 0 270)
			(size 0.254 0.254)
			(drill 1.1176)
			(layers "*.Cu" "*.Mask")
			(clearance 0.7874)
			(thermal_gap 0.7874)
		)
		(pad "" np_thru_hole circle
			(at 9.99998 0 270)
			(size 0.254 0.254)
			(drill 1.6002)
			(layers "*.Cu" "*.Mask")
			(clearance 1.0287)
			(thermal_gap 1.0287)
		)
		(pad "1" smd rect
			(at -9.249918 -5.275072 270)
			(size 0.3048 1.5494)
			(layers "F.Cu" "F.Mask" "F.Paste")
			(net "Z50_SSD_B_PRESENT_R#")
		)
		(pad "2" smd rect
			(at -8.999982 2.275078 270)
			(size 0.3048 1.5494)
			(layers "F.Cu" "F.Mask" "F.Paste")
			(net "P3V3_PWR")
		)
		(pad "3" smd rect
			(at -8.750046 -5.275072 270)
			(size 0.3048 1.5494)
			(layers "F.Cu" "F.Mask" "F.Paste")
			(net "GND")
		)
		(pad "4" smd rect
			(at -8.50011 2.275078 270)
			(size 0.3048 1.5494)
			(layers "F.Cu" "F.Mask" "F.Paste")
			(net "P3V3_PWR")
		)
		(pad "5" smd rect
			(at -8.24992 -5.275072 270)
			(size 0.3048 1.5494)
			(layers "F.Cu" "F.Mask" "F.Paste")
			(net "Net_117")
		)
		(pad "6" smd rect
			(at -7.999984 2.275078 270)
			(size 0.3048 1.5494)
			(layers "F.Cu" "F.Mask" "F.Paste")
			(net "Net_124")
		)
		(pad "7" smd rect
			(at -7.750048 -5.275072 270)
			(size 0.3048 1.5494)
			(layers "F.Cu" "F.Mask" "F.Paste")
			(net "Net_118")
		)
		(pad "8" smd rect
			(at -7.500112 2.275078 270)
			(size 0.3048 1.5494)
			(layers "F.Cu" "F.Mask" "F.Paste")
			(net "Net_125")
		)
		(pad "9" smd rect
			(at -7.249922 -5.275072 270)
			(size 0.3048 1.5494)
			(layers "F.Cu" "F.Mask" "F.Paste")
			(net "GND")
		)
		(pad "10" smd rect
			(at -6.999986 2.275078 270)
			(size 0.3048 1.5494)
			(layers "F.Cu" "F.Mask" "F.Paste")
			(net "Z50_SSD_B_R_ACT#")
		)
		(pad "11" smd rect
			(at -6.75005 -5.275072 270)
			(size 0.3048 1.5494)
			(layers "F.Cu" "F.Mask" "F.Paste")
			(net "Net_119")
		)
		(pad "12" smd rect
			(at -6.500114 2.275078 270)
			(size 0.3048 1.5494)
			(layers "F.Cu" "F.Mask" "F.Paste")
			(net "P3V3_PWR")
		)
		(pad "13" smd rect
			(at -6.249924 -5.275072 270)
			(size 0.3048 1.5494)
			(layers "F.Cu" "F.Mask" "F.Paste")
			(net "Net_120")
		)
		(pad "14" smd rect
			(at -5.999988 2.275078 270)
			(size 0.3048 1.5494)
			(layers "F.Cu" "F.Mask" "F.Paste")
			(net "P3V3_PWR")
		)
		(pad "15" smd rect
			(at -5.750052 -5.275072 270)
			(size 0.3048 1.5494)
			(layers "F.Cu" "F.Mask" "F.Paste")
			(net "GND")
		)
		(pad "16" smd rect
			(at -5.500116 2.275078 270)
			(size 0.3048 1.5494)
			(layers "F.Cu" "F.Mask" "F.Paste")
			(net "P3V3_PWR")
		)
		(pad "17" smd rect
			(at -5.249926 -5.275072 270)
			(size 0.3048 1.5494)
			(layers "F.Cu" "F.Mask" "F.Paste")
			(net "Net_121")
		)
		(pad "18" smd rect
			(at -4.99999 2.275078 270)
			(size 0.3048 1.5494)
			(layers "F.Cu" "F.Mask" "F.Paste")
			(net "P3V3_PWR")
		)
		(pad "19" smd rect
			(at -4.750054 -5.275072 270)
			(size 0.3048 1.5494)
			(layers "F.Cu" "F.Mask" "F.Paste")
			(net "Net_122")
		)
		(pad "20" smd rect
			(at -4.500118 2.275078 270)
			(size 0.3048 1.5494)
			(layers "F.Cu" "F.Mask" "F.Paste")
			(net "Net_126")
		)
		(pad "21" smd rect
			(at -4.249928 -5.275072 270)
			(size 0.3048 1.5494)
			(layers "F.Cu" "F.Mask" "F.Paste")
			(net "GND")
		)
		(pad "22" smd rect
			(at -3.999992 2.275078 270)
			(size 0.3048 1.5494)
			(layers "F.Cu" "F.Mask" "F.Paste")
			(net "Net_127")
		)
		(pad "23" smd rect
			(at -3.750056 -5.275072 270)
			(size 0.3048 1.5494)
			(layers "F.Cu" "F.Mask" "F.Paste")
			(net "Net_123")
		)
		(pad "24" smd rect
			(at -3.50012 2.275078 270)
			(size 0.3048 1.5494)
			(layers "F.Cu" "F.Mask" "F.Paste")
			(net "Net_107")
		)
		(pad "25" smd rect
			(at -3.24993 -5.275072 270)
			(size 0.3048 1.5494)
			(layers "F.Cu" "F.Mask" "F.Paste")
			(net "Net_106")
		)
		(pad "26" smd rect
			(at -2.999994 2.275078 270)
			(size 0.3048 1.5494)
			(layers "F.Cu" "F.Mask" "F.Paste")
			(net "Net_108")
		)
		(pad "27" smd rect
			(at -2.750058 -5.275072 270)
			(size 0.3048 1.5494)
			(layers "F.Cu" "F.Mask" "F.Paste")
			(net "GND")
		)
		(pad "28" smd rect
			(at -2.500122 2.275078 270)
			(size 0.3048 1.5494)
			(layers "F.Cu" "F.Mask" "F.Paste")
			(net "Net_109")
		)
		(pad "29" smd rect
			(at -2.249932 -5.275072 270)
			(size 0.3048 1.5494)
			(layers "F.Cu" "F.Mask" "F.Paste")
			(net "D85_PCIE_B_RX0_N")
		)
		(pad "30" smd rect
			(at -1.999996 2.275078 270)
			(size 0.3048 1.5494)
			(layers "F.Cu" "F.Mask" "F.Paste")
			(net "Net_110")
		)
		(pad "31" smd rect
			(at -1.75006 -5.275072 270)
			(size 0.3048 1.5494)
			(layers "F.Cu" "F.Mask" "F.Paste")
			(net "D85_PCIE_B_RX0_P")
		)
		(pad "32" smd rect
			(at -1.500124 2.275078 270)
			(size 0.3048 1.5494)
			(layers "F.Cu" "F.Mask" "F.Paste")
			(net "Net_111")
		)
		(pad "33" smd rect
			(at -1.249934 -5.275072 270)
			(size 0.3048 1.5494)
			(layers "F.Cu" "F.Mask" "F.Paste")
			(net "GND")
		)
		(pad "34" smd rect
			(at -0.999998 2.275078 270)
			(size 0.3048 1.5494)
			(layers "F.Cu" "F.Mask" "F.Paste")
			(net "Net_112")
		)
		(pad "35" smd rect
			(at -0.750062 -5.275072 270)
			(size 0.3048 1.5494)
			(layers "F.Cu" "F.Mask" "F.Paste")
			(net "D85_PCIE_B_TX0_P")
		)
		(pad "36" smd rect
			(at -0.500126 2.275078 270)
			(size 0.3048 1.5494)
			(layers "F.Cu" "F.Mask" "F.Paste")
			(net "Net_113")
		)
		(pad "37" smd rect
			(at -0.249936 -5.275072 270)
			(size 0.3048 1.5494)
			(layers "F.Cu" "F.Mask" "F.Paste")
			(net "D85_PCIE_B_TX0_N")
		)
		(pad "38" smd rect
			(at 0 2.275078 270)
			(size 0.3048 1.5494)
			(layers "F.Cu" "F.Mask" "F.Paste")
			(net "Net_114")
		)
		(pad "39" smd rect
			(at 0.249936 -5.275072 270)
			(size 0.3048 1.5494)
			(layers "F.Cu" "F.Mask" "F.Paste")
			(net "GND")
		)
		(pad "40" smd rect
			(at 0.500126 2.275078 270)
			(size 0.3048 1.5494)
			(layers "F.Cu" "F.Mask" "F.Paste")
			(net "Z50_SSD_B1_SMB_CLK")
		)
		(pad "41" smd rect
			(at 0.750062 -5.275072 270)
			(size 0.3048 1.5494)
			(layers "F.Cu" "F.Mask" "F.Paste")
			(net "D85_PCIE_B_RX1_N")
		)
		(pad "42" smd rect
			(at 0.999998 2.275078 270)
			(size 0.3048 1.5494)
			(layers "F.Cu" "F.Mask" "F.Paste")
			(net "Z50_SSD_B1_SMB_DATA")
		)
		(pad "43" smd rect
			(at 1.249934 -5.275072 270)
			(size 0.3048 1.5494)
			(layers "F.Cu" "F.Mask" "F.Paste")
			(net "D85_PCIE_B_RX1_P")
		)
		(pad "44" smd rect
			(at 1.500124 2.275078 270)
			(size 0.3048 1.5494)
			(layers "F.Cu" "F.Mask" "F.Paste")
			(net "Z50_SSD_B1_ALERT#")
		)
		(pad "45" smd rect
			(at 1.75006 -5.275072 270)
			(size 0.3048 1.5494)
			(layers "F.Cu" "F.Mask" "F.Paste")
			(net "GND")
		)
		(pad "46" smd rect
			(at 1.999996 2.275078 270)
			(size 0.3048 1.5494)
			(layers "F.Cu" "F.Mask" "F.Paste")
			(net "Net_115")
		)
		(pad "47" smd rect
			(at 2.249932 -5.275072 270)
			(size 0.3048 1.5494)
			(layers "F.Cu" "F.Mask" "F.Paste")
			(net "D85_PCIE_B_TX1_P")
		)
		(pad "48" smd rect
			(at 2.500122 2.275078 270)
			(size 0.3048 1.5494)
			(layers "F.Cu" "F.Mask" "F.Paste")
			(net "Net_116")
		)
		(pad "49" smd rect
			(at 2.750058 -5.275072 270)
			(size 0.3048 1.5494)
			(layers "F.Cu" "F.Mask" "F.Paste")
			(net "D85_PCIE_B_TX1_N")
		)
		(pad "50" smd rect
			(at 2.999994 2.275078 270)
			(size 0.3048 1.5494)
			(layers "F.Cu" "F.Mask" "F.Paste")
			(net "Z50_DEV_RST#")
		)
		(pad "51" smd rect
			(at 3.24993 -5.275072 270)
			(size 0.3048 1.5494)
			(layers "F.Cu" "F.Mask" "F.Paste")
			(net "GND")
		)
		(pad "52" smd rect
			(at 3.50012 2.275078 270)
			(size 0.3048 1.5494)
			(layers "F.Cu" "F.Mask" "F.Paste")
			(net "Z50_SSD_B1_CLKREQ#")
		)
		(pad "53" smd rect
			(at 3.750056 -5.275072 270)
			(size 0.3048 1.5494)
			(layers "F.Cu" "F.Mask" "F.Paste")
			(net "D85_PCIE_B_REFCLK_N")
		)
		(pad "54" smd rect
			(at 3.999992 2.275078 270)
			(size 0.3048 1.5494)
			(layers "F.Cu" "F.Mask" "F.Paste")
			(net "Net_103")
		)
		(pad "55" smd rect
			(at 4.249928 -5.275072 270)
			(size 0.3048 1.5494)
			(layers "F.Cu" "F.Mask" "F.Paste")
			(net "D85_PCIE_B_REFCLK_P")
		)
		(pad "56" smd rect
			(at 4.500118 2.275078 270)
			(size 0.3048 1.5494)
			(layers "F.Cu" "F.Mask" "F.Paste")
			(net "SSD_B1_MFG_DATA_TP")
		)
		(pad "57" smd rect
			(at 4.750054 -5.275072 270)
			(size 0.3048 1.5494)
			(layers "F.Cu" "F.Mask" "F.Paste")
			(net "GND")
		)
		(pad "58" smd rect
			(at 4.99999 2.275078 270)
			(size 0.3048 1.5494)
			(layers "F.Cu" "F.Mask" "F.Paste")
			(net "SSD_B1_MFG_CLK_TP")
		)
		(pad "67" smd rect
			(at 7.249922 -5.275072 270)
			(size 0.3048 1.5494)
			(layers "F.Cu" "F.Mask" "F.Paste")
			(net "Net_101")
		)
		(pad "68" smd rect
			(at 7.500112 2.275078 270)
			(size 0.3048 1.5494)
			(layers "F.Cu" "F.Mask" "F.Paste")
			(net "Net_104")
		)
		(pad "69" smd rect
			(at 7.750048 -5.275072 270)
			(size 0.3048 1.5494)
			(layers "F.Cu" "F.Mask" "F.Paste")
			(net "Net_102")
		)
		(pad "70" smd rect
			(at 7.999984 2.275078 270)
			(size 0.3048 1.5494)
			(layers "F.Cu" "F.Mask" "F.Paste")
			(net "P3V3_PWR")
		)
		(pad "71" smd rect
			(at 8.24992 -5.275072 270)
			(size 0.3048 1.5494)
			(layers "F.Cu" "F.Mask" "F.Paste")
			(net "GND")
		)
		(pad "72" smd rect
			(at 8.50011 2.275078 270)
			(size 0.3048 1.5494)
			(layers "F.Cu" "F.Mask" "F.Paste")
			(net "P3V3_PWR")
		)
		(pad "73" smd rect
			(at 8.750046 -5.275072 270)
			(size 0.3048 1.5494)
			(layers "F.Cu" "F.Mask" "F.Paste")
			(net "GND")
		)
		(pad "74" smd rect
			(at 8.999982 2.275078 270)
			(size 0.3048 1.5494)
			(layers "F.Cu" "F.Mask" "F.Paste")
			(net "P3V3_PWR")
		)
		(pad "75" smd rect
			(at 9.249918 -5.275072 270)
			(size 0.3048 1.5494)
			(layers "F.Cu" "F.Mask" "F.Paste")
			(net "GND")
		)
		(pad "76" smd rect
			(at -10.349992 -4.500118 270)
			(size 1.1938 2.7432)
			(layers "F.Cu" "F.Mask" "F.Paste")
			(net "GND")
		)
		(pad "77" smd rect
			(at 10.349992 -4.500118 270)
			(size 1.1938 2.7432)
			(layers "F.Cu" "F.Mask" "F.Paste")
			(net "GND")
		)
		(zone
			(layer "F.Cu")
			(hatch none 0.5)
			(connect_pads
				(clearance 0)
			)
			(min_thickness 0.25)
			(keepout
				(tracks allowed)
				(vias not_allowed)
				(pads allowed)
				(copperpour not_allowed)
				(footprints allowed)
			)
			(placement
				(enabled no)
				(sheetname "")
			)
			(fill
				(thermal_gap 0.5)
				(thermal_bridge_width 0.5)
				(island_removal_mode 0)
			)
			(polygon
				(pts
					(xy 65.949576 -35.592258) (xy 65.949576 -21.287486) (xy 66.457576 -21.287486) (xy 66.457576 -35.592258)
				)
			)
		)
		(zone
			(layer "F.Cu")
			(hatch none 0.5)
			(connect_pads
				(clearance 0)
			)
			(min_thickness 0.25)
			(keepout
				(tracks allowed)
				(vias not_allowed)
				(pads allowed)
				(copperpour not_allowed)
				(footprints allowed)
			)
			(placement
				(enabled no)
				(sheetname "")
			)
			(fill
				(thermal_gap 0.5)
				(thermal_bridge_width 0.5)
				(island_removal_mode 0)
			)
			(polygon
				(pts
					(xy 65.949576 -19.092164) (xy 65.949576 -17.287494) (xy 66.457576 -17.287494) (xy 66.457576 -19.092164)
				)
			)
		)
		(zone
			(layer "F.Cu")
			(hatch none 0.5)
			(connect_pads
				(clearance 0)
			)
			(min_thickness 0.25)
			(keepout
				(tracks allowed)
				(vias not_allowed)
				(pads allowed)
				(copperpour not_allowed)
				(footprints allowed)
			)
			(placement
				(enabled no)
				(sheetname "")
			)
			(fill
				(thermal_gap 0.5)
				(thermal_bridge_width 0.5)
				(island_removal_mode 0)
			)
			(polygon
				(pts
					(xy 71.442326 -35.842194) (xy 71.442326 -21.537422) (xy 71.950326 -21.537422) (xy 71.950326 -35.842194)
				)
			)
		)
		(zone
			(layer "F.Cu")
			(hatch none 0.5)
			(connect_pads
				(clearance 0)
			)
			(min_thickness 0.25)
			(keepout
				(tracks allowed)
				(vias not_allowed)
				(pads allowed)
				(copperpour not_allowed)
				(footprints allowed)
			)
			(placement
				(enabled no)
				(sheetname "")
			)
			(fill
				(thermal_gap 0.5)
				(thermal_bridge_width 0.5)
				(island_removal_mode 0)
			)
			(polygon
				(pts
					(xy 71.442326 -19.342354) (xy 71.442326 -17.037558) (xy 71.950326 -17.037558) (xy 71.950326 -19.342354)
				)
			)
		)
		(zone
			(layers "F.Cu" "B.Cu" "In1.Cu" "In2.Cu" "In3.Cu" "In4.Cu" "In5.Cu" "In6.Cu")
			(hatch none 0.5)
			(connect_pads
				(clearance 0)
			)
			(min_thickness 0.25)
			(keepout
				(tracks not_allowed)
				(vias allowed)
				(pads allowed)
				(copperpour not_allowed)
				(footprints allowed)
			)
			(placement
				(enabled no)
				(sheetname "")
			)
			(fill
				(thermal_gap 0.5)
				(thermal_bridge_width 0.5)
				(island_removal_mode 0)
			)
			(polygon
				(pts
					(arc
						(start 68.313554 -36.439856)
						(mid 66.586354 -36.439856)
						(end 68.313554 -36.439856)
					)
				)
			)
		)
		(zone
			(layers "F.Cu" "B.Cu" "In1.Cu" "In2.Cu" "In3.Cu" "In4.Cu" "In5.Cu" "In6.Cu")
			(hatch none 0.5)
			(connect_pads
				(clearance 0)
			)
			(min_thickness 0.25)
			(keepout
				(tracks not_allowed)
				(vias allowed)
				(pads allowed)
				(copperpour not_allowed)
				(footprints allowed)
			)
			(placement
				(enabled no)
				(sheetname "")
			)
			(fill
				(thermal_gap 0.5)
				(thermal_bridge_width 0.5)
				(island_removal_mode 0)
			)
			(polygon
				(pts
					(arc
						(start 68.554854 -16.439896)
						(mid 66.345054 -16.439896)
						(end 68.554854 -16.439896)
					)
				)
			)
		)
	)
	(footprint ""
		(layer "F.Cu")
		(at 55.753 -82.296 90)
		(property "Reference" "PL3"
			(at 0 0 90)
			(layer "F.SilkS")
			(hide yes)
			(effects
				(font
					(size 1.27 1.27)
				)
			)
		)
		(property "Value" "IND-1D5UH-107-GP"
			(at -0.509016 -7.542784 90)
			(unlocked yes)
			(layer "F.Fab")
			(hide yes)
			(effects
				(font
					(size 1.016 1.016)
					(thickness 0.1524)
				)
			)
		)
		(property "Device Type" "L7774-1711H197"
			(at -0.509016 -9.066784 90)
			(unlocked yes)
			(layer "F.Fab")
			(hide yes)
			(effects
				(font
					(size 1.016 1.016)
					(thickness 0.1524)
				)
			)
		)
		(duplicate_pad_numbers_are_jumpers no)
		(fp_line
			(start 3.9497 -4.7371)
			(end 3.9497 4.7371)
			(stroke
				(width 0.1524)
				(type default)
			)
			(layer "F.SilkS")
		)
		(fp_line
			(start -3.9497 -4.7371)
			(end 3.9497 -4.7371)
			(stroke
				(width 0.1524)
				(type default)
			)
			(layer "F.SilkS")
		)
		(fp_line
			(start 3.9497 4.7371)
			(end -3.9497 4.7371)
			(stroke
				(width 0.1524)
				(type default)
			)
			(layer "F.SilkS")
		)
		(fp_line
			(start -3.9497 4.7371)
			(end -3.9497 -4.7371)
			(stroke
				(width 0.1524)
				(type default)
			)
			(layer "F.SilkS")
		)
		(fp_rect
			(start -3.6957 3.8481)
			(end 3.6957 -3.8481)
			(stroke
				(width 0)
				(type default)
			)
			(fill no)
			(layer "F.CrtYd")
		)
		(fp_poly
			(pts
				(xy -4.2037 4.8133) (xy -4.2037 -2.208022) (xy -3.6957 -2.208022) (xy -3.6957 3.8481) (xy 3.6957 3.8481)
				(xy 3.6957 -3.8481) (xy -3.6957 -3.8481) (xy -3.6957 -2.208276) (xy -4.2037 -2.208276) (xy -4.2037 -4.8133)
				(xy 4.2037 -4.8133) (xy 4.2037 4.8133)
			)
			(stroke
				(width 0)
				(type default)
			)
			(fill no)
			(layer "F.CrtYd")
		)
		(fp_rect
			(start -4.2037 4.8133)
			(end 4.2037 -4.8133)
			(stroke
				(width 0)
				(type default)
			)
			(fill no)
			(layer "F.Fab")
		)
		(pad "1" smd rect
			(at 0 -3.189478 90)
			(size 1.3462 2.5908)
			(layers "F.Cu" "F.Mask" "F.Paste")
			(net "P3V3_DEV_LL")
		)
		(pad "2" smd rect
			(at 0 3.189478 90)
			(size 1.3462 2.5908)
			(layers "F.Cu" "F.Mask" "F.Paste")
			(net "P3V3_PWR")
		)
	)
	(footprint ""
		(layer "F.Cu")
		(at 31.369 -78.74)
		(property "Reference" "R41"
			(at 0 0 0)
			(layer "F.SilkS")
			(hide yes)
			(effects
				(font
					(size 1.27 1.27)
				)
			)
		)
		(property "Value" "0R2J-2-GP"
			(at 0.064008 -3.993896 0)
			(unlocked yes)
			(layer "F.Fab")
			(hide yes)
			(effects
				(font
					(size 1.016 1.016)
					(thickness 0.1524)
				)
			)
		)
		(property "Device Type" "R402H16"
			(at 0.064008 -5.517896 0)
			(unlocked yes)
			(layer "F.Fab")
			(hide yes)
			(effects
				(font
					(size 1.016 1.016)
					(thickness 0.1524)
				)
			)
		)
		(duplicate_pad_numbers_are_jumpers no)
		(fp_line
			(start -0.508 -0.9398)
			(end -0.508 0.9398)
			(stroke
				(width 0.1524)
				(type default)
			)
			(layer "F.SilkS")
		)
		(fp_line
			(start 0.508 -0.9398)
			(end -0.508 -0.9398)
			(stroke
				(width 0.1524)
				(type default)
			)
			(layer "F.SilkS")
		)
		(fp_rect
			(start -0.508 0.9398)
			(end 0.508 -0.9398)
			(stroke
				(width 0)
				(type default)
			)
			(fill no)
			(layer "F.CrtYd")
		)
		(fp_rect
			(start -0.508 0.9398)
			(end 0.508 -0.9398)
			(stroke
				(width 0)
				(type default)
			)
			(fill no)
			(layer "F.Fab")
		)
		(pad "1" smd custom
			(at 0 -0.4445)
			(size 0.1397 0.1397)
			(layers "F.Cu" "F.Mask" "F.Paste")
			(net "Z50_SSD_B1_SMB_CLK_R")
			(options
				(clearance outline)
				(anchor circle)
			)
			(primitives
				(gr_poly
					(pts
						(arc
							(start -0.1778 -0.2794)
							(mid -0.249642 -0.249642)
							(end -0.2794 -0.1778)
						)
						(arc
							(start -0.2794 0.1778)
							(mid -0.249642 0.249642)
							(end -0.1778 0.2794)
						)
						(arc
							(start 0.1778 0.2794)
							(mid 0.249642 0.249642)
							(end 0.2794 0.1778)
						)
						(arc
							(start 0.2794 -0.1778)
							(mid 0.249642 -0.249642)
							(end 0.1778 -0.2794)
						)
					)
					(width 0)
					(fill yes)
				)
			)
		)
		(pad "2" smd custom
			(at 0 0.4445)
			(size 0.1397 0.1397)
			(layers "F.Cu" "F.Mask" "F.Paste")
			(net "Z50_SSD_B1_SMB_CLK_LL")
			(options
				(clearance outline)
				(anchor circle)
			)
			(primitives
				(gr_poly
					(pts
						(arc
							(start -0.1778 -0.2794)
							(mid -0.249642 -0.249642)
							(end -0.2794 -0.1778)
						)
						(arc
							(start -0.2794 0.1778)
							(mid -0.249642 0.249642)
							(end -0.1778 0.2794)
						)
						(arc
							(start 0.1778 0.2794)
							(mid 0.249642 0.249642)
							(end 0.2794 0.1778)
						)
						(arc
							(start 0.2794 -0.1778)
							(mid 0.249642 -0.249642)
							(end 0.1778 -0.2794)
						)
					)
					(width 0)
					(fill yes)
				)
			)
		)
	)
	(footprint ""
		(layer "F.Cu")
		(at 74.676 -38.735 180)
		(property "Reference" "R44"
			(at 0 0 180)
			(layer "F.SilkS")
			(hide yes)
			(effects
				(font
					(size 1.27 1.27)
				)
			)
		)
		(property "Value" "47KR2F-GP"
			(at 0.064008 -3.993896 180)
			(unlocked yes)
			(layer "F.Fab")
			(hide yes)
			(effects
				(font
					(size 1.016 1.016)
					(thickness 0.1524)
				)
			)
		)
		(property "Device Type" "R402H16"
			(at 0.064008 -5.517896 180)
			(unlocked yes)
			(layer "F.Fab")
			(hide yes)
			(effects
				(font
					(size 1.016 1.016)
					(thickness 0.1524)
				)
			)
		)
		(duplicate_pad_numbers_are_jumpers no)
		(fp_line
			(start 0.508 -0.9398)
			(end -0.508 -0.9398)
			(stroke
				(width 0.1524)
				(type default)
			)
			(layer "F.SilkS")
		)
		(fp_line
			(start -0.508 -0.9398)
			(end -0.508 0.9398)
			(stroke
				(width 0.1524)
				(type default)
			)
			(layer "F.SilkS")
		)
		(fp_rect
			(start -0.508 0.9398)
			(end 0.508 -0.9398)
			(stroke
				(width 0)
				(type default)
			)
			(fill no)
			(layer "F.CrtYd")
		)
		(fp_rect
			(start -0.508 0.9398)
			(end 0.508 -0.9398)
			(stroke
				(width 0)
				(type default)
			)
			(fill no)
			(layer "F.Fab")
		)
		(pad "1" smd custom
			(at 0 -0.4445 180)
			(size 0.1397 0.1397)
			(layers "F.Cu" "F.Mask" "F.Paste")
			(net "P3V3_DPB")
			(options
				(clearance outline)
				(anchor circle)
			)
			(primitives
				(gr_poly
					(pts
						(arc
							(start -0.1778 -0.2794)
							(mid -0.249642 -0.249642)
							(end -0.2794 -0.1778)
						)
						(arc
							(start -0.2794 0.1778)
							(mid -0.249642 0.249642)
							(end -0.1778 0.2794)
						)
						(arc
							(start 0.1778 0.2794)
							(mid 0.249642 0.249642)
							(end 0.2794 0.1778)
						)
						(arc
							(start 0.2794 -0.1778)
							(mid 0.249642 -0.249642)
							(end 0.1778 -0.2794)
						)
					)
					(width 0)
					(fill yes)
				)
			)
		)
		(pad "2" smd custom
			(at 0 0.4445 180)
			(size 0.1397 0.1397)
			(layers "F.Cu" "F.Mask" "F.Paste")
			(net "Z50_SSD_A_PRSNT#")
			(options
				(clearance outline)
				(anchor circle)
			)
			(primitives
				(gr_poly
					(pts
						(arc
							(start -0.1778 -0.2794)
							(mid -0.249642 -0.249642)
							(end -0.2794 -0.1778)
						)
						(arc
							(start -0.2794 0.1778)
							(mid -0.249642 0.249642)
							(end -0.1778 0.2794)
						)
						(arc
							(start 0.1778 0.2794)
							(mid 0.249642 0.249642)
							(end 0.2794 0.1778)
						)
						(arc
							(start 0.2794 -0.1778)
							(mid 0.249642 -0.249642)
							(end 0.1778 -0.2794)
						)
					)
					(width 0)
					(fill yes)
				)
			)
		)
	)
	(footprint ""
		(layer "F.Cu")
		(at 67.449954 -54.040024 -90)
		(property "Reference" "SSD_A1"
			(at 0 0 270)
			(layer "F.SilkS")
			(hide yes)
			(effects
				(font
					(size 1.27 1.27)
				)
			)
		)
		(property "Value" "SKT-MINI75P-11-GP"
			(at 12.6619 2.2733 270)
			(unlocked yes)
			(layer "F.Fab")
			(hide yes)
			(effects
				(font
					(size 1.016 1.016)
					(thickness 0.1524)
				)
			)
		)
		(property "Device Type" "MDT580M01001"
			(at 12.6619 0.7493 270)
			(unlocked yes)
			(layer "F.Fab")
			(hide yes)
			(effects
				(font
					(size 1.016 1.016)
					(thickness 0.1524)
				)
			)
		)
		(duplicate_pad_numbers_are_jumpers no)
		(fp_line
			(start -11.2522 3.302)
			(end -11.2522 -6.2992)
			(stroke
				(width 0.1524)
				(type default)
			)
			(layer "F.SilkS")
		)
		(fp_line
			(start 11.2522 3.302)
			(end -11.2522 3.302)
			(stroke
				(width 0.1524)
				(type default)
			)
			(layer "F.SilkS")
		)
		(fp_line
			(start -11.2522 -6.2992)
			(end 11.2522 -6.2992)
			(stroke
				(width 0.1524)
				(type default)
			)
			(layer "F.SilkS")
		)
		(fp_line
			(start 11.2522 -6.2992)
			(end 11.2522 3.302)
			(stroke
				(width 0.1524)
				(type default)
			)
			(layer "F.SilkS")
		)
		(fp_line
			(start -9.525 -6.3881)
			(end -9.017 -6.3881)
			(stroke
				(width 0.3302)
				(type default)
			)
			(layer "F.SilkS")
		)
		(fp_poly
			(pts
				(xy -9.273794 -6.315202) (xy -8.841994 -6.747002) (xy -9.705594 -6.747002)
			)
			(stroke
				(width 0)
				(type default)
			)
			(fill yes)
			(layer "F.SilkS")
		)
		(fp_rect
			(start -10.9982 2.8448)
			(end 10.9982 -5.6896)
			(stroke
				(width 0)
				(type default)
			)
			(fill no)
			(layer "F.CrtYd")
		)
		(fp_poly
			(pts
				(xy -11.5062 3.556) (xy -11.5062 -6.5532) (xy 11.5062 -6.5532) (xy 11.5062 -0.00635) (xy 10.9982 -0.00635)
				(xy 10.9982 -5.6896) (xy -10.9982 -5.6896) (xy -10.9982 2.8448) (xy 10.9982 2.8448) (xy 10.9982 0.00635)
				(xy 11.5062 0.00635) (xy 11.5062 3.556)
			)
			(stroke
				(width 0)
				(type default)
			)
			(fill no)
			(layer "F.CrtYd")
		)
		(fp_rect
			(start -11.5062 3.556)
			(end 11.5062 -6.5532)
			(stroke
				(width 0)
				(type default)
			)
			(fill no)
			(layer "F.Fab")
		)
		(pad "" np_thru_hole circle
			(at -9.99998 0 270)
			(size 0.254 0.254)
			(drill 1.1176)
			(layers "*.Cu" "*.Mask")
			(clearance 0.7874)
			(thermal_gap 0.7874)
		)
		(pad "" np_thru_hole circle
			(at 9.99998 0 270)
			(size 0.254 0.254)
			(drill 1.6002)
			(layers "*.Cu" "*.Mask")
			(clearance 1.0287)
			(thermal_gap 1.0287)
		)
		(pad "1" smd rect
			(at -9.249918 -5.275072 270)
			(size 0.3048 1.5494)
			(layers "F.Cu" "F.Mask" "F.Paste")
			(net "Z50_SSD_A_PRESENT_R#")
		)
		(pad "2" smd rect
			(at -8.999982 2.275078 270)
			(size 0.3048 1.5494)
			(layers "F.Cu" "F.Mask" "F.Paste")
			(net "P3V3_PWR")
		)
		(pad "3" smd rect
			(at -8.750046 -5.275072 270)
			(size 0.3048 1.5494)
			(layers "F.Cu" "F.Mask" "F.Paste")
			(net "GND")
		)
		(pad "4" smd rect
			(at -8.50011 2.275078 270)
			(size 0.3048 1.5494)
			(layers "F.Cu" "F.Mask" "F.Paste")
			(net "P3V3_PWR")
		)
		(pad "5" smd rect
			(at -8.24992 -5.275072 270)
			(size 0.3048 1.5494)
			(layers "F.Cu" "F.Mask" "F.Paste")
			(net "Net_145")
		)
		(pad "6" smd rect
			(at -7.999984 2.275078 270)
			(size 0.3048 1.5494)
			(layers "F.Cu" "F.Mask" "F.Paste")
			(net "Net_152")
		)
		(pad "7" smd rect
			(at -7.750048 -5.275072 270)
			(size 0.3048 1.5494)
			(layers "F.Cu" "F.Mask" "F.Paste")
			(net "Net_146")
		)
		(pad "8" smd rect
			(at -7.500112 2.275078 270)
			(size 0.3048 1.5494)
			(layers "F.Cu" "F.Mask" "F.Paste")
			(net "Net_153")
		)
		(pad "9" smd rect
			(at -7.249922 -5.275072 270)
			(size 0.3048 1.5494)
			(layers "F.Cu" "F.Mask" "F.Paste")
			(net "GND")
		)
		(pad "10" smd rect
			(at -6.999986 2.275078 270)
			(size 0.3048 1.5494)
			(layers "F.Cu" "F.Mask" "F.Paste")
			(net "Z50_SSD_A_R_ACT#")
		)
		(pad "11" smd rect
			(at -6.75005 -5.275072 270)
			(size 0.3048 1.5494)
			(layers "F.Cu" "F.Mask" "F.Paste")
			(net "Net_147")
		)
		(pad "12" smd rect
			(at -6.500114 2.275078 270)
			(size 0.3048 1.5494)
			(layers "F.Cu" "F.Mask" "F.Paste")
			(net "P3V3_PWR")
		)
		(pad "13" smd rect
			(at -6.249924 -5.275072 270)
			(size 0.3048 1.5494)
			(layers "F.Cu" "F.Mask" "F.Paste")
			(net "Net_148")
		)
		(pad "14" smd rect
			(at -5.999988 2.275078 270)
			(size 0.3048 1.5494)
			(layers "F.Cu" "F.Mask" "F.Paste")
			(net "P3V3_PWR")
		)
		(pad "15" smd rect
			(at -5.750052 -5.275072 270)
			(size 0.3048 1.5494)
			(layers "F.Cu" "F.Mask" "F.Paste")
			(net "GND")
		)
		(pad "16" smd rect
			(at -5.500116 2.275078 270)
			(size 0.3048 1.5494)
			(layers "F.Cu" "F.Mask" "F.Paste")
			(net "P3V3_PWR")
		)
		(pad "17" smd rect
			(at -5.249926 -5.275072 270)
			(size 0.3048 1.5494)
			(layers "F.Cu" "F.Mask" "F.Paste")
			(net "Net_149")
		)
		(pad "18" smd rect
			(at -4.99999 2.275078 270)
			(size 0.3048 1.5494)
			(layers "F.Cu" "F.Mask" "F.Paste")
			(net "P3V3_PWR")
		)
		(pad "19" smd rect
			(at -4.750054 -5.275072 270)
			(size 0.3048 1.5494)
			(layers "F.Cu" "F.Mask" "F.Paste")
			(net "Net_150")
		)
		(pad "20" smd rect
			(at -4.500118 2.275078 270)
			(size 0.3048 1.5494)
			(layers "F.Cu" "F.Mask" "F.Paste")
			(net "Net_154")
		)
		(pad "21" smd rect
			(at -4.249928 -5.275072 270)
			(size 0.3048 1.5494)
			(layers "F.Cu" "F.Mask" "F.Paste")
			(net "GND")
		)
		(pad "22" smd rect
			(at -3.999992 2.275078 270)
			(size 0.3048 1.5494)
			(layers "F.Cu" "F.Mask" "F.Paste")
			(net "Net_155")
		)
		(pad "23" smd rect
			(at -3.750056 -5.275072 270)
			(size 0.3048 1.5494)
			(layers "F.Cu" "F.Mask" "F.Paste")
			(net "Net_151")
		)
		(pad "24" smd rect
			(at -3.50012 2.275078 270)
			(size 0.3048 1.5494)
			(layers "F.Cu" "F.Mask" "F.Paste")
			(net "Net_135")
		)
		(pad "25" smd rect
			(at -3.24993 -5.275072 270)
			(size 0.3048 1.5494)
			(layers "F.Cu" "F.Mask" "F.Paste")
			(net "Net_134")
		)
		(pad "26" smd rect
			(at -2.999994 2.275078 270)
			(size 0.3048 1.5494)
			(layers "F.Cu" "F.Mask" "F.Paste")
			(net "Net_136")
		)
		(pad "27" smd rect
			(at -2.750058 -5.275072 270)
			(size 0.3048 1.5494)
			(layers "F.Cu" "F.Mask" "F.Paste")
			(net "GND")
		)
		(pad "28" smd rect
			(at -2.500122 2.275078 270)
			(size 0.3048 1.5494)
			(layers "F.Cu" "F.Mask" "F.Paste")
			(net "Net_137")
		)
		(pad "29" smd rect
			(at -2.249932 -5.275072 270)
			(size 0.3048 1.5494)
			(layers "F.Cu" "F.Mask" "F.Paste")
			(net "D85_PCIE_A_RX0_N")
		)
		(pad "30" smd rect
			(at -1.999996 2.275078 270)
			(size 0.3048 1.5494)
			(layers "F.Cu" "F.Mask" "F.Paste")
			(net "Net_138")
		)
		(pad "31" smd rect
			(at -1.75006 -5.275072 270)
			(size 0.3048 1.5494)
			(layers "F.Cu" "F.Mask" "F.Paste")
			(net "D85_PCIE_A_RX0_P")
		)
		(pad "32" smd rect
			(at -1.500124 2.275078 270)
			(size 0.3048 1.5494)
			(layers "F.Cu" "F.Mask" "F.Paste")
			(net "Net_139")
		)
		(pad "33" smd rect
			(at -1.249934 -5.275072 270)
			(size 0.3048 1.5494)
			(layers "F.Cu" "F.Mask" "F.Paste")
			(net "GND")
		)
		(pad "34" smd rect
			(at -0.999998 2.275078 270)
			(size 0.3048 1.5494)
			(layers "F.Cu" "F.Mask" "F.Paste")
			(net "Net_140")
		)
		(pad "35" smd rect
			(at -0.750062 -5.275072 270)
			(size 0.3048 1.5494)
			(layers "F.Cu" "F.Mask" "F.Paste")
			(net "D85_PCIE_A_TX0_P")
		)
		(pad "36" smd rect
			(at -0.500126 2.275078 270)
			(size 0.3048 1.5494)
			(layers "F.Cu" "F.Mask" "F.Paste")
			(net "Net_141")
		)
		(pad "37" smd rect
			(at -0.249936 -5.275072 270)
			(size 0.3048 1.5494)
			(layers "F.Cu" "F.Mask" "F.Paste")
			(net "D85_PCIE_A_TX0_N")
		)
		(pad "38" smd rect
			(at 0 2.275078 270)
			(size 0.3048 1.5494)
			(layers "F.Cu" "F.Mask" "F.Paste")
			(net "Net_142")
		)
		(pad "39" smd rect
			(at 0.249936 -5.275072 270)
			(size 0.3048 1.5494)
			(layers "F.Cu" "F.Mask" "F.Paste")
			(net "GND")
		)
		(pad "40" smd rect
			(at 0.500126 2.275078 270)
			(size 0.3048 1.5494)
			(layers "F.Cu" "F.Mask" "F.Paste")
			(net "Z50_SSD_A1_SMB_CLK")
		)
		(pad "41" smd rect
			(at 0.750062 -5.275072 270)
			(size 0.3048 1.5494)
			(layers "F.Cu" "F.Mask" "F.Paste")
			(net "D85_PCIE_A_RX1_N")
		)
		(pad "42" smd rect
			(at 0.999998 2.275078 270)
			(size 0.3048 1.5494)
			(layers "F.Cu" "F.Mask" "F.Paste")
			(net "Z50_SSD_A1_SMB_DATA")
		)
		(pad "43" smd rect
			(at 1.249934 -5.275072 270)
			(size 0.3048 1.5494)
			(layers "F.Cu" "F.Mask" "F.Paste")
			(net "D85_PCIE_A_RX1_P")
		)
		(pad "44" smd rect
			(at 1.500124 2.275078 270)
			(size 0.3048 1.5494)
			(layers "F.Cu" "F.Mask" "F.Paste")
			(net "Z50_SSD_A1_ALERT#")
		)
		(pad "45" smd rect
			(at 1.75006 -5.275072 270)
			(size 0.3048 1.5494)
			(layers "F.Cu" "F.Mask" "F.Paste")
			(net "GND")
		)
		(pad "46" smd rect
			(at 1.999996 2.275078 270)
			(size 0.3048 1.5494)
			(layers "F.Cu" "F.Mask" "F.Paste")
			(net "Net_143")
		)
		(pad "47" smd rect
			(at 2.249932 -5.275072 270)
			(size 0.3048 1.5494)
			(layers "F.Cu" "F.Mask" "F.Paste")
			(net "D85_PCIE_A_TX1_P")
		)
		(pad "48" smd rect
			(at 2.500122 2.275078 270)
			(size 0.3048 1.5494)
			(layers "F.Cu" "F.Mask" "F.Paste")
			(net "Net_144")
		)
		(pad "49" smd rect
			(at 2.750058 -5.275072 270)
			(size 0.3048 1.5494)
			(layers "F.Cu" "F.Mask" "F.Paste")
			(net "D85_PCIE_A_TX1_N")
		)
		(pad "50" smd rect
			(at 2.999994 2.275078 270)
			(size 0.3048 1.5494)
			(layers "F.Cu" "F.Mask" "F.Paste")
			(net "Z50_DEV_RST#")
		)
		(pad "51" smd rect
			(at 3.24993 -5.275072 270)
			(size 0.3048 1.5494)
			(layers "F.Cu" "F.Mask" "F.Paste")
			(net "GND")
		)
		(pad "52" smd rect
			(at 3.50012 2.275078 270)
			(size 0.3048 1.5494)
			(layers "F.Cu" "F.Mask" "F.Paste")
			(net "Z50_SSD_A1_CLKREQ#")
		)
		(pad "53" smd rect
			(at 3.750056 -5.275072 270)
			(size 0.3048 1.5494)
			(layers "F.Cu" "F.Mask" "F.Paste")
			(net "D85_PCIE_A_REFCLK_N")
		)
		(pad "54" smd rect
			(at 3.999992 2.275078 270)
			(size 0.3048 1.5494)
			(layers "F.Cu" "F.Mask" "F.Paste")
			(net "Net_131")
		)
		(pad "55" smd rect
			(at 4.249928 -5.275072 270)
			(size 0.3048 1.5494)
			(layers "F.Cu" "F.Mask" "F.Paste")
			(net "D85_PCIE_A_REFCLK_P")
		)
		(pad "56" smd rect
			(at 4.500118 2.275078 270)
			(size 0.3048 1.5494)
			(layers "F.Cu" "F.Mask" "F.Paste")
			(net "SSD_A1_MFG_DATA_TP")
		)
		(pad "57" smd rect
			(at 4.750054 -5.275072 270)
			(size 0.3048 1.5494)
			(layers "F.Cu" "F.Mask" "F.Paste")
			(net "GND")
		)
		(pad "58" smd rect
			(at 4.99999 2.275078 270)
			(size 0.3048 1.5494)
			(layers "F.Cu" "F.Mask" "F.Paste")
			(net "SSD_A1_MFG_CLK_TP")
		)
		(pad "67" smd rect
			(at 7.249922 -5.275072 270)
			(size 0.3048 1.5494)
			(layers "F.Cu" "F.Mask" "F.Paste")
			(net "Net_129")
		)
		(pad "68" smd rect
			(at 7.500112 2.275078 270)
			(size 0.3048 1.5494)
			(layers "F.Cu" "F.Mask" "F.Paste")
			(net "Net_132")
		)
		(pad "69" smd rect
			(at 7.750048 -5.275072 270)
			(size 0.3048 1.5494)
			(layers "F.Cu" "F.Mask" "F.Paste")
			(net "Net_130")
		)
		(pad "70" smd rect
			(at 7.999984 2.275078 270)
			(size 0.3048 1.5494)
			(layers "F.Cu" "F.Mask" "F.Paste")
			(net "P3V3_PWR")
		)
		(pad "71" smd rect
			(at 8.24992 -5.275072 270)
			(size 0.3048 1.5494)
			(layers "F.Cu" "F.Mask" "F.Paste")
			(net "GND")
		)
		(pad "72" smd rect
			(at 8.50011 2.275078 270)
			(size 0.3048 1.5494)
			(layers "F.Cu" "F.Mask" "F.Paste")
			(net "P3V3_PWR")
		)
		(pad "73" smd rect
			(at 8.750046 -5.275072 270)
			(size 0.3048 1.5494)
			(layers "F.Cu" "F.Mask" "F.Paste")
			(net "GND")
		)
		(pad "74" smd rect
			(at 8.999982 2.275078 270)
			(size 0.3048 1.5494)
			(layers "F.Cu" "F.Mask" "F.Paste")
			(net "P3V3_PWR")
		)
		(pad "75" smd rect
			(at 9.249918 -5.275072 270)
			(size 0.3048 1.5494)
			(layers "F.Cu" "F.Mask" "F.Paste")
			(net "GND")
		)
		(pad "76" smd rect
			(at -10.349992 -4.500118 270)
			(size 1.1938 2.7432)
			(layers "F.Cu" "F.Mask" "F.Paste")
			(net "GND")
		)
		(pad "77" smd rect
			(at 10.349992 -4.500118 270)
			(size 1.1938 2.7432)
			(layers "F.Cu" "F.Mask" "F.Paste")
			(net "GND")
		)
		(zone
			(layer "F.Cu")
			(hatch none 0.5)
			(connect_pads
				(clearance 0)
			)
			(min_thickness 0.25)
			(keepout
				(tracks allowed)
				(vias not_allowed)
				(pads allowed)
				(copperpour not_allowed)
				(footprints allowed)
			)
			(placement
				(enabled no)
				(sheetname "")
			)
			(fill
				(thermal_gap 0.5)
				(thermal_bridge_width 0.5)
				(island_removal_mode 0)
			)
			(polygon
				(pts
					(xy 65.949576 -63.192406) (xy 65.949576 -48.887634) (xy 66.457576 -48.887634) (xy 66.457576 -63.192406)
				)
			)
		)
		(zone
			(layer "F.Cu")
			(hatch none 0.5)
			(connect_pads
				(clearance 0)
			)
			(min_thickness 0.25)
			(keepout
				(tracks allowed)
				(vias not_allowed)
				(pads allowed)
				(copperpour not_allowed)
				(footprints allowed)
			)
			(placement
				(enabled no)
				(sheetname "")
			)
			(fill
				(thermal_gap 0.5)
				(thermal_bridge_width 0.5)
				(island_removal_mode 0)
			)
			(polygon
				(pts
					(xy 65.949576 -46.692312) (xy 65.949576 -44.887642) (xy 66.457576 -44.887642) (xy 66.457576 -46.692312)
				)
			)
		)
		(zone
			(layer "F.Cu")
			(hatch none 0.5)
			(connect_pads
				(clearance 0)
			)
			(min_thickness 0.25)
			(keepout
				(tracks allowed)
				(vias not_allowed)
				(pads allowed)
				(copperpour not_allowed)
				(footprints allowed)
			)
			(placement
				(enabled no)
				(sheetname "")
			)
			(fill
				(thermal_gap 0.5)
				(thermal_bridge_width 0.5)
				(island_removal_mode 0)
			)
			(polygon
				(pts
					(xy 71.442326 -63.442342) (xy 71.442326 -49.13757) (xy 71.950326 -49.13757) (xy 71.950326 -63.442342)
				)
			)
		)
		(zone
			(layer "F.Cu")
			(hatch none 0.5)
			(connect_pads
				(clearance 0)
			)
			(min_thickness 0.25)
			(keepout
				(tracks allowed)
				(vias not_allowed)
				(pads allowed)
				(copperpour not_allowed)
				(footprints allowed)
			)
			(placement
				(enabled no)
				(sheetname "")
			)
			(fill
				(thermal_gap 0.5)
				(thermal_bridge_width 0.5)
				(island_removal_mode 0)
			)
			(polygon
				(pts
					(xy 71.442326 -46.942502) (xy 71.442326 -44.637706) (xy 71.950326 -44.637706) (xy 71.950326 -46.942502)
				)
			)
		)
		(zone
			(layers "F.Cu" "B.Cu" "In1.Cu" "In2.Cu" "In3.Cu" "In4.Cu" "In5.Cu" "In6.Cu")
			(hatch none 0.5)
			(connect_pads
				(clearance 0)
			)
			(min_thickness 0.25)
			(keepout
				(tracks not_allowed)
				(vias allowed)
				(pads allowed)
				(copperpour not_allowed)
				(footprints allowed)
			)
			(placement
				(enabled no)
				(sheetname "")
			)
			(fill
				(thermal_gap 0.5)
				(thermal_bridge_width 0.5)
				(island_removal_mode 0)
			)
			(polygon
				(pts
					(arc
						(start 68.313554 -64.040004)
						(mid 66.586354 -64.040004)
						(end 68.313554 -64.040004)
					)
				)
			)
		)
		(zone
			(layers "F.Cu" "B.Cu" "In1.Cu" "In2.Cu" "In3.Cu" "In4.Cu" "In5.Cu" "In6.Cu")
			(hatch none 0.5)
			(connect_pads
				(clearance 0)
			)
			(min_thickness 0.25)
			(keepout
				(tracks not_allowed)
				(vias allowed)
				(pads allowed)
				(copperpour not_allowed)
				(footprints allowed)
			)
			(placement
				(enabled no)
				(sheetname "")
			)
			(fill
				(thermal_gap 0.5)
				(thermal_bridge_width 0.5)
				(island_removal_mode 0)
			)
			(polygon
				(pts
					(arc
						(start 68.554854 -44.040044)
						(mid 66.345054 -44.040044)
						(end 68.554854 -44.040044)
					)
				)
			)
		)
	)
	(footprint ""
		(layer "F.Cu")
		(at 59.817 -44.577 -90)
		(property "Reference" "C1"
			(at 0 0 270)
			(layer "F.SilkS")
			(hide yes)
			(effects
				(font
					(size 1.27 1.27)
				)
			)
		)
		(property "Value" "SC1U6D3V2KX-9-GP"
			(at 1.1811 -2.7051 270)
			(unlocked yes)
			(layer "F.Fab")
			(hide yes)
			(effects
				(font
					(size 1.016 1.016)
					(thickness 0.1524)
				)
			)
		)
		(property "Device Type" "C402H22"
			(at 1.1811 -4.2291 270)
			(unlocked yes)
			(layer "F.Fab")
			(hide yes)
			(effects
				(font
					(size 1.016 1.016)
					(thickness 0.1524)
				)
			)
		)
		(duplicate_pad_numbers_are_jumpers no)
		(fp_rect
			(start -0.4318 0.9525)
			(end 0.4318 -0.9525)
			(stroke
				(width 0)
				(type default)
			)
			(fill no)
			(layer "F.CrtYd")
		)
		(fp_rect
			(start -0.4318 0.9525)
			(end 0.4318 -0.9525)
			(stroke
				(width 0)
				(type default)
			)
			(fill no)
			(layer "F.Fab")
		)
		(pad "1" smd custom
			(at 0 -0.4445 270)
			(size 0.1524 0.1524)
			(layers "F.Cu" "F.Mask" "F.Paste")
			(net "P3V3_PWR")
			(options
				(clearance outline)
				(anchor circle)
			)
			(primitives
				(gr_poly
					(pts
						(arc
							(start 0.3048 -0.2032)
							(mid 0.275042 -0.275042)
							(end 0.2032 -0.3048)
						)
						(arc
							(start -0.2032 -0.3048)
							(mid -0.275042 -0.275042)
							(end -0.3048 -0.2032)
						)
						(arc
							(start -0.3048 0.2032)
							(mid -0.275042 0.275042)
							(end -0.2032 0.3048)
						)
						(arc
							(start 0.2032 0.3048)
							(mid 0.275042 0.275042)
							(end 0.3048 0.2032)
						)
					)
					(width 0)
					(fill yes)
				)
			)
		)
		(pad "2" smd custom
			(at 0 0.4445 270)
			(size 0.1524 0.1524)
			(layers "F.Cu" "F.Mask" "F.Paste")
			(net "GND")
			(options
				(clearance outline)
				(anchor circle)
			)
			(primitives
				(gr_poly
					(pts
						(arc
							(start 0.3048 -0.2032)
							(mid 0.275042 -0.275042)
							(end 0.2032 -0.3048)
						)
						(arc
							(start -0.2032 -0.3048)
							(mid -0.275042 -0.275042)
							(end -0.3048 -0.2032)
						)
						(arc
							(start -0.3048 0.2032)
							(mid -0.275042 0.275042)
							(end -0.2032 0.3048)
						)
						(arc
							(start 0.2032 0.3048)
							(mid 0.275042 0.275042)
							(end 0.3048 0.2032)
						)
					)
					(width 0)
					(fill yes)
				)
			)
		)
	)
	(footprint ""
		(layer "F.Cu")
		(at 60.200032 -4.500118)
		(property "Reference" "H3"
			(at 0 0 0)
			(layer "F.SilkS")
			(hide yes)
			(effects
				(font
					(size 1.27 1.27)
				)
			)
		)
		(property "Value" "HOLE315R140-GP"
			(at 0 -7.5692 0)
			(unlocked yes)
			(layer "F.Fab")
			(hide yes)
			(effects
				(font
					(size 1.016 1.016)
					(thickness 0.1524)
				)
			)
		)
		(property "Device Type" "HOLE315R140"
			(at 0 -9.0932 0)
			(unlocked yes)
			(layer "F.Fab")
			(hide yes)
			(effects
				(font
					(size 1.016 1.016)
					(thickness 0.1524)
				)
			)
		)
		(duplicate_pad_numbers_are_jumpers no)
		(fp_poly
			(pts
				(arc
					(start 4.3053 0)
					(mid -4.3053 0)
					(end 4.3053 0)
				)
			)
			(stroke
				(width 0)
				(type default)
			)
			(fill no)
			(layer "F.CrtYd")
		)
		(fp_poly
			(pts
				(arc
					(start 4.3053 0)
					(mid -4.3053 0)
					(end 4.3053 0)
				)
			)
			(stroke
				(width 0)
				(type default)
			)
			(fill no)
			(layer "F.Fab")
		)
		(pad "1" thru_hole circle
			(at 0.00127 0.00127)
			(size 8.001 8.001)
			(drill 3.556)
			(layers "*.Cu" "*.Mask")
			(remove_unused_layers no)
			(net "GND")
			(clearance -1.7145)
			(thermal_gap 0.3048)
			(padstack
				(mode front_inner_back)
				(layer "Inner"
					(shape circle)
					(size 3.9624 3.9624)
					(clearance 0.3048)
				)
				(layer "B.Cu"
					(shape circle)
					(size 8.001 8.001)
					(clearance -1.7145)
				)
			)
		)
	)
	(footprint ""
		(layer "F.Cu")
		(at 18.415 -87.63 -90)
		(property "Reference" "PR20"
			(at 0 0 270)
			(layer "F.SilkS")
			(hide yes)
			(effects
				(font
					(size 1.27 1.27)
				)
			)
		)
		(property "Value" "10KR2F-2-GP"
			(at 0.064008 -3.993896 270)
			(unlocked yes)
			(layer "F.Fab")
			(hide yes)
			(effects
				(font
					(size 1.016 1.016)
					(thickness 0.1524)
				)
			)
		)
		(property "Device Type" "R402H16"
			(at 0.064008 -5.517896 270)
			(unlocked yes)
			(layer "F.Fab")
			(hide yes)
			(effects
				(font
					(size 1.016 1.016)
					(thickness 0.1524)
				)
			)
		)
		(duplicate_pad_numbers_are_jumpers no)
		(fp_line
			(start -0.508 -0.9398)
			(end -0.508 0.9398)
			(stroke
				(width 0.1524)
				(type default)
			)
			(layer "F.SilkS")
		)
		(fp_line
			(start 0.508 -0.9398)
			(end -0.508 -0.9398)
			(stroke
				(width 0.1524)
				(type default)
			)
			(layer "F.SilkS")
		)
		(fp_rect
			(start -0.508 0.9398)
			(end 0.508 -0.9398)
			(stroke
				(width 0)
				(type default)
			)
			(fill no)
			(layer "F.CrtYd")
		)
		(fp_rect
			(start -0.508 0.9398)
			(end 0.508 -0.9398)
			(stroke
				(width 0)
				(type default)
			)
			(fill no)
			(layer "F.Fab")
		)
		(pad "1" smd custom
			(at 0 -0.4445 270)
			(size 0.1397 0.1397)
			(layers "F.Cu" "F.Mask" "F.Paste")
			(net "P3V3_PWR")
			(options
				(clearance outline)
				(anchor circle)
			)
			(primitives
				(gr_poly
					(pts
						(arc
							(start -0.1778 -0.2794)
							(mid -0.249642 -0.249642)
							(end -0.2794 -0.1778)
						)
						(arc
							(start -0.2794 0.1778)
							(mid -0.249642 0.249642)
							(end -0.1778 0.2794)
						)
						(arc
							(start 0.1778 0.2794)
							(mid 0.249642 0.249642)
							(end 0.2794 0.1778)
						)
						(arc
							(start 0.2794 -0.1778)
							(mid 0.249642 -0.249642)
							(end 0.1778 -0.2794)
						)
					)
					(width 0)
					(fill yes)
				)
			)
		)
		(pad "2" smd custom
			(at 0 0.4445 270)
			(size 0.1397 0.1397)
			(layers "F.Cu" "F.Mask" "F.Paste")
			(net "P1V8_PWR_GD")
			(options
				(clearance outline)
				(anchor circle)
			)
			(primitives
				(gr_poly
					(pts
						(arc
							(start -0.1778 -0.2794)
							(mid -0.249642 -0.249642)
							(end -0.2794 -0.1778)
						)
						(arc
							(start -0.2794 0.1778)
							(mid -0.249642 0.249642)
							(end -0.1778 0.2794)
						)
						(arc
							(start 0.1778 0.2794)
							(mid 0.249642 0.249642)
							(end 0.2794 0.1778)
						)
						(arc
							(start 0.2794 -0.1778)
							(mid 0.249642 -0.249642)
							(end 0.1778 -0.2794)
						)
					)
					(width 0)
					(fill yes)
				)
			)
		)
	)
	(footprint ""
		(layer "F.Cu")
		(at 43.053 -84.709 180)
		(property "Reference" "PC31"
			(at 0 0 180)
			(layer "F.SilkS")
			(hide yes)
			(effects
				(font
					(size 1.27 1.27)
				)
			)
		)
		(property "Value" "SCD1U25V3KX-GP"
			(at 0 -2.8194 180)
			(unlocked yes)
			(layer "F.Fab")
			(hide yes)
			(effects
				(font
					(size 1.016 1.016)
					(thickness 0.1524)
				)
			)
		)
		(property "Device Type" "C603H36"
			(at 0 -4.3434 180)
			(unlocked yes)
			(layer "F.Fab")
			(hide yes)
			(effects
				(font
					(size 1.016 1.016)
					(thickness 0.1524)
				)
			)
		)
		(duplicate_pad_numbers_are_jumpers no)
		(fp_line
			(start 0.508 0)
			(end -0.508 0)
			(stroke
				(width 0.2032)
				(type default)
			)
			(layer "F.SilkS")
		)
		(fp_rect
			(start -0.5842 1.3335)
			(end 0.5842 -1.3335)
			(stroke
				(width 0)
				(type default)
			)
			(fill no)
			(layer "F.CrtYd")
		)
		(fp_rect
			(start -0.5842 1.3335)
			(end 0.5842 -1.3335)
			(stroke
				(width 0)
				(type default)
			)
			(fill no)
			(layer "F.Fab")
		)
		(pad "1" smd custom
			(at 0 -0.762 180)
			(size 0.2159 0.2159)
			(layers "F.Cu" "F.Mask" "F.Paste")
			(net "P3V3_DEV_VIN")
			(options
				(clearance outline)
				(anchor circle)
			)
			(primitives
				(gr_poly
					(pts
						(arc
							(start -0.3302 -0.4318)
							(mid -0.402042 -0.402042)
							(end -0.4318 -0.3302)
						)
						(arc
							(start -0.4318 0.3302)
							(mid -0.402042 0.402042)
							(end -0.3302 0.4318)
						)
						(arc
							(start 0.3302 0.4318)
							(mid 0.402042 0.402042)
							(end 0.4318 0.3302)
						)
						(arc
							(start 0.4318 -0.3302)
							(mid 0.402042 -0.402042)
							(end 0.3302 -0.4318)
						)
					)
					(width 0)
					(fill yes)
				)
			)
		)
		(pad "2" smd custom
			(at 0 0.762 180)
			(size 0.2159 0.2159)
			(layers "F.Cu" "F.Mask" "F.Paste")
			(net "GND")
			(options
				(clearance outline)
				(anchor circle)
			)
			(primitives
				(gr_poly
					(pts
						(arc
							(start -0.3302 -0.4318)
							(mid -0.402042 -0.402042)
							(end -0.4318 -0.3302)
						)
						(arc
							(start -0.4318 0.3302)
							(mid -0.402042 0.402042)
							(end -0.3302 0.4318)
						)
						(arc
							(start 0.3302 0.4318)
							(mid 0.402042 0.402042)
							(end 0.4318 0.3302)
						)
						(arc
							(start 0.4318 -0.3302)
							(mid 0.402042 -0.402042)
							(end 0.3302 -0.4318)
						)
					)
					(width 0)
					(fill yes)
				)
			)
		)
	)
	(footprint ""
		(layer "F.Cu")
		(at 48.133 -86.36)
		(property "Reference" "PR33"
			(at 0 0 0)
			(layer "F.SilkS")
			(hide yes)
			(effects
				(font
					(size 1.27 1.27)
				)
			)
		)
		(property "Value" "3D01R5F-GP"
			(at 0 -8.9535 0)
			(unlocked yes)
			(layer "F.Fab")
			(hide yes)
			(effects
				(font
					(size 1.27 1.016)
					(thickness 0.1524)
				)
			)
		)
		(property "Device Type" "R805H24"
			(at 0 -10.6299 0)
			(unlocked yes)
			(layer "F.Fab")
			(hide yes)
			(effects
				(font
					(size 1.27 1.016)
					(thickness 0.1524)
				)
			)
		)
		(duplicate_pad_numbers_are_jumpers no)
		(fp_line
			(start -0.889 -1.7018)
			(end -0.889 0.2794)
			(stroke
				(width 0.1524)
				(type default)
			)
			(layer "F.SilkS")
		)
		(fp_line
			(start -0.889 0.0762)
			(end -0.889 1.7018)
			(stroke
				(width 0.1524)
				(type default)
			)
			(layer "F.SilkS")
		)
		(fp_line
			(start -0.889 1.7018)
			(end 0.889 1.7018)
			(stroke
				(width 0.1524)
				(type default)
			)
			(layer "F.SilkS")
		)
		(fp_line
			(start 0.889 -1.7018)
			(end -0.889 -1.7018)
			(stroke
				(width 0.1524)
				(type default)
			)
			(layer "F.SilkS")
		)
		(fp_line
			(start 0.889 -1.7018)
			(end 0.889 -0.381)
			(stroke
				(width 0.1524)
				(type default)
			)
			(layer "F.SilkS")
		)
		(fp_line
			(start 0.889 1.7018)
			(end 0.889 -0.508)
			(stroke
				(width 0.1524)
				(type default)
			)
			(layer "F.SilkS")
		)
		(fp_poly
			(pts
				(xy 0.9652 -1.778) (xy 0.9652 1.778) (xy -0.9652 1.778) (xy -0.9652 -1.778)
			)
			(stroke
				(width 0)
				(type default)
			)
			(fill no)
			(layer "F.CrtYd")
		)
		(fp_rect
			(start -0.9652 1.778)
			(end 0.9652 -1.778)
			(stroke
				(width 0)
				(type default)
			)
			(fill no)
			(layer "F.Fab")
		)
		(pad "1" smd rect
			(at 0 -0.9652)
			(size 1.397 1.143)
			(layers "F.Cu" "F.Mask" "F.Paste")
			(net "P3V3_DEV_SNB")
		)
		(pad "2" smd rect
			(at 0 0.9652)
			(size 1.397 1.143)
			(layers "F.Cu" "F.Mask" "F.Paste")
			(net "GND")
		)
	)
	(footprint ""
		(layer "F.Cu")
		(at 17.272 -86.154006)
		(property "Reference" "TP5"
			(at 0 0 0)
			(layer "F.SilkS")
			(hide yes)
			(effects
				(font
					(size 1.27 1.27)
				)
			)
		)
		(property "Value" "TPAD28-1-GP-U"
			(at 0.0508 -1.9304 0)
			(unlocked yes)
			(layer "F.Fab")
			(hide yes)
			(effects
				(font
					(size 1.016 1.016)
					(thickness 0.1524)
				)
			)
		)
		(property "Device Type" "TPAD28-1-U"
			(at 0.0508 -3.4544 0)
			(unlocked yes)
			(layer "F.Fab")
			(hide yes)
			(effects
				(font
					(size 1.016 1.016)
					(thickness 0.1524)
				)
			)
		)
		(duplicate_pad_numbers_are_jumpers no)
		(fp_poly
			(pts
				(arc
					(start 0.3556 0)
					(mid -0.3556 0)
					(end 0.3556 0)
				)
			)
			(stroke
				(width 0)
				(type default)
			)
			(fill no)
			(layer "F.CrtYd")
		)
		(fp_poly
			(pts
				(arc
					(start 0.9525 0)
					(mid -0.9525 0)
					(end 0.9525 0)
				)
			)
			(stroke
				(width 0)
				(type default)
			)
			(fill no)
			(layer "F.Fab")
		)
		(pad "1" smd circle
			(at 0 0)
			(size 0.7112 0.7112)
			(layers "F.Cu" "F.Mask" "F.Paste")
			(net "P1V8_PWR_GD")
		)
	)
	(footprint ""
		(layer "F.Cu")
		(at 20.447 -72.565006 90)
		(property "Reference" "PC23"
			(at 0 0 90)
			(layer "F.SilkS")
			(hide yes)
			(effects
				(font
					(size 1.27 1.27)
				)
			)
		)
		(property "Value" "SC4D7U16V5KX-1-GP"
			(at -0.0762 -6.1214 90)
			(unlocked yes)
			(layer "F.Fab")
			(hide yes)
			(effects
				(font
					(size 1.016 1.016)
					(thickness 0.1524)
				)
			)
		)
		(property "Device Type" "C805H56"
			(at -0.0762 -8.1534 90)
			(unlocked yes)
			(layer "F.Fab")
			(hide yes)
			(effects
				(font
					(size 1.016 1.016)
					(thickness 0.1524)
				)
			)
		)
		(duplicate_pad_numbers_are_jumpers no)
		(fp_line
			(start 0.635 0)
			(end -0.635 0)
			(stroke
				(width 0.508)
				(type default)
			)
			(layer "F.SilkS")
		)
		(fp_rect
			(start -0.9652 1.778)
			(end 0.9652 -1.778)
			(stroke
				(width 0)
				(type default)
			)
			(fill no)
			(layer "F.CrtYd")
		)
		(fp_poly
			(pts
				(xy -0.9652 -1.778) (xy 0.9652 -1.778) (xy 0.9652 1.778) (xy -0.9652 1.778)
			)
			(stroke
				(width 0)
				(type default)
			)
			(fill no)
			(layer "F.Fab")
		)
		(pad "1" smd rect
			(at 0 -0.9652 90)
			(size 1.397 1.143)
			(layers "F.Cu" "F.Mask" "F.Paste")
			(net "P1V8_PWR")
		)
		(pad "2" smd rect
			(at 0 0.9652 90)
			(size 1.397 1.143)
			(layers "F.Cu" "F.Mask" "F.Paste")
			(net "GND")
		)
	)
	(footprint ""
		(layer "F.Cu")
		(at 75.692 -38.735 180)
		(property "Reference" "R45"
			(at 0 0 180)
			(layer "F.SilkS")
			(hide yes)
			(effects
				(font
					(size 1.27 1.27)
				)
			)
		)
		(property "Value" "47KR2F-GP"
			(at 0.064008 -3.993896 180)
			(unlocked yes)
			(layer "F.Fab")
			(hide yes)
			(effects
				(font
					(size 1.016 1.016)
					(thickness 0.1524)
				)
			)
		)
		(property "Device Type" "R402H16"
			(at 0.064008 -5.517896 180)
			(unlocked yes)
			(layer "F.Fab")
			(hide yes)
			(effects
				(font
					(size 1.016 1.016)
					(thickness 0.1524)
				)
			)
		)
		(duplicate_pad_numbers_are_jumpers no)
		(fp_line
			(start 0.508 -0.9398)
			(end -0.508 -0.9398)
			(stroke
				(width 0.1524)
				(type default)
			)
			(layer "F.SilkS")
		)
		(fp_line
			(start -0.508 -0.9398)
			(end -0.508 0.9398)
			(stroke
				(width 0.1524)
				(type default)
			)
			(layer "F.SilkS")
		)
		(fp_rect
			(start -0.508 0.9398)
			(end 0.508 -0.9398)
			(stroke
				(width 0)
				(type default)
			)
			(fill no)
			(layer "F.CrtYd")
		)
		(fp_rect
			(start -0.508 0.9398)
			(end 0.508 -0.9398)
			(stroke
				(width 0)
				(type default)
			)
			(fill no)
			(layer "F.Fab")
		)
		(pad "1" smd custom
			(at 0 -0.4445 180)
			(size 0.1397 0.1397)
			(layers "F.Cu" "F.Mask" "F.Paste")
			(net "P3V3_DPB")
			(options
				(clearance outline)
				(anchor circle)
			)
			(primitives
				(gr_poly
					(pts
						(arc
							(start -0.1778 -0.2794)
							(mid -0.249642 -0.249642)
							(end -0.2794 -0.1778)
						)
						(arc
							(start -0.2794 0.1778)
							(mid -0.249642 0.249642)
							(end -0.1778 0.2794)
						)
						(arc
							(start 0.1778 0.2794)
							(mid 0.249642 0.249642)
							(end 0.2794 0.1778)
						)
						(arc
							(start 0.2794 -0.1778)
							(mid 0.249642 -0.249642)
							(end 0.1778 -0.2794)
						)
					)
					(width 0)
					(fill yes)
				)
			)
		)
		(pad "2" smd custom
			(at 0 0.4445 180)
			(size 0.1397 0.1397)
			(layers "F.Cu" "F.Mask" "F.Paste")
			(net "Z50_SSD_B_PRSNT#")
			(options
				(clearance outline)
				(anchor circle)
			)
			(primitives
				(gr_poly
					(pts
						(arc
							(start -0.1778 -0.2794)
							(mid -0.249642 -0.249642)
							(end -0.2794 -0.1778)
						)
						(arc
							(start -0.2794 0.1778)
							(mid -0.249642 0.249642)
							(end -0.1778 0.2794)
						)
						(arc
							(start 0.1778 0.2794)
							(mid 0.249642 0.249642)
							(end 0.2794 0.1778)
						)
						(arc
							(start 0.2794 -0.1778)
							(mid 0.249642 -0.249642)
							(end 0.1778 -0.2794)
						)
					)
					(width 0)
					(fill yes)
				)
			)
		)
	)
	(footprint ""
		(layer "F.Cu")
		(at 14.732 -80.693006 180)
		(property "Reference" "PR24"
			(at 0 0 180)
			(layer "F.SilkS")
			(hide yes)
			(effects
				(font
					(size 1.27 1.27)
				)
			)
		)
		(property "Value" "0R3F-1-GP-U"
			(at -0.0254 -2.5146 180)
			(unlocked yes)
			(layer "F.Fab")
			(hide yes)
			(effects
				(font
					(size 1.016 1.016)
					(thickness 0.1524)
				)
			)
		)
		(property "Device Type" "R603H24"
			(at -0.0254 -4.0386 180)
			(unlocked yes)
			(layer "F.Fab")
			(hide yes)
			(effects
				(font
					(size 1.016 1.016)
					(thickness 0.1524)
				)
			)
		)
		(duplicate_pad_numbers_are_jumpers no)
		(fp_line
			(start 0.2032 0)
			(end 0.4826 0)
			(stroke
				(width 0.2032)
				(type default)
			)
			(layer "F.SilkS")
		)
		(fp_line
			(start -0.4826 0)
			(end -0.2032 0)
			(stroke
				(width 0.2032)
				(type default)
			)
			(layer "F.SilkS")
		)
		(fp_rect
			(start -0.5842 1.3335)
			(end 0.5842 -1.3335)
			(stroke
				(width 0)
				(type default)
			)
			(fill no)
			(layer "F.CrtYd")
		)
		(fp_rect
			(start -0.5842 1.3335)
			(end 0.5842 -1.3335)
			(stroke
				(width 0)
				(type default)
			)
			(fill no)
			(layer "F.Fab")
		)
		(pad "1" smd custom
			(at 0 -0.762 180)
			(size 0.2159 0.2159)
			(layers "F.Cu" "F.Mask" "F.Paste")
			(net "P3V3_PWR")
			(options
				(clearance outline)
				(anchor circle)
			)
			(primitives
				(gr_poly
					(pts
						(arc
							(start -0.3302 -0.4318)
							(mid -0.402042 -0.402042)
							(end -0.4318 -0.3302)
						)
						(arc
							(start -0.4318 0.3302)
							(mid -0.402042 0.402042)
							(end -0.3302 0.4318)
						)
						(arc
							(start 0.3302 0.4318)
							(mid 0.402042 0.402042)
							(end 0.4318 0.3302)
						)
						(arc
							(start 0.4318 -0.3302)
							(mid 0.402042 -0.402042)
							(end 0.3302 -0.4318)
						)
					)
					(width 0)
					(fill yes)
				)
			)
		)
		(pad "2" smd custom
			(at 0 0.762 180)
			(size 0.2159 0.2159)
			(layers "F.Cu" "F.Mask" "F.Paste")
			(net "P1V8_PWR_EN_R")
			(options
				(clearance outline)
				(anchor circle)
			)
			(primitives
				(gr_poly
					(pts
						(arc
							(start -0.3302 -0.4318)
							(mid -0.402042 -0.402042)
							(end -0.4318 -0.3302)
						)
						(arc
							(start -0.4318 0.3302)
							(mid -0.402042 0.402042)
							(end -0.3302 0.4318)
						)
						(arc
							(start 0.3302 0.4318)
							(mid 0.402042 0.402042)
							(end 0.4318 0.3302)
						)
						(arc
							(start 0.4318 -0.3302)
							(mid 0.402042 -0.402042)
							(end 0.3302 -0.4318)
						)
					)
					(width 0)
					(fill yes)
				)
			)
		)
	)
	(footprint ""
		(layer "F.Cu")
		(at 29.083 -72.009)
		(property "Reference" "R53"
			(at 0 0 0)
			(layer "F.SilkS")
			(hide yes)
			(effects
				(font
					(size 1.27 1.27)
				)
			)
		)
		(property "Value" "33R2J-2-GP"
			(at 0.064008 -3.993896 0)
			(unlocked yes)
			(layer "F.Fab")
			(hide yes)
			(effects
				(font
					(size 1.016 1.016)
					(thickness 0.1524)
				)
			)
		)
		(property "Device Type" "R402H16"
			(at 0.064008 -5.517896 0)
			(unlocked yes)
			(layer "F.Fab")
			(hide yes)
			(effects
				(font
					(size 1.016 1.016)
					(thickness 0.1524)
				)
			)
		)
		(duplicate_pad_numbers_are_jumpers no)
		(fp_line
			(start -0.508 -0.9398)
			(end -0.508 0.9398)
			(stroke
				(width 0.1524)
				(type default)
			)
			(layer "F.SilkS")
		)
		(fp_line
			(start 0.508 -0.9398)
			(end -0.508 -0.9398)
			(stroke
				(width 0.1524)
				(type default)
			)
			(layer "F.SilkS")
		)
		(fp_rect
			(start -0.508 0.9398)
			(end 0.508 -0.9398)
			(stroke
				(width 0)
				(type default)
			)
			(fill no)
			(layer "F.CrtYd")
		)
		(fp_rect
			(start -0.508 0.9398)
			(end 0.508 -0.9398)
			(stroke
				(width 0)
				(type default)
			)
			(fill no)
			(layer "F.Fab")
		)
		(pad "1" smd custom
			(at 0 -0.4445)
			(size 0.1397 0.1397)
			(layers "F.Cu" "F.Mask" "F.Paste")
			(net "Z50_SSD_B1_SMB_CLK_LR")
			(options
				(clearance outline)
				(anchor circle)
			)
			(primitives
				(gr_poly
					(pts
						(arc
							(start -0.1778 -0.2794)
							(mid -0.249642 -0.249642)
							(end -0.2794 -0.1778)
						)
						(arc
							(start -0.2794 0.1778)
							(mid -0.249642 0.249642)
							(end -0.1778 0.2794)
						)
						(arc
							(start 0.1778 0.2794)
							(mid 0.249642 0.249642)
							(end 0.2794 0.1778)
						)
						(arc
							(start 0.2794 -0.1778)
							(mid 0.249642 -0.249642)
							(end 0.1778 -0.2794)
						)
					)
					(width 0)
					(fill yes)
				)
			)
		)
		(pad "2" smd custom
			(at 0 0.4445)
			(size 0.1397 0.1397)
			(layers "F.Cu" "F.Mask" "F.Paste")
			(net "Z50_SSD_B1_SMB_CLK")
			(options
				(clearance outline)
				(anchor circle)
			)
			(primitives
				(gr_poly
					(pts
						(arc
							(start -0.1778 -0.2794)
							(mid -0.249642 -0.249642)
							(end -0.2794 -0.1778)
						)
						(arc
							(start -0.2794 0.1778)
							(mid -0.249642 0.249642)
							(end -0.1778 0.2794)
						)
						(arc
							(start 0.1778 0.2794)
							(mid 0.249642 0.249642)
							(end 0.2794 0.1778)
						)
						(arc
							(start 0.2794 -0.1778)
							(mid 0.249642 -0.249642)
							(end 0.1778 -0.2794)
						)
					)
					(width 0)
					(fill yes)
				)
			)
		)
	)
	(footprint ""
		(layer "F.Cu")
		(at 59.817 -61.722 -90)
		(property "Reference" "C14"
			(at 0 0 270)
			(layer "F.SilkS")
			(hide yes)
			(effects
				(font
					(size 1.27 1.27)
				)
			)
		)
		(property "Value" "SCD1U16V2KX-3GP"
			(at 1.1811 -2.7051 270)
			(unlocked yes)
			(layer "F.Fab")
			(hide yes)
			(effects
				(font
					(size 1.016 1.016)
					(thickness 0.1524)
				)
			)
		)
		(property "Device Type" "C402H22"
			(at 1.1811 -4.2291 270)
			(unlocked yes)
			(layer "F.Fab")
			(hide yes)
			(effects
				(font
					(size 1.016 1.016)
					(thickness 0.1524)
				)
			)
		)
		(duplicate_pad_numbers_are_jumpers no)
		(fp_rect
			(start -0.4318 0.9525)
			(end 0.4318 -0.9525)
			(stroke
				(width 0)
				(type default)
			)
			(fill no)
			(layer "F.CrtYd")
		)
		(fp_rect
			(start -0.4318 0.9525)
			(end 0.4318 -0.9525)
			(stroke
				(width 0)
				(type default)
			)
			(fill no)
			(layer "F.Fab")
		)
		(pad "1" smd custom
			(at 0 -0.4445 270)
			(size 0.1524 0.1524)
			(layers "F.Cu" "F.Mask" "F.Paste")
			(net "P3V3_PWR")
			(options
				(clearance outline)
				(anchor circle)
			)
			(primitives
				(gr_poly
					(pts
						(arc
							(start 0.3048 -0.2032)
							(mid 0.275042 -0.275042)
							(end 0.2032 -0.3048)
						)
						(arc
							(start -0.2032 -0.3048)
							(mid -0.275042 -0.275042)
							(end -0.3048 -0.2032)
						)
						(arc
							(start -0.3048 0.2032)
							(mid -0.275042 0.275042)
							(end -0.2032 0.3048)
						)
						(arc
							(start 0.2032 0.3048)
							(mid 0.275042 0.275042)
							(end 0.3048 0.2032)
						)
					)
					(width 0)
					(fill yes)
				)
			)
		)
		(pad "2" smd custom
			(at 0 0.4445 270)
			(size 0.1524 0.1524)
			(layers "F.Cu" "F.Mask" "F.Paste")
			(net "GND")
			(options
				(clearance outline)
				(anchor circle)
			)
			(primitives
				(gr_poly
					(pts
						(arc
							(start 0.3048 -0.2032)
							(mid 0.275042 -0.275042)
							(end 0.2032 -0.3048)
						)
						(arc
							(start -0.2032 -0.3048)
							(mid -0.275042 -0.275042)
							(end -0.3048 -0.2032)
						)
						(arc
							(start -0.3048 0.2032)
							(mid -0.275042 0.275042)
							(end -0.2032 0.3048)
						)
						(arc
							(start 0.2032 0.3048)
							(mid 0.275042 0.275042)
							(end 0.3048 0.2032)
						)
					)
					(width 0)
					(fill yes)
				)
			)
		)
	)
	(footprint ""
		(layer "F.Cu")
		(at 25.908 -75.819 180)
		(property "Reference" "U7"
			(at 0 0 180)
			(layer "F.SilkS")
			(hide yes)
			(effects
				(font
					(size 1.27 1.27)
				)
			)
		)
		(property "Value" "TXS0102DCUR-1-GP"
			(at 0 -11.1252 180)
			(unlocked yes)
			(layer "F.Fab")
			(hide yes)
			(effects
				(font
					(size 1.016 1.016)
					(thickness 0.1524)
				)
			)
		)
		(property "Device Type" "SSOIC8-4H36"
			(at 0 -12.6492 180)
			(unlocked yes)
			(layer "F.Fab")
			(hide yes)
			(effects
				(font
					(size 1.016 1.016)
					(thickness 0.1524)
				)
			)
		)
		(duplicate_pad_numbers_are_jumpers no)
		(fp_line
			(start 1.2573 2.1844)
			(end -1.2573 2.1844)
			(stroke
				(width 0.1524)
				(type default)
			)
			(layer "F.SilkS")
		)
		(fp_line
			(start 1.2573 -2.1844)
			(end 1.2573 2.1844)
			(stroke
				(width 0.1524)
				(type default)
			)
			(layer "F.SilkS")
		)
		(fp_line
			(start -0.9017 -0.0381)
			(end -1.2065 0.2667)
			(stroke
				(width 0.1524)
				(type default)
			)
			(layer "F.SilkS")
		)
		(fp_line
			(start -1.2065 0.2667)
			(end -1.27 0.2667)
			(stroke
				(width 0.1524)
				(type default)
			)
			(layer "F.SilkS")
		)
		(fp_line
			(start -1.2192 -0.3556)
			(end -0.9017 -0.0381)
			(stroke
				(width 0.1524)
				(type default)
			)
			(layer "F.SilkS")
		)
		(fp_line
			(start -1.2573 2.1844)
			(end -1.2573 -2.1844)
			(stroke
				(width 0.1524)
				(type default)
			)
			(layer "F.SilkS")
		)
		(fp_line
			(start -1.2573 -0.3556)
			(end -1.2192 -0.3556)
			(stroke
				(width 0.1524)
				(type default)
			)
			(layer "F.SilkS")
		)
		(fp_line
			(start -1.2573 -2.1844)
			(end 1.2573 -2.1844)
			(stroke
				(width 0.1524)
				(type default)
			)
			(layer "F.SilkS")
		)
		(fp_line
			(start -1.2954 0.4572)
			(end -1.2954 2.159)
			(stroke
				(width 0.4064)
				(type default)
			)
			(layer "F.SilkS")
		)
		(fp_poly
			(pts
				(xy -1.5113 2.4384) (xy 1.5113 2.4384) (xy 1.5113 -2.4384) (xy -1.5113 -2.4384)
			)
			(stroke
				(width 0)
				(type default)
			)
			(fill no)
			(layer "F.CrtYd")
		)
		(fp_poly
			(pts
				(xy -1.5113 -2.4384) (xy 1.5113 -2.4384) (xy 1.5113 2.4384) (xy -1.5113 2.4384)
			)
			(stroke
				(width 0)
				(type default)
			)
			(fill no)
			(layer "F.Fab")
		)
		(pad "1" smd rect
			(at -0.75057 1.1684 180)
			(size 0.3048 1.524)
			(layers "F.Cu" "F.Mask" "F.Paste")
			(net "Z50_SSD_A1_SMB_CLK_LL")
		)
		(pad "2" smd rect
			(at -0.25019 1.1684 180)
			(size 0.3048 1.524)
			(layers "F.Cu" "F.Mask" "F.Paste")
			(net "GND")
		)
		(pad "3" smd rect
			(at 0.25019 1.1684 180)
			(size 0.3048 1.524)
			(layers "F.Cu" "F.Mask" "F.Paste")
			(net "P1V8_PWR")
		)
		(pad "4" smd rect
			(at 0.75057 1.1684 180)
			(size 0.3048 1.524)
			(layers "F.Cu" "F.Mask" "F.Paste")
			(net "Z50_SSD_A1_SMB_CLK_LR")
		)
		(pad "5" smd rect
			(at 0.75057 -1.1684 180)
			(size 0.3048 1.524)
			(layers "F.Cu" "F.Mask" "F.Paste")
			(net "Z50_SSD_A1_SMB_DATA_LR")
		)
		(pad "6" smd rect
			(at 0.25019 -1.1684 180)
			(size 0.3048 1.524)
			(layers "F.Cu" "F.Mask" "F.Paste")
			(net "SSD_A1_SMB_OE")
		)
		(pad "7" smd rect
			(at -0.25019 -1.1684 180)
			(size 0.3048 1.524)
			(layers "F.Cu" "F.Mask" "F.Paste")
			(net "P3V3_DPB")
		)
		(pad "8" smd rect
			(at -0.75057 -1.1684 180)
			(size 0.3048 1.524)
			(layers "F.Cu" "F.Mask" "F.Paste")
			(net "Z50_SSD_A1_SMB_DATA_LL")
		)
	)
	(footprint ""
		(layer "F.Cu")
		(at 25.146 -71.755)
		(property "Reference" "R55"
			(at 0 0 0)
			(layer "F.SilkS")
			(hide yes)
			(effects
				(font
					(size 1.27 1.27)
				)
			)
		)
		(property "Value" "33R2J-2-GP"
			(at 0.064008 -3.993896 0)
			(unlocked yes)
			(layer "F.Fab")
			(hide yes)
			(effects
				(font
					(size 1.016 1.016)
					(thickness 0.1524)
				)
			)
		)
		(property "Device Type" "R402H16"
			(at 0.064008 -5.517896 0)
			(unlocked yes)
			(layer "F.Fab")
			(hide yes)
			(effects
				(font
					(size 1.016 1.016)
					(thickness 0.1524)
				)
			)
		)
		(duplicate_pad_numbers_are_jumpers no)
		(fp_line
			(start -0.508 -0.9398)
			(end -0.508 0.9398)
			(stroke
				(width 0.1524)
				(type default)
			)
			(layer "F.SilkS")
		)
		(fp_line
			(start 0.508 -0.9398)
			(end -0.508 -0.9398)
			(stroke
				(width 0.1524)
				(type default)
			)
			(layer "F.SilkS")
		)
		(fp_rect
			(start -0.508 0.9398)
			(end 0.508 -0.9398)
			(stroke
				(width 0)
				(type default)
			)
			(fill no)
			(layer "F.CrtYd")
		)
		(fp_rect
			(start -0.508 0.9398)
			(end 0.508 -0.9398)
			(stroke
				(width 0)
				(type default)
			)
			(fill no)
			(layer "F.Fab")
		)
		(pad "1" smd custom
			(at 0 -0.4445)
			(size 0.1397 0.1397)
			(layers "F.Cu" "F.Mask" "F.Paste")
			(net "Z50_SSD_A1_SMB_DATA_LR")
			(options
				(clearance outline)
				(anchor circle)
			)
			(primitives
				(gr_poly
					(pts
						(arc
							(start -0.1778 -0.2794)
							(mid -0.249642 -0.249642)
							(end -0.2794 -0.1778)
						)
						(arc
							(start -0.2794 0.1778)
							(mid -0.249642 0.249642)
							(end -0.1778 0.2794)
						)
						(arc
							(start 0.1778 0.2794)
							(mid 0.249642 0.249642)
							(end 0.2794 0.1778)
						)
						(arc
							(start 0.2794 -0.1778)
							(mid 0.249642 -0.249642)
							(end 0.1778 -0.2794)
						)
					)
					(width 0)
					(fill yes)
				)
			)
		)
		(pad "2" smd custom
			(at 0 0.4445)
			(size 0.1397 0.1397)
			(layers "F.Cu" "F.Mask" "F.Paste")
			(net "Z50_SSD_A1_SMB_DATA")
			(options
				(clearance outline)
				(anchor circle)
			)
			(primitives
				(gr_poly
					(pts
						(arc
							(start -0.1778 -0.2794)
							(mid -0.249642 -0.249642)
							(end -0.2794 -0.1778)
						)
						(arc
							(start -0.2794 0.1778)
							(mid -0.249642 0.249642)
							(end -0.1778 0.2794)
						)
						(arc
							(start 0.1778 0.2794)
							(mid 0.249642 0.249642)
							(end 0.2794 0.1778)
						)
						(arc
							(start 0.2794 -0.1778)
							(mid 0.249642 -0.249642)
							(end 0.1778 -0.2794)
						)
					)
					(width 0)
					(fill yes)
				)
			)
		)
	)
	(footprint ""
		(layer "F.Cu")
		(at 37.338 -80.264)
		(property "Reference" "PC37"
			(at 0 0 0)
			(layer "F.SilkS")
			(hide yes)
			(effects
				(font
					(size 1.27 1.27)
				)
			)
		)
		(property "Value" "SC10U16V5KX-1-GP"
			(at -0.0762 -6.1214 0)
			(unlocked yes)
			(layer "F.Fab")
			(hide yes)
			(effects
				(font
					(size 1.016 1.016)
					(thickness 0.1524)
				)
			)
		)
		(property "Device Type" "C805H54"
			(at -0.0762 -8.1534 0)
			(unlocked yes)
			(layer "F.Fab")
			(hide yes)
			(effects
				(font
					(size 1.016 1.016)
					(thickness 0.1524)
				)
			)
		)
		(duplicate_pad_numbers_are_jumpers no)
		(fp_line
			(start 0.635 0)
			(end -0.635 0)
			(stroke
				(width 0.508)
				(type default)
			)
			(layer "F.SilkS")
		)
		(fp_rect
			(start -0.9652 1.778)
			(end 0.9652 -1.778)
			(stroke
				(width 0)
				(type default)
			)
			(fill no)
			(layer "F.CrtYd")
		)
		(fp_poly
			(pts
				(xy -0.9652 -1.778) (xy 0.9652 -1.778) (xy 0.9652 1.778) (xy -0.9652 1.778)
			)
			(stroke
				(width 0)
				(type default)
			)
			(fill no)
			(layer "F.Fab")
		)
		(pad "1" smd rect
			(at 0 -0.9652)
			(size 1.397 1.143)
			(layers "F.Cu" "F.Mask" "F.Paste")
			(net "P3V3_DEV_VIN")
		)
		(pad "2" smd rect
			(at 0 0.9652)
			(size 1.397 1.143)
			(layers "F.Cu" "F.Mask" "F.Paste")
			(net "GND")
		)
	)
	(footprint ""
		(layer "B.Cu")
		(at 23.495 -77.216)
		(property "Reference" "R61"
			(at 0 0 0)
			(layer "B.SilkS")
			(hide yes)
			(effects
				(font
					(size 1.27 1.27)
				)
				(justify mirror)
			)
		)
		(property "Value" "0R2J-2-GP"
			(at -0.064008 -3.993896 0)
			(unlocked yes)
			(layer "B.Fab")
			(hide yes)
			(effects
				(font
					(size 1.016 1.016)
					(thickness 0.1524)
				)
				(justify mirror)
			)
		)
		(property "Device Type" "R402H16"
			(at -0.064008 -5.517896 0)
			(unlocked yes)
			(layer "B.Fab")
			(hide yes)
			(effects
				(font
					(size 1.016 1.016)
					(thickness 0.1524)
				)
				(justify mirror)
			)
		)
		(duplicate_pad_numbers_are_jumpers no)
		(fp_line
			(start -0.508 -0.9398)
			(end 0.508 -0.9398)
			(stroke
				(width 0.1524)
				(type default)
			)
			(layer "B.SilkS")
		)
		(fp_line
			(start 0.508 -0.9398)
			(end 0.508 0.9398)
			(stroke
				(width 0.1524)
				(type default)
			)
			(layer "B.SilkS")
		)
		(fp_rect
			(start 0.508 0.9398)
			(end -0.508 -0.9398)
			(stroke
				(width 0)
				(type default)
			)
			(fill no)
			(layer "B.CrtYd")
		)
		(fp_rect
			(start 0.508 0.9398)
			(end -0.508 -0.9398)
			(stroke
				(width 0)
				(type default)
			)
			(fill no)
			(layer "B.Fab")
		)
		(pad "1" smd custom
			(at 0 -0.4445 180)
			(size 0.1397 0.1397)
			(layers "B.Cu" "B.Mask" "B.Paste")
			(net "Z50_SSD_A1_SMB_DATA_R")
			(options
				(clearance outline)
				(anchor circle)
			)
			(primitives
				(gr_poly
					(pts
						(arc
							(start -0.1778 0.2794)
							(mid -0.249642 0.249642)
							(end -0.2794 0.1778)
						)
						(arc
							(start -0.2794 -0.1778)
							(mid -0.249642 -0.249642)
							(end -0.1778 -0.2794)
						)
						(arc
							(start 0.1778 -0.2794)
							(mid 0.249642 -0.249642)
							(end 0.2794 -0.1778)
						)
						(arc
							(start 0.2794 0.1778)
							(mid 0.249642 0.249642)
							(end 0.1778 0.2794)
						)
					)
					(width 0)
					(fill yes)
				)
			)
		)
		(pad "2" smd custom
			(at 0 0.4445 180)
			(size 0.1397 0.1397)
			(layers "B.Cu" "B.Mask" "B.Paste")
			(net "Z50_SSD_A1_SMB_DATA")
			(options
				(clearance outline)
				(anchor circle)
			)
			(primitives
				(gr_poly
					(pts
						(arc
							(start -0.1778 0.2794)
							(mid -0.249642 0.249642)
							(end -0.2794 0.1778)
						)
						(arc
							(start -0.2794 -0.1778)
							(mid -0.249642 -0.249642)
							(end -0.1778 -0.2794)
						)
						(arc
							(start 0.1778 -0.2794)
							(mid 0.249642 -0.249642)
							(end 0.2794 -0.1778)
						)
						(arc
							(start 0.2794 0.1778)
							(mid 0.249642 0.249642)
							(end 0.1778 0.2794)
						)
					)
					(width 0)
					(fill yes)
				)
			)
		)
	)
	(footprint ""
		(layer "B.Cu")
		(at 59.260994 -40.259)
		(property "Reference" "R7"
			(at 0 0 0)
			(layer "B.SilkS")
			(hide yes)
			(effects
				(font
					(size 1.27 1.27)
				)
				(justify mirror)
			)
		)
		(property "Value" "4K7R2F-GP"
			(at -0.064008 -3.993896 0)
			(unlocked yes)
			(layer "B.Fab")
			(hide yes)
			(effects
				(font
					(size 1.016 1.016)
					(thickness 0.1524)
				)
				(justify mirror)
			)
		)
		(property "Device Type" "R402H16"
			(at -0.064008 -5.517896 0)
			(unlocked yes)
			(layer "B.Fab")
			(hide yes)
			(effects
				(font
					(size 1.016 1.016)
					(thickness 0.1524)
				)
				(justify mirror)
			)
		)
		(duplicate_pad_numbers_are_jumpers no)
		(fp_line
			(start -0.508 -0.9398)
			(end 0.508 -0.9398)
			(stroke
				(width 0.1524)
				(type default)
			)
			(layer "B.SilkS")
		)
		(fp_line
			(start 0.508 -0.9398)
			(end 0.508 0.9398)
			(stroke
				(width 0.1524)
				(type default)
			)
			(layer "B.SilkS")
		)
		(fp_rect
			(start 0.508 0.9398)
			(end -0.508 -0.9398)
			(stroke
				(width 0)
				(type default)
			)
			(fill no)
			(layer "B.CrtYd")
		)
		(fp_rect
			(start 0.508 0.9398)
			(end -0.508 -0.9398)
			(stroke
				(width 0)
				(type default)
			)
			(fill no)
			(layer "B.Fab")
		)
		(pad "1" smd custom
			(at 0 -0.4445 180)
			(size 0.1397 0.1397)
			(layers "B.Cu" "B.Mask" "B.Paste")
			(net "P3V3_DPB")
			(options
				(clearance outline)
				(anchor circle)
			)
			(primitives
				(gr_poly
					(pts
						(arc
							(start -0.1778 0.2794)
							(mid -0.249642 0.249642)
							(end -0.2794 0.1778)
						)
						(arc
							(start -0.2794 -0.1778)
							(mid -0.249642 -0.249642)
							(end -0.1778 -0.2794)
						)
						(arc
							(start 0.1778 -0.2794)
							(mid 0.249642 -0.249642)
							(end 0.2794 -0.1778)
						)
						(arc
							(start 0.2794 0.1778)
							(mid 0.249642 0.249642)
							(end 0.1778 0.2794)
						)
					)
					(width 0)
					(fill yes)
				)
			)
		)
		(pad "2" smd custom
			(at 0 0.4445 180)
			(size 0.1397 0.1397)
			(layers "B.Cu" "B.Mask" "B.Paste")
			(net "Z50_TEMP_1_A1")
			(options
				(clearance outline)
				(anchor circle)
			)
			(primitives
				(gr_poly
					(pts
						(arc
							(start -0.1778 0.2794)
							(mid -0.249642 0.249642)
							(end -0.2794 0.1778)
						)
						(arc
							(start -0.2794 -0.1778)
							(mid -0.249642 -0.249642)
							(end -0.1778 -0.2794)
						)
						(arc
							(start 0.1778 -0.2794)
							(mid 0.249642 -0.249642)
							(end 0.2794 -0.1778)
						)
						(arc
							(start 0.2794 0.1778)
							(mid 0.249642 0.249642)
							(end 0.1778 0.2794)
						)
					)
					(width 0)
					(fill yes)
				)
			)
		)
	)
	(footprint ""
		(layer "B.Cu")
		(at 58.244994 -40.259 180)
		(property "Reference" "R11"
			(at 0 0 0)
			(layer "B.SilkS")
			(hide yes)
			(effects
				(font
					(size 1.27 1.27)
				)
				(justify mirror)
			)
		)
		(property "Value" "4K7R2F-GP"
			(at -0.064008 -3.993896 180)
			(unlocked yes)
			(layer "B.Fab")
			(hide yes)
			(effects
				(font
					(size 1.016 1.016)
					(thickness 0.1524)
				)
				(justify mirror)
			)
		)
		(property "Device Type" "R402H16"
			(at -0.064008 -5.517896 180)
			(unlocked yes)
			(layer "B.Fab")
			(hide yes)
			(effects
				(font
					(size 1.016 1.016)
					(thickness 0.1524)
				)
				(justify mirror)
			)
		)
		(duplicate_pad_numbers_are_jumpers no)
		(fp_line
			(start 0.508 -0.9398)
			(end 0.508 0.9398)
			(stroke
				(width 0.1524)
				(type default)
			)
			(layer "B.SilkS")
		)
		(fp_line
			(start -0.508 -0.9398)
			(end 0.508 -0.9398)
			(stroke
				(width 0.1524)
				(type default)
			)
			(layer "B.SilkS")
		)
		(fp_rect
			(start 0.508 0.9398)
			(end -0.508 -0.9398)
			(stroke
				(width 0)
				(type default)
			)
			(fill no)
			(layer "B.CrtYd")
		)
		(fp_rect
			(start 0.508 0.9398)
			(end -0.508 -0.9398)
			(stroke
				(width 0)
				(type default)
			)
			(fill no)
			(layer "B.Fab")
		)
		(pad "1" smd custom
			(at 0 -0.4445)
			(size 0.1397 0.1397)
			(layers "B.Cu" "B.Mask" "B.Paste")
			(net "Z50_TEMP_1_A1")
			(options
				(clearance outline)
				(anchor circle)
			)
			(primitives
				(gr_poly
					(pts
						(arc
							(start -0.1778 0.2794)
							(mid -0.249642 0.249642)
							(end -0.2794 0.1778)
						)
						(arc
							(start -0.2794 -0.1778)
							(mid -0.249642 -0.249642)
							(end -0.1778 -0.2794)
						)
						(arc
							(start 0.1778 -0.2794)
							(mid 0.249642 -0.249642)
							(end 0.2794 -0.1778)
						)
						(arc
							(start 0.2794 0.1778)
							(mid 0.249642 0.249642)
							(end 0.1778 0.2794)
						)
					)
					(width 0)
					(fill yes)
				)
			)
		)
		(pad "2" smd custom
			(at 0 0.4445)
			(size 0.1397 0.1397)
			(layers "B.Cu" "B.Mask" "B.Paste")
			(net "GND")
			(options
				(clearance outline)
				(anchor circle)
			)
			(primitives
				(gr_poly
					(pts
						(arc
							(start -0.1778 0.2794)
							(mid -0.249642 0.249642)
							(end -0.2794 0.1778)
						)
						(arc
							(start -0.2794 -0.1778)
							(mid -0.249642 -0.249642)
							(end -0.1778 -0.2794)
						)
						(arc
							(start 0.1778 -0.2794)
							(mid 0.249642 -0.249642)
							(end 0.2794 -0.1778)
						)
						(arc
							(start 0.2794 0.1778)
							(mid 0.249642 0.249642)
							(end 0.1778 0.2794)
						)
					)
					(width 0)
					(fill yes)
				)
			)
		)
	)
	(footprint ""
		(layer "B.Cu")
		(at 30.861 -86.233 180)
		(property "Reference" "R59"
			(at 0 0 0)
			(layer "B.SilkS")
			(hide yes)
			(effects
				(font
					(size 1.27 1.27)
				)
				(justify mirror)
			)
		)
		(property "Value" "47KR2F-GP"
			(at -0.064008 -3.993896 180)
			(unlocked yes)
			(layer "B.Fab")
			(hide yes)
			(effects
				(font
					(size 1.016 1.016)
					(thickness 0.1524)
				)
				(justify mirror)
			)
		)
		(property "Device Type" "R402H16"
			(at -0.064008 -5.517896 180)
			(unlocked yes)
			(layer "B.Fab")
			(hide yes)
			(effects
				(font
					(size 1.016 1.016)
					(thickness 0.1524)
				)
				(justify mirror)
			)
		)
		(duplicate_pad_numbers_are_jumpers no)
		(fp_line
			(start 0.508 -0.9398)
			(end 0.508 0.9398)
			(stroke
				(width 0.1524)
				(type default)
			)
			(layer "B.SilkS")
		)
		(fp_line
			(start -0.508 -0.9398)
			(end 0.508 -0.9398)
			(stroke
				(width 0.1524)
				(type default)
			)
			(layer "B.SilkS")
		)
		(fp_rect
			(start 0.508 0.9398)
			(end -0.508 -0.9398)
			(stroke
				(width 0)
				(type default)
			)
			(fill no)
			(layer "B.CrtYd")
		)
		(fp_rect
			(start 0.508 0.9398)
			(end -0.508 -0.9398)
			(stroke
				(width 0)
				(type default)
			)
			(fill no)
			(layer "B.Fab")
		)
		(pad "1" smd custom
			(at 0 -0.4445)
			(size 0.1397 0.1397)
			(layers "B.Cu" "B.Mask" "B.Paste")
			(net "Z50_SSD_B1_SMB_DATA_R")
			(options
				(clearance outline)
				(anchor circle)
			)
			(primitives
				(gr_poly
					(pts
						(arc
							(start -0.1778 0.2794)
							(mid -0.249642 0.249642)
							(end -0.2794 0.1778)
						)
						(arc
							(start -0.2794 -0.1778)
							(mid -0.249642 -0.249642)
							(end -0.1778 -0.2794)
						)
						(arc
							(start 0.1778 -0.2794)
							(mid 0.249642 -0.249642)
							(end 0.2794 -0.1778)
						)
						(arc
							(start 0.2794 0.1778)
							(mid 0.249642 0.249642)
							(end 0.1778 0.2794)
						)
					)
					(width 0)
					(fill yes)
				)
			)
		)
		(pad "2" smd custom
			(at 0 0.4445)
			(size 0.1397 0.1397)
			(layers "B.Cu" "B.Mask" "B.Paste")
			(net "P3V3_DPB")
			(options
				(clearance outline)
				(anchor circle)
			)
			(primitives
				(gr_poly
					(pts
						(arc
							(start -0.1778 0.2794)
							(mid -0.249642 0.249642)
							(end -0.2794 0.1778)
						)
						(arc
							(start -0.2794 -0.1778)
							(mid -0.249642 -0.249642)
							(end -0.1778 -0.2794)
						)
						(arc
							(start 0.1778 -0.2794)
							(mid 0.249642 -0.249642)
							(end 0.2794 -0.1778)
						)
						(arc
							(start 0.2794 0.1778)
							(mid 0.249642 0.249642)
							(end 0.1778 0.2794)
						)
					)
					(width 0)
					(fill yes)
				)
			)
		)
	)
	(footprint ""
		(layer "B.Cu")
		(at 68.707 -60.579 180)
		(property "Reference" "R49"
			(at 0 0 0)
			(layer "B.SilkS")
			(hide yes)
			(effects
				(font
					(size 1.27 1.27)
				)
				(justify mirror)
			)
		)
		(property "Value" "47KR2F-GP"
			(at -0.064008 -3.993896 180)
			(unlocked yes)
			(layer "B.Fab")
			(hide yes)
			(effects
				(font
					(size 1.016 1.016)
					(thickness 0.1524)
				)
				(justify mirror)
			)
		)
		(property "Device Type" "R402H16"
			(at -0.064008 -5.517896 180)
			(unlocked yes)
			(layer "B.Fab")
			(hide yes)
			(effects
				(font
					(size 1.016 1.016)
					(thickness 0.1524)
				)
				(justify mirror)
			)
		)
		(duplicate_pad_numbers_are_jumpers no)
		(fp_line
			(start 0.508 -0.9398)
			(end 0.508 0.9398)
			(stroke
				(width 0.1524)
				(type default)
			)
			(layer "B.SilkS")
		)
		(fp_line
			(start -0.508 -0.9398)
			(end 0.508 -0.9398)
			(stroke
				(width 0.1524)
				(type default)
			)
			(layer "B.SilkS")
		)
		(fp_rect
			(start 0.508 0.9398)
			(end -0.508 -0.9398)
			(stroke
				(width 0)
				(type default)
			)
			(fill no)
			(layer "B.CrtYd")
		)
		(fp_rect
			(start 0.508 0.9398)
			(end -0.508 -0.9398)
			(stroke
				(width 0)
				(type default)
			)
			(fill no)
			(layer "B.Fab")
		)
		(pad "1" smd custom
			(at 0 -0.4445)
			(size 0.1397 0.1397)
			(layers "B.Cu" "B.Mask" "B.Paste")
			(net "Z50_SSD_A_ACT#")
			(options
				(clearance outline)
				(anchor circle)
			)
			(primitives
				(gr_poly
					(pts
						(arc
							(start -0.1778 0.2794)
							(mid -0.249642 0.249642)
							(end -0.2794 0.1778)
						)
						(arc
							(start -0.2794 -0.1778)
							(mid -0.249642 -0.249642)
							(end -0.1778 -0.2794)
						)
						(arc
							(start 0.1778 -0.2794)
							(mid 0.249642 -0.249642)
							(end 0.2794 -0.1778)
						)
						(arc
							(start 0.2794 0.1778)
							(mid 0.249642 0.249642)
							(end 0.1778 0.2794)
						)
					)
					(width 0)
					(fill yes)
				)
			)
		)
		(pad "2" smd custom
			(at 0 0.4445)
			(size 0.1397 0.1397)
			(layers "B.Cu" "B.Mask" "B.Paste")
			(net "GND")
			(options
				(clearance outline)
				(anchor circle)
			)
			(primitives
				(gr_poly
					(pts
						(arc
							(start -0.1778 0.2794)
							(mid -0.249642 0.249642)
							(end -0.2794 0.1778)
						)
						(arc
							(start -0.2794 -0.1778)
							(mid -0.249642 -0.249642)
							(end -0.1778 -0.2794)
						)
						(arc
							(start 0.1778 -0.2794)
							(mid 0.249642 -0.249642)
							(end 0.2794 -0.1778)
						)
						(arc
							(start 0.2794 0.1778)
							(mid 0.249642 0.249642)
							(end 0.1778 0.2794)
						)
					)
					(width 0)
					(fill yes)
				)
			)
		)
	)
	(footprint ""
		(layer "B.Cu")
		(at 65.151 -22.479 90)
		(property "Reference" "R42"
			(at 0 0 90)
			(layer "B.SilkS")
			(hide yes)
			(effects
				(font
					(size 1.27 1.27)
				)
				(justify mirror)
			)
		)
		(property "Value" "4K7R2F-GP"
			(at -0.064008 -3.993896 90)
			(unlocked yes)
			(layer "B.Fab")
			(hide yes)
			(effects
				(font
					(size 1.016 1.016)
					(thickness 0.1524)
				)
				(justify mirror)
			)
		)
		(property "Device Type" "R402H16"
			(at -0.064008 -5.517896 90)
			(unlocked yes)
			(layer "B.Fab")
			(hide yes)
			(effects
				(font
					(size 1.016 1.016)
					(thickness 0.1524)
				)
				(justify mirror)
			)
		)
		(duplicate_pad_numbers_are_jumpers no)
		(fp_line
			(start 0.508 -0.9398)
			(end 0.508 0.9398)
			(stroke
				(width 0.1524)
				(type default)
			)
			(layer "B.SilkS")
		)
		(fp_line
			(start -0.508 -0.9398)
			(end 0.508 -0.9398)
			(stroke
				(width 0.1524)
				(type default)
			)
			(layer "B.SilkS")
		)
		(fp_rect
			(start 0.508 0.9398)
			(end -0.508 -0.9398)
			(stroke
				(width 0)
				(type default)
			)
			(fill no)
			(layer "B.CrtYd")
		)
		(fp_rect
			(start 0.508 0.9398)
			(end -0.508 -0.9398)
			(stroke
				(width 0)
				(type default)
			)
			(fill no)
			(layer "B.Fab")
		)
		(pad "1" smd custom
			(at 0 -0.4445 270)
			(size 0.1397 0.1397)
			(layers "B.Cu" "B.Mask" "B.Paste")
			(net "P3V3_PWR")
			(options
				(clearance outline)
				(anchor circle)
			)
			(primitives
				(gr_poly
					(pts
						(arc
							(start -0.1778 0.2794)
							(mid -0.249642 0.249642)
							(end -0.2794 0.1778)
						)
						(arc
							(start -0.2794 -0.1778)
							(mid -0.249642 -0.249642)
							(end -0.1778 -0.2794)
						)
						(arc
							(start 0.1778 -0.2794)
							(mid 0.249642 -0.249642)
							(end 0.2794 -0.1778)
						)
						(arc
							(start 0.2794 0.1778)
							(mid 0.249642 0.249642)
							(end 0.1778 0.2794)
						)
					)
					(width 0)
					(fill yes)
				)
			)
		)
		(pad "2" smd custom
			(at 0 0.4445 270)
			(size 0.1397 0.1397)
			(layers "B.Cu" "B.Mask" "B.Paste")
			(net "Z50_SSD_B1_CLKREQ#")
			(options
				(clearance outline)
				(anchor circle)
			)
			(primitives
				(gr_poly
					(pts
						(arc
							(start -0.1778 0.2794)
							(mid -0.249642 0.249642)
							(end -0.2794 0.1778)
						)
						(arc
							(start -0.2794 -0.1778)
							(mid -0.249642 -0.249642)
							(end -0.1778 -0.2794)
						)
						(arc
							(start 0.1778 -0.2794)
							(mid 0.249642 -0.249642)
							(end 0.2794 -0.1778)
						)
						(arc
							(start 0.2794 0.1778)
							(mid 0.249642 0.249642)
							(end 0.1778 0.2794)
						)
					)
					(width 0)
					(fill yes)
				)
			)
		)
	)
	(footprint ""
		(layer "B.Cu")
		(at 30.226 -78.74)
		(property "Reference" "R60"
			(at 0 0 0)
			(layer "B.SilkS")
			(hide yes)
			(effects
				(font
					(size 1.27 1.27)
				)
				(justify mirror)
			)
		)
		(property "Value" "47KR2F-GP"
			(at -0.064008 -3.993896 0)
			(unlocked yes)
			(layer "B.Fab")
			(hide yes)
			(effects
				(font
					(size 1.016 1.016)
					(thickness 0.1524)
				)
				(justify mirror)
			)
		)
		(property "Device Type" "R402H16"
			(at -0.064008 -5.517896 0)
			(unlocked yes)
			(layer "B.Fab")
			(hide yes)
			(effects
				(font
					(size 1.016 1.016)
					(thickness 0.1524)
				)
				(justify mirror)
			)
		)
		(duplicate_pad_numbers_are_jumpers no)
		(fp_line
			(start -0.508 -0.9398)
			(end 0.508 -0.9398)
			(stroke
				(width 0.1524)
				(type default)
			)
			(layer "B.SilkS")
		)
		(fp_line
			(start 0.508 -0.9398)
			(end 0.508 0.9398)
			(stroke
				(width 0.1524)
				(type default)
			)
			(layer "B.SilkS")
		)
		(fp_rect
			(start 0.508 0.9398)
			(end -0.508 -0.9398)
			(stroke
				(width 0)
				(type default)
			)
			(fill no)
			(layer "B.CrtYd")
		)
		(fp_rect
			(start 0.508 0.9398)
			(end -0.508 -0.9398)
			(stroke
				(width 0)
				(type default)
			)
			(fill no)
			(layer "B.Fab")
		)
		(pad "1" smd custom
			(at 0 -0.4445 180)
			(size 0.1397 0.1397)
			(layers "B.Cu" "B.Mask" "B.Paste")
			(net "Z50_SSD_A1_SMB_CLK_R")
			(options
				(clearance outline)
				(anchor circle)
			)
			(primitives
				(gr_poly
					(pts
						(arc
							(start -0.1778 0.2794)
							(mid -0.249642 0.249642)
							(end -0.2794 0.1778)
						)
						(arc
							(start -0.2794 -0.1778)
							(mid -0.249642 -0.249642)
							(end -0.1778 -0.2794)
						)
						(arc
							(start 0.1778 -0.2794)
							(mid 0.249642 -0.249642)
							(end 0.2794 -0.1778)
						)
						(arc
							(start 0.2794 0.1778)
							(mid 0.249642 0.249642)
							(end 0.1778 0.2794)
						)
					)
					(width 0)
					(fill yes)
				)
			)
		)
		(pad "2" smd custom
			(at 0 0.4445 180)
			(size 0.1397 0.1397)
			(layers "B.Cu" "B.Mask" "B.Paste")
			(net "P3V3_DPB")
			(options
				(clearance outline)
				(anchor circle)
			)
			(primitives
				(gr_poly
					(pts
						(arc
							(start -0.1778 0.2794)
							(mid -0.249642 0.249642)
							(end -0.2794 0.1778)
						)
						(arc
							(start -0.2794 -0.1778)
							(mid -0.249642 -0.249642)
							(end -0.1778 -0.2794)
						)
						(arc
							(start 0.1778 -0.2794)
							(mid 0.249642 -0.249642)
							(end 0.2794 -0.1778)
						)
						(arc
							(start 0.2794 0.1778)
							(mid 0.249642 0.249642)
							(end 0.1778 0.2794)
						)
					)
					(width 0)
					(fill yes)
				)
			)
		)
	)
	(footprint ""
		(layer "B.Cu")
		(at 42.750994 -76.2 180)
		(property "Reference" "PR30"
			(at 0 0 0)
			(layer "B.SilkS")
			(hide yes)
			(effects
				(font
					(size 1.27 1.27)
				)
				(justify mirror)
			)
		)
		(property "Value" "100KR2F-L1-GP"
			(at -0.064008 -3.993896 180)
			(unlocked yes)
			(layer "B.Fab")
			(hide yes)
			(effects
				(font
					(size 1.016 1.016)
					(thickness 0.1524)
				)
				(justify mirror)
			)
		)
		(property "Device Type" "R402H16"
			(at -0.064008 -5.517896 180)
			(unlocked yes)
			(layer "B.Fab")
			(hide yes)
			(effects
				(font
					(size 1.016 1.016)
					(thickness 0.1524)
				)
				(justify mirror)
			)
		)
		(duplicate_pad_numbers_are_jumpers no)
		(fp_line
			(start 0.508 -0.9398)
			(end 0.508 0.9398)
			(stroke
				(width 0.1524)
				(type default)
			)
			(layer "B.SilkS")
		)
		(fp_line
			(start -0.508 -0.9398)
			(end 0.508 -0.9398)
			(stroke
				(width 0.1524)
				(type default)
			)
			(layer "B.SilkS")
		)
		(fp_rect
			(start 0.508 0.9398)
			(end -0.508 -0.9398)
			(stroke
				(width 0)
				(type default)
			)
			(fill no)
			(layer "B.CrtYd")
		)
		(fp_rect
			(start 0.508 0.9398)
			(end -0.508 -0.9398)
			(stroke
				(width 0)
				(type default)
			)
			(fill no)
			(layer "B.Fab")
		)
		(pad "1" smd custom
			(at 0 -0.4445)
			(size 0.1397 0.1397)
			(layers "B.Cu" "B.Mask" "B.Paste")
			(net "AGND_P3V3_DEV")
			(options
				(clearance outline)
				(anchor circle)
			)
			(primitives
				(gr_poly
					(pts
						(arc
							(start -0.1778 0.2794)
							(mid -0.249642 0.249642)
							(end -0.2794 0.1778)
						)
						(arc
							(start -0.2794 -0.1778)
							(mid -0.249642 -0.249642)
							(end -0.1778 -0.2794)
						)
						(arc
							(start 0.1778 -0.2794)
							(mid 0.249642 -0.249642)
							(end 0.2794 -0.1778)
						)
						(arc
							(start 0.2794 0.1778)
							(mid 0.249642 0.249642)
							(end 0.1778 0.2794)
						)
					)
					(width 0)
					(fill yes)
				)
			)
		)
		(pad "2" smd custom
			(at 0 0.4445)
			(size 0.1397 0.1397)
			(layers "B.Cu" "B.Mask" "B.Paste")
			(net "P3V3_DEV_MODE")
			(options
				(clearance outline)
				(anchor circle)
			)
			(primitives
				(gr_poly
					(pts
						(arc
							(start -0.1778 0.2794)
							(mid -0.249642 0.249642)
							(end -0.2794 0.1778)
						)
						(arc
							(start -0.2794 -0.1778)
							(mid -0.249642 -0.249642)
							(end -0.1778 -0.2794)
						)
						(arc
							(start 0.1778 -0.2794)
							(mid 0.249642 -0.249642)
							(end 0.2794 -0.1778)
						)
						(arc
							(start 0.2794 0.1778)
							(mid 0.249642 0.249642)
							(end 0.1778 0.2794)
						)
					)
					(width 0)
					(fill yes)
				)
			)
		)
	)
	(footprint ""
		(layer "B.Cu")
		(at 28.956 -71.755 180)
		(property "Reference" "R34"
			(at 0 0 0)
			(layer "B.SilkS")
			(hide yes)
			(effects
				(font
					(size 1.27 1.27)
				)
				(justify mirror)
			)
		)
		(property "Value" "47KR2F-GP"
			(at -0.064008 -3.993896 180)
			(unlocked yes)
			(layer "B.Fab")
			(hide yes)
			(effects
				(font
					(size 1.016 1.016)
					(thickness 0.1524)
				)
				(justify mirror)
			)
		)
		(property "Device Type" "R402H16"
			(at -0.064008 -5.517896 180)
			(unlocked yes)
			(layer "B.Fab")
			(hide yes)
			(effects
				(font
					(size 1.016 1.016)
					(thickness 0.1524)
				)
				(justify mirror)
			)
		)
		(duplicate_pad_numbers_are_jumpers no)
		(fp_line
			(start 0.508 -0.9398)
			(end 0.508 0.9398)
			(stroke
				(width 0.1524)
				(type default)
			)
			(layer "B.SilkS")
		)
		(fp_line
			(start -0.508 -0.9398)
			(end 0.508 -0.9398)
			(stroke
				(width 0.1524)
				(type default)
			)
			(layer "B.SilkS")
		)
		(fp_rect
			(start 0.508 0.9398)
			(end -0.508 -0.9398)
			(stroke
				(width 0)
				(type default)
			)
			(fill no)
			(layer "B.CrtYd")
		)
		(fp_rect
			(start 0.508 0.9398)
			(end -0.508 -0.9398)
			(stroke
				(width 0)
				(type default)
			)
			(fill no)
			(layer "B.Fab")
		)
		(pad "1" smd custom
			(at 0 -0.4445)
			(size 0.1397 0.1397)
			(layers "B.Cu" "B.Mask" "B.Paste")
			(net "Z50_SSD_B1_SMB_DATA")
			(options
				(clearance outline)
				(anchor circle)
			)
			(primitives
				(gr_poly
					(pts
						(arc
							(start -0.1778 0.2794)
							(mid -0.249642 0.249642)
							(end -0.2794 0.1778)
						)
						(arc
							(start -0.2794 -0.1778)
							(mid -0.249642 -0.249642)
							(end -0.1778 -0.2794)
						)
						(arc
							(start 0.1778 -0.2794)
							(mid 0.249642 -0.249642)
							(end 0.2794 -0.1778)
						)
						(arc
							(start 0.2794 0.1778)
							(mid 0.249642 0.249642)
							(end 0.1778 0.2794)
						)
					)
					(width 0)
					(fill yes)
				)
			)
		)
		(pad "2" smd custom
			(at 0 0.4445)
			(size 0.1397 0.1397)
			(layers "B.Cu" "B.Mask" "B.Paste")
			(net "P1V8_PWR")
			(options
				(clearance outline)
				(anchor circle)
			)
			(primitives
				(gr_poly
					(pts
						(arc
							(start -0.1778 0.2794)
							(mid -0.249642 0.249642)
							(end -0.2794 0.1778)
						)
						(arc
							(start -0.2794 -0.1778)
							(mid -0.249642 -0.249642)
							(end -0.1778 -0.2794)
						)
						(arc
							(start 0.1778 -0.2794)
							(mid 0.249642 -0.249642)
							(end 0.2794 -0.1778)
						)
						(arc
							(start 0.2794 0.1778)
							(mid 0.249642 0.249642)
							(end 0.1778 0.2794)
						)
					)
					(width 0)
					(fill yes)
				)
			)
		)
	)
	(footprint ""
		(layer "B.Cu")
		(at 62.738 -39.751 90)
		(property "Reference" "R9"
			(at 0 0 90)
			(layer "B.SilkS")
			(hide yes)
			(effects
				(font
					(size 1.27 1.27)
				)
				(justify mirror)
			)
		)
		(property "Value" "0R2J-2-GP"
			(at -0.064008 -3.993896 90)
			(unlocked yes)
			(layer "B.Fab")
			(hide yes)
			(effects
				(font
					(size 1.016 1.016)
					(thickness 0.1524)
				)
				(justify mirror)
			)
		)
		(property "Device Type" "R402H16"
			(at -0.064008 -5.517896 90)
			(unlocked yes)
			(layer "B.Fab")
			(hide yes)
			(effects
				(font
					(size 1.016 1.016)
					(thickness 0.1524)
				)
				(justify mirror)
			)
		)
		(duplicate_pad_numbers_are_jumpers no)
		(fp_line
			(start 0.508 -0.9398)
			(end 0.508 0.9398)
			(stroke
				(width 0.1524)
				(type default)
			)
			(layer "B.SilkS")
		)
		(fp_line
			(start -0.508 -0.9398)
			(end 0.508 -0.9398)
			(stroke
				(width 0.1524)
				(type default)
			)
			(layer "B.SilkS")
		)
		(fp_rect
			(start 0.508 0.9398)
			(end -0.508 -0.9398)
			(stroke
				(width 0)
				(type default)
			)
			(fill no)
			(layer "B.CrtYd")
		)
		(fp_rect
			(start 0.508 0.9398)
			(end -0.508 -0.9398)
			(stroke
				(width 0)
				(type default)
			)
			(fill no)
			(layer "B.Fab")
		)
		(pad "1" smd custom
			(at 0 -0.4445 270)
			(size 0.1397 0.1397)
			(layers "B.Cu" "B.Mask" "B.Paste")
			(net "Z50_SMB_CLK")
			(options
				(clearance outline)
				(anchor circle)
			)
			(primitives
				(gr_poly
					(pts
						(arc
							(start -0.1778 0.2794)
							(mid -0.249642 0.249642)
							(end -0.2794 0.1778)
						)
						(arc
							(start -0.2794 -0.1778)
							(mid -0.249642 -0.249642)
							(end -0.1778 -0.2794)
						)
						(arc
							(start 0.1778 -0.2794)
							(mid 0.249642 -0.249642)
							(end 0.2794 -0.1778)
						)
						(arc
							(start 0.2794 0.1778)
							(mid 0.249642 0.249642)
							(end 0.1778 0.2794)
						)
					)
					(width 0)
					(fill yes)
				)
			)
		)
		(pad "2" smd custom
			(at 0 0.4445 270)
			(size 0.1397 0.1397)
			(layers "B.Cu" "B.Mask" "B.Paste")
			(net "Z50_TEMP_1_CLK")
			(options
				(clearance outline)
				(anchor circle)
			)
			(primitives
				(gr_poly
					(pts
						(arc
							(start -0.1778 0.2794)
							(mid -0.249642 0.249642)
							(end -0.2794 0.1778)
						)
						(arc
							(start -0.2794 -0.1778)
							(mid -0.249642 -0.249642)
							(end -0.1778 -0.2794)
						)
						(arc
							(start 0.1778 -0.2794)
							(mid 0.249642 -0.249642)
							(end 0.2794 -0.1778)
						)
						(arc
							(start 0.2794 0.1778)
							(mid 0.249642 0.249642)
							(end 0.1778 0.2794)
						)
					)
					(width 0)
					(fill yes)
				)
			)
		)
	)
	(footprint ""
		(layer "B.Cu")
		(at 25.4 -74.676)
		(property "Reference" "R57"
			(at 0 0 0)
			(layer "B.SilkS")
			(hide yes)
			(effects
				(font
					(size 1.27 1.27)
				)
				(justify mirror)
			)
		)
		(property "Value" "10KR2F-2-GP"
			(at -0.064008 -3.993896 0)
			(unlocked yes)
			(layer "B.Fab")
			(hide yes)
			(effects
				(font
					(size 1.016 1.016)
					(thickness 0.1524)
				)
				(justify mirror)
			)
		)
		(property "Device Type" "R402H16"
			(at -0.064008 -5.517896 0)
			(unlocked yes)
			(layer "B.Fab")
			(hide yes)
			(effects
				(font
					(size 1.016 1.016)
					(thickness 0.1524)
				)
				(justify mirror)
			)
		)
		(duplicate_pad_numbers_are_jumpers no)
		(fp_line
			(start -0.508 -0.9398)
			(end 0.508 -0.9398)
			(stroke
				(width 0.1524)
				(type default)
			)
			(layer "B.SilkS")
		)
		(fp_line
			(start 0.508 -0.9398)
			(end 0.508 0.9398)
			(stroke
				(width 0.1524)
				(type default)
			)
			(layer "B.SilkS")
		)
		(fp_rect
			(start 0.508 0.9398)
			(end -0.508 -0.9398)
			(stroke
				(width 0)
				(type default)
			)
			(fill no)
			(layer "B.CrtYd")
		)
		(fp_rect
			(start 0.508 0.9398)
			(end -0.508 -0.9398)
			(stroke
				(width 0)
				(type default)
			)
			(fill no)
			(layer "B.Fab")
		)
		(pad "1" smd custom
			(at 0 -0.4445 180)
			(size 0.1397 0.1397)
			(layers "B.Cu" "B.Mask" "B.Paste")
			(net "P3V3_PWR")
			(options
				(clearance outline)
				(anchor circle)
			)
			(primitives
				(gr_poly
					(pts
						(arc
							(start -0.1778 0.2794)
							(mid -0.249642 0.249642)
							(end -0.2794 0.1778)
						)
						(arc
							(start -0.2794 -0.1778)
							(mid -0.249642 -0.249642)
							(end -0.1778 -0.2794)
						)
						(arc
							(start 0.1778 -0.2794)
							(mid 0.249642 -0.249642)
							(end 0.2794 -0.1778)
						)
						(arc
							(start 0.2794 0.1778)
							(mid 0.249642 0.249642)
							(end 0.1778 0.2794)
						)
					)
					(width 0)
					(fill yes)
				)
			)
		)
		(pad "2" smd custom
			(at 0 0.4445 180)
			(size 0.1397 0.1397)
			(layers "B.Cu" "B.Mask" "B.Paste")
			(net "SSD_A1_SMB_OE")
			(options
				(clearance outline)
				(anchor circle)
			)
			(primitives
				(gr_poly
					(pts
						(arc
							(start -0.1778 0.2794)
							(mid -0.249642 0.249642)
							(end -0.2794 0.1778)
						)
						(arc
							(start -0.2794 -0.1778)
							(mid -0.249642 -0.249642)
							(end -0.1778 -0.2794)
						)
						(arc
							(start 0.1778 -0.2794)
							(mid 0.249642 -0.249642)
							(end 0.2794 -0.1778)
						)
						(arc
							(start 0.2794 0.1778)
							(mid 0.249642 0.249642)
							(end 0.1778 0.2794)
						)
					)
					(width 0)
					(fill yes)
				)
			)
		)
	)
	(footprint ""
		(layer "B.Cu")
		(at 60.579 -45.593 -90)
		(property "Reference" "C17"
			(at 0 0 90)
			(layer "B.SilkS")
			(hide yes)
			(effects
				(font
					(size 1.27 1.27)
				)
				(justify mirror)
			)
		)
		(property "Value" "SC10U6D3V5KX-4GP"
			(at 0.0762 -6.1214 270)
			(unlocked yes)
			(layer "B.Fab")
			(hide yes)
			(effects
				(font
					(size 1.016 1.016)
					(thickness 0.1524)
				)
				(justify mirror)
			)
		)
		(property "Device Type" "C805H58"
			(at 0.0762 -8.1534 270)
			(unlocked yes)
			(layer "B.Fab")
			(hide yes)
			(effects
				(font
					(size 1.016 1.016)
					(thickness 0.1524)
				)
				(justify mirror)
			)
		)
		(duplicate_pad_numbers_are_jumpers no)
		(fp_line
			(start -0.635 0)
			(end 0.635 0)
			(stroke
				(width 0.508)
				(type default)
			)
			(layer "B.SilkS")
		)
		(fp_rect
			(start 0.9652 1.778)
			(end -0.9652 -1.778)
			(stroke
				(width 0)
				(type default)
			)
			(fill no)
			(layer "B.CrtYd")
		)
		(fp_poly
			(pts
				(xy 0.9652 -1.778) (xy -0.9652 -1.778) (xy -0.9652 1.778) (xy 0.9652 1.778)
			)
			(stroke
				(width 0)
				(type default)
			)
			(fill no)
			(layer "B.Fab")
		)
		(pad "1" smd rect
			(at 0 -0.9652 90)
			(size 1.397 1.143)
			(layers "B.Cu" "B.Mask" "B.Paste")
			(net "P3V3_PWR")
		)
		(pad "2" smd rect
			(at 0 0.9652 90)
			(size 1.397 1.143)
			(layers "B.Cu" "B.Mask" "B.Paste")
			(net "GND")
		)
	)
	(footprint ""
		(layer "B.Cu")
		(at 65.913 -20.913852)
		(property "Reference" "TP9"
			(at 0 0 0)
			(layer "B.SilkS")
			(hide yes)
			(effects
				(font
					(size 1.27 1.27)
				)
				(justify mirror)
			)
		)
		(property "Value" "TPAD28-1-GP-U"
			(at -0.0508 -1.9304 0)
			(unlocked yes)
			(layer "B.Fab")
			(hide yes)
			(effects
				(font
					(size 1.016 1.016)
					(thickness 0.1524)
				)
				(justify mirror)
			)
		)
		(property "Device Type" "TPAD28-1-U"
			(at -0.0508 -3.4544 0)
			(unlocked yes)
			(layer "B.Fab")
			(hide yes)
			(effects
				(font
					(size 1.016 1.016)
					(thickness 0.1524)
				)
				(justify mirror)
			)
		)
		(duplicate_pad_numbers_are_jumpers no)
		(fp_poly
			(pts
				(arc
					(start 0.3556 0)
					(mid -0.3556 0)
					(end 0.3556 0)
				)
			)
			(stroke
				(width 0)
				(type default)
			)
			(fill no)
			(layer "B.CrtYd")
		)
		(fp_poly
			(pts
				(arc
					(start 0.9525 0)
					(mid -0.9525 0)
					(end 0.9525 0)
				)
			)
			(stroke
				(width 0)
				(type default)
			)
			(fill no)
			(layer "B.Fab")
		)
		(pad "1" smd circle
			(at 0 0 180)
			(size 0.7112 0.7112)
			(layers "B.Cu" "B.Mask" "B.Paste")
			(net "SSD_B1_MFG_DATA_TP")
		)
	)
	(footprint ""
		(layer "B.Cu")
		(at 55.450994 -77.724)
		(property "Reference" "PR26"
			(at 0 0 0)
			(layer "B.SilkS")
			(hide yes)
			(effects
				(font
					(size 1.27 1.27)
				)
				(justify mirror)
			)
		)
		(property "Value" "2KR2F-3-GP"
			(at -0.064008 -3.993896 0)
			(unlocked yes)
			(layer "B.Fab")
			(hide yes)
			(effects
				(font
					(size 1.016 1.016)
					(thickness 0.1524)
				)
				(justify mirror)
			)
		)
		(property "Device Type" "R402H16"
			(at -0.064008 -5.517896 0)
			(unlocked yes)
			(layer "B.Fab")
			(hide yes)
			(effects
				(font
					(size 1.016 1.016)
					(thickness 0.1524)
				)
				(justify mirror)
			)
		)
		(duplicate_pad_numbers_are_jumpers no)
		(fp_line
			(start -0.508 -0.9398)
			(end 0.508 -0.9398)
			(stroke
				(width 0.1524)
				(type default)
			)
			(layer "B.SilkS")
		)
		(fp_line
			(start 0.508 -0.9398)
			(end 0.508 0.9398)
			(stroke
				(width 0.1524)
				(type default)
			)
			(layer "B.SilkS")
		)
		(fp_rect
			(start 0.508 0.9398)
			(end -0.508 -0.9398)
			(stroke
				(width 0)
				(type default)
			)
			(fill no)
			(layer "B.CrtYd")
		)
		(fp_rect
			(start 0.508 0.9398)
			(end -0.508 -0.9398)
			(stroke
				(width 0)
				(type default)
			)
			(fill no)
			(layer "B.Fab")
		)
		(pad "1" smd custom
			(at 0 -0.4445 180)
			(size 0.1397 0.1397)
			(layers "B.Cu" "B.Mask" "B.Paste")
			(net "P3V3_DEV_LL")
			(options
				(clearance outline)
				(anchor circle)
			)
			(primitives
				(gr_poly
					(pts
						(arc
							(start -0.1778 0.2794)
							(mid -0.249642 0.249642)
							(end -0.2794 0.1778)
						)
						(arc
							(start -0.2794 -0.1778)
							(mid -0.249642 -0.249642)
							(end -0.1778 -0.2794)
						)
						(arc
							(start 0.1778 -0.2794)
							(mid 0.249642 -0.249642)
							(end 0.2794 -0.1778)
						)
						(arc
							(start 0.2794 0.1778)
							(mid 0.249642 0.249642)
							(end 0.1778 0.2794)
						)
					)
					(width 0)
					(fill yes)
				)
			)
		)
		(pad "2" smd custom
			(at 0 0.4445 180)
			(size 0.1397 0.1397)
			(layers "B.Cu" "B.Mask" "B.Paste")
			(net "P3V3_DEV_LL_R")
			(options
				(clearance outline)
				(anchor circle)
			)
			(primitives
				(gr_poly
					(pts
						(arc
							(start -0.1778 0.2794)
							(mid -0.249642 0.249642)
							(end -0.2794 0.1778)
						)
						(arc
							(start -0.2794 -0.1778)
							(mid -0.249642 -0.249642)
							(end -0.1778 -0.2794)
						)
						(arc
							(start 0.1778 -0.2794)
							(mid 0.249642 -0.249642)
							(end 0.2794 -0.1778)
						)
						(arc
							(start 0.2794 0.1778)
							(mid 0.249642 0.249642)
							(end 0.1778 0.2794)
						)
					)
					(width 0)
					(fill yes)
				)
			)
		)
	)
	(footprint ""
		(layer "B.Cu")
		(at 50.751994 -76.835 180)
		(property "Reference" "PR28"
			(at 0 0 0)
			(layer "B.SilkS")
			(hide yes)
			(effects
				(font
					(size 1.27 1.27)
				)
				(justify mirror)
			)
		)
		(property "Value" "10KR2F-2-GP"
			(at -0.064008 -3.993896 180)
			(unlocked yes)
			(layer "B.Fab")
			(hide yes)
			(effects
				(font
					(size 1.016 1.016)
					(thickness 0.1524)
				)
				(justify mirror)
			)
		)
		(property "Device Type" "R402H16"
			(at -0.064008 -5.517896 180)
			(unlocked yes)
			(layer "B.Fab")
			(hide yes)
			(effects
				(font
					(size 1.016 1.016)
					(thickness 0.1524)
				)
				(justify mirror)
			)
		)
		(duplicate_pad_numbers_are_jumpers no)
		(fp_line
			(start 0.508 -0.9398)
			(end 0.508 0.9398)
			(stroke
				(width 0.1524)
				(type default)
			)
			(layer "B.SilkS")
		)
		(fp_line
			(start -0.508 -0.9398)
			(end 0.508 -0.9398)
			(stroke
				(width 0.1524)
				(type default)
			)
			(layer "B.SilkS")
		)
		(fp_rect
			(start 0.508 0.9398)
			(end -0.508 -0.9398)
			(stroke
				(width 0)
				(type default)
			)
			(fill no)
			(layer "B.CrtYd")
		)
		(fp_rect
			(start 0.508 0.9398)
			(end -0.508 -0.9398)
			(stroke
				(width 0)
				(type default)
			)
			(fill no)
			(layer "B.Fab")
		)
		(pad "1" smd custom
			(at 0 -0.4445)
			(size 0.1397 0.1397)
			(layers "B.Cu" "B.Mask" "B.Paste")
			(net "AGND_P3V3_DEV")
			(options
				(clearance outline)
				(anchor circle)
			)
			(primitives
				(gr_poly
					(pts
						(arc
							(start -0.1778 0.2794)
							(mid -0.249642 0.249642)
							(end -0.2794 0.1778)
						)
						(arc
							(start -0.2794 -0.1778)
							(mid -0.249642 -0.249642)
							(end -0.1778 -0.2794)
						)
						(arc
							(start 0.1778 -0.2794)
							(mid 0.249642 -0.249642)
							(end 0.2794 -0.1778)
						)
						(arc
							(start 0.2794 0.1778)
							(mid 0.249642 0.249642)
							(end 0.1778 0.2794)
						)
					)
					(width 0)
					(fill yes)
				)
			)
		)
		(pad "2" smd custom
			(at 0 0.4445)
			(size 0.1397 0.1397)
			(layers "B.Cu" "B.Mask" "B.Paste")
			(net "P3V3_DEV_EN")
			(options
				(clearance outline)
				(anchor circle)
			)
			(primitives
				(gr_poly
					(pts
						(arc
							(start -0.1778 0.2794)
							(mid -0.249642 0.249642)
							(end -0.2794 0.1778)
						)
						(arc
							(start -0.2794 -0.1778)
							(mid -0.249642 -0.249642)
							(end -0.1778 -0.2794)
						)
						(arc
							(start 0.1778 -0.2794)
							(mid 0.249642 -0.249642)
							(end 0.2794 -0.1778)
						)
						(arc
							(start 0.2794 0.1778)
							(mid 0.249642 0.249642)
							(end 0.1778 0.2794)
						)
					)
					(width 0)
					(fill yes)
				)
			)
		)
	)
	(footprint ""
		(layer "B.Cu")
		(at 29.21 -78.74)
		(property "Reference" "R58"
			(at 0 0 0)
			(layer "B.SilkS")
			(hide yes)
			(effects
				(font
					(size 1.27 1.27)
				)
				(justify mirror)
			)
		)
		(property "Value" "47KR2F-GP"
			(at -0.064008 -3.993896 0)
			(unlocked yes)
			(layer "B.Fab")
			(hide yes)
			(effects
				(font
					(size 1.016 1.016)
					(thickness 0.1524)
				)
				(justify mirror)
			)
		)
		(property "Device Type" "R402H16"
			(at -0.064008 -5.517896 0)
			(unlocked yes)
			(layer "B.Fab")
			(hide yes)
			(effects
				(font
					(size 1.016 1.016)
					(thickness 0.1524)
				)
				(justify mirror)
			)
		)
		(duplicate_pad_numbers_are_jumpers no)
		(fp_line
			(start -0.508 -0.9398)
			(end 0.508 -0.9398)
			(stroke
				(width 0.1524)
				(type default)
			)
			(layer "B.SilkS")
		)
		(fp_line
			(start 0.508 -0.9398)
			(end 0.508 0.9398)
			(stroke
				(width 0.1524)
				(type default)
			)
			(layer "B.SilkS")
		)
		(fp_rect
			(start 0.508 0.9398)
			(end -0.508 -0.9398)
			(stroke
				(width 0)
				(type default)
			)
			(fill no)
			(layer "B.CrtYd")
		)
		(fp_rect
			(start 0.508 0.9398)
			(end -0.508 -0.9398)
			(stroke
				(width 0)
				(type default)
			)
			(fill no)
			(layer "B.Fab")
		)
		(pad "1" smd custom
			(at 0 -0.4445 180)
			(size 0.1397 0.1397)
			(layers "B.Cu" "B.Mask" "B.Paste")
			(net "Z50_SSD_A1_SMB_DATA_R")
			(options
				(clearance outline)
				(anchor circle)
			)
			(primitives
				(gr_poly
					(pts
						(arc
							(start -0.1778 0.2794)
							(mid -0.249642 0.249642)
							(end -0.2794 0.1778)
						)
						(arc
							(start -0.2794 -0.1778)
							(mid -0.249642 -0.249642)
							(end -0.1778 -0.2794)
						)
						(arc
							(start 0.1778 -0.2794)
							(mid 0.249642 -0.249642)
							(end 0.2794 -0.1778)
						)
						(arc
							(start 0.2794 0.1778)
							(mid 0.249642 0.249642)
							(end 0.1778 0.2794)
						)
					)
					(width 0)
					(fill yes)
				)
			)
		)
		(pad "2" smd custom
			(at 0 0.4445 180)
			(size 0.1397 0.1397)
			(layers "B.Cu" "B.Mask" "B.Paste")
			(net "P3V3_DPB")
			(options
				(clearance outline)
				(anchor circle)
			)
			(primitives
				(gr_poly
					(pts
						(arc
							(start -0.1778 0.2794)
							(mid -0.249642 0.249642)
							(end -0.2794 0.1778)
						)
						(arc
							(start -0.2794 -0.1778)
							(mid -0.249642 -0.249642)
							(end -0.1778 -0.2794)
						)
						(arc
							(start 0.1778 -0.2794)
							(mid 0.249642 -0.249642)
							(end 0.2794 -0.1778)
						)
						(arc
							(start 0.2794 0.1778)
							(mid 0.249642 0.249642)
							(end 0.1778 0.2794)
						)
					)
					(width 0)
					(fill yes)
				)
			)
		)
	)
	(footprint ""
		(layer "B.Cu")
		(at 25.146 -71.755 180)
		(property "Reference" "R36"
			(at 0 0 0)
			(layer "B.SilkS")
			(hide yes)
			(effects
				(font
					(size 1.27 1.27)
				)
				(justify mirror)
			)
		)
		(property "Value" "47KR2F-GP"
			(at -0.064008 -3.993896 180)
			(unlocked yes)
			(layer "B.Fab")
			(hide yes)
			(effects
				(font
					(size 1.016 1.016)
					(thickness 0.1524)
				)
				(justify mirror)
			)
		)
		(property "Device Type" "R402H16"
			(at -0.064008 -5.517896 180)
			(unlocked yes)
			(layer "B.Fab")
			(hide yes)
			(effects
				(font
					(size 1.016 1.016)
					(thickness 0.1524)
				)
				(justify mirror)
			)
		)
		(duplicate_pad_numbers_are_jumpers no)
		(fp_line
			(start 0.508 -0.9398)
			(end 0.508 0.9398)
			(stroke
				(width 0.1524)
				(type default)
			)
			(layer "B.SilkS")
		)
		(fp_line
			(start -0.508 -0.9398)
			(end 0.508 -0.9398)
			(stroke
				(width 0.1524)
				(type default)
			)
			(layer "B.SilkS")
		)
		(fp_rect
			(start 0.508 0.9398)
			(end -0.508 -0.9398)
			(stroke
				(width 0)
				(type default)
			)
			(fill no)
			(layer "B.CrtYd")
		)
		(fp_rect
			(start 0.508 0.9398)
			(end -0.508 -0.9398)
			(stroke
				(width 0)
				(type default)
			)
			(fill no)
			(layer "B.Fab")
		)
		(pad "1" smd custom
			(at 0 -0.4445)
			(size 0.1397 0.1397)
			(layers "B.Cu" "B.Mask" "B.Paste")
			(net "Z50_SSD_A1_SMB_DATA")
			(options
				(clearance outline)
				(anchor circle)
			)
			(primitives
				(gr_poly
					(pts
						(arc
							(start -0.1778 0.2794)
							(mid -0.249642 0.249642)
							(end -0.2794 0.1778)
						)
						(arc
							(start -0.2794 -0.1778)
							(mid -0.249642 -0.249642)
							(end -0.1778 -0.2794)
						)
						(arc
							(start 0.1778 -0.2794)
							(mid 0.249642 -0.249642)
							(end 0.2794 -0.1778)
						)
						(arc
							(start 0.2794 0.1778)
							(mid 0.249642 0.249642)
							(end 0.1778 0.2794)
						)
					)
					(width 0)
					(fill yes)
				)
			)
		)
		(pad "2" smd custom
			(at 0 0.4445)
			(size 0.1397 0.1397)
			(layers "B.Cu" "B.Mask" "B.Paste")
			(net "P1V8_PWR")
			(options
				(clearance outline)
				(anchor circle)
			)
			(primitives
				(gr_poly
					(pts
						(arc
							(start -0.1778 0.2794)
							(mid -0.249642 0.249642)
							(end -0.2794 0.1778)
						)
						(arc
							(start -0.2794 -0.1778)
							(mid -0.249642 -0.249642)
							(end -0.1778 -0.2794)
						)
						(arc
							(start 0.1778 -0.2794)
							(mid 0.249642 -0.249642)
							(end 0.2794 -0.1778)
						)
						(arc
							(start 0.2794 0.1778)
							(mid 0.249642 0.249642)
							(end 0.1778 0.2794)
						)
					)
					(width 0)
					(fill yes)
				)
			)
		)
	)
	(footprint ""
		(layer "B.Cu")
		(at 64.008 -20.913852)
		(property "Reference" "TP8"
			(at 0 0 0)
			(layer "B.SilkS")
			(hide yes)
			(effects
				(font
					(size 1.27 1.27)
				)
				(justify mirror)
			)
		)
		(property "Value" "TPAD28-1-GP-U"
			(at -0.0508 -1.9304 0)
			(unlocked yes)
			(layer "B.Fab")
			(hide yes)
			(effects
				(font
					(size 1.016 1.016)
					(thickness 0.1524)
				)
				(justify mirror)
			)
		)
		(property "Device Type" "TPAD28-1-U"
			(at -0.0508 -3.4544 0)
			(unlocked yes)
			(layer "B.Fab")
			(hide yes)
			(effects
				(font
					(size 1.016 1.016)
					(thickness 0.1524)
				)
				(justify mirror)
			)
		)
		(duplicate_pad_numbers_are_jumpers no)
		(fp_poly
			(pts
				(arc
					(start 0.3556 0)
					(mid -0.3556 0)
					(end 0.3556 0)
				)
			)
			(stroke
				(width 0)
				(type default)
			)
			(fill no)
			(layer "B.CrtYd")
		)
		(fp_poly
			(pts
				(arc
					(start 0.9525 0)
					(mid -0.9525 0)
					(end 0.9525 0)
				)
			)
			(stroke
				(width 0)
				(type default)
			)
			(fill no)
			(layer "B.Fab")
		)
		(pad "1" smd circle
			(at 0 0 180)
			(size 0.7112 0.7112)
			(layers "B.Cu" "B.Mask" "B.Paste")
			(net "SSD_B1_MFG_CLK_TP")
		)
	)
	(footprint ""
		(layer "B.Cu")
		(at 56.466994 -77.724)
		(property "Reference" "PC41"
			(at 0 0 0)
			(layer "B.SilkS")
			(hide yes)
			(effects
				(font
					(size 1.27 1.27)
				)
				(justify mirror)
			)
		)
		(property "Value" "SCD1U25V2KX-2-GP"
			(at -1.1811 -2.7051 0)
			(unlocked yes)
			(layer "B.Fab")
			(hide yes)
			(effects
				(font
					(size 1.016 1.016)
					(thickness 0.1524)
				)
				(justify mirror)
			)
		)
		(property "Device Type" "C402H22"
			(at -1.1811 -4.2291 0)
			(unlocked yes)
			(layer "B.Fab")
			(hide yes)
			(effects
				(font
					(size 1.016 1.016)
					(thickness 0.1524)
				)
				(justify mirror)
			)
		)
		(duplicate_pad_numbers_are_jumpers no)
		(fp_rect
			(start 0.4318 0.9525)
			(end -0.4318 -0.9525)
			(stroke
				(width 0)
				(type default)
			)
			(fill no)
			(layer "B.CrtYd")
		)
		(fp_rect
			(start 0.4318 0.9525)
			(end -0.4318 -0.9525)
			(stroke
				(width 0)
				(type default)
			)
			(fill no)
			(layer "B.Fab")
		)
		(pad "1" smd custom
			(at 0 -0.4445 180)
			(size 0.1524 0.1524)
			(layers "B.Cu" "B.Mask" "B.Paste")
			(net "P3V3_PWR")
			(options
				(clearance outline)
				(anchor circle)
			)
			(primitives
				(gr_poly
					(pts
						(arc
							(start 0.3048 0.2032)
							(mid 0.275042 0.275042)
							(end 0.2032 0.3048)
						)
						(arc
							(start -0.2032 0.3048)
							(mid -0.275042 0.275042)
							(end -0.3048 0.2032)
						)
						(arc
							(start -0.3048 -0.2032)
							(mid -0.275042 -0.275042)
							(end -0.2032 -0.3048)
						)
						(arc
							(start 0.2032 -0.3048)
							(mid 0.275042 -0.275042)
							(end 0.3048 -0.2032)
						)
					)
					(width 0)
					(fill yes)
				)
			)
		)
		(pad "2" smd custom
			(at 0 0.4445 180)
			(size 0.1524 0.1524)
			(layers "B.Cu" "B.Mask" "B.Paste")
			(net "P3V3_DEV_LL_R")
			(options
				(clearance outline)
				(anchor circle)
			)
			(primitives
				(gr_poly
					(pts
						(arc
							(start 0.3048 0.2032)
							(mid 0.275042 0.275042)
							(end 0.2032 0.3048)
						)
						(arc
							(start -0.2032 0.3048)
							(mid -0.275042 0.275042)
							(end -0.3048 0.2032)
						)
						(arc
							(start -0.3048 -0.2032)
							(mid -0.275042 -0.275042)
							(end -0.2032 -0.3048)
						)
						(arc
							(start 0.2032 -0.3048)
							(mid 0.275042 -0.275042)
							(end 0.3048 -0.2032)
						)
					)
					(width 0)
					(fill yes)
				)
			)
		)
	)
	(footprint ""
		(layer "B.Cu")
		(at 39.575994 -78.613)
		(property "Reference" "PC36"
			(at 0 0 0)
			(layer "B.SilkS")
			(hide yes)
			(effects
				(font
					(size 1.27 1.27)
				)
				(justify mirror)
			)
		)
		(property "Value" "SC4D7U25V5KX-1-GP"
			(at 0.0762 -6.1214 0)
			(unlocked yes)
			(layer "B.Fab")
			(hide yes)
			(effects
				(font
					(size 1.016 1.016)
					(thickness 0.1524)
				)
				(justify mirror)
			)
		)
		(property "Device Type" "C805H58"
			(at 0.0762 -8.1534 0)
			(unlocked yes)
			(layer "B.Fab")
			(hide yes)
			(effects
				(font
					(size 1.016 1.016)
					(thickness 0.1524)
				)
				(justify mirror)
			)
		)
		(duplicate_pad_numbers_are_jumpers no)
		(fp_line
			(start -0.635 0)
			(end 0.635 0)
			(stroke
				(width 0.508)
				(type default)
			)
			(layer "B.SilkS")
		)
		(fp_rect
			(start 0.9652 1.778)
			(end -0.9652 -1.778)
			(stroke
				(width 0)
				(type default)
			)
			(fill no)
			(layer "B.CrtYd")
		)
		(fp_poly
			(pts
				(xy 0.9652 -1.778) (xy -0.9652 -1.778) (xy -0.9652 1.778) (xy 0.9652 1.778)
			)
			(stroke
				(width 0)
				(type default)
			)
			(fill no)
			(layer "B.Fab")
		)
		(pad "1" smd rect
			(at 0 -0.9652 180)
			(size 1.397 1.143)
			(layers "B.Cu" "B.Mask" "B.Paste")
			(net "P3V3_DEV_VDD")
		)
		(pad "2" smd rect
			(at 0 0.9652 180)
			(size 1.397 1.143)
			(layers "B.Cu" "B.Mask" "B.Paste")
			(net "GND")
		)
	)
	(footprint ""
		(layer "B.Cu")
		(at 64.008 -48.514)
		(property "Reference" "TP6"
			(at 0 0 0)
			(layer "B.SilkS")
			(hide yes)
			(effects
				(font
					(size 1.27 1.27)
				)
				(justify mirror)
			)
		)
		(property "Value" "TPAD28-1-GP-U"
			(at -0.0508 -1.9304 0)
			(unlocked yes)
			(layer "B.Fab")
			(hide yes)
			(effects
				(font
					(size 1.016 1.016)
					(thickness 0.1524)
				)
				(justify mirror)
			)
		)
		(property "Device Type" "TPAD28-1-U"
			(at -0.0508 -3.4544 0)
			(unlocked yes)
			(layer "B.Fab")
			(hide yes)
			(effects
				(font
					(size 1.016 1.016)
					(thickness 0.1524)
				)
				(justify mirror)
			)
		)
		(duplicate_pad_numbers_are_jumpers no)
		(fp_poly
			(pts
				(arc
					(start 0.3556 0)
					(mid -0.3556 0)
					(end 0.3556 0)
				)
			)
			(stroke
				(width 0)
				(type default)
			)
			(fill no)
			(layer "B.CrtYd")
		)
		(fp_poly
			(pts
				(arc
					(start 0.9525 0)
					(mid -0.9525 0)
					(end 0.9525 0)
				)
			)
			(stroke
				(width 0)
				(type default)
			)
			(fill no)
			(layer "B.Fab")
		)
		(pad "1" smd circle
			(at 0 0 180)
			(size 0.7112 0.7112)
			(layers "B.Cu" "B.Mask" "B.Paste")
			(net "SSD_A1_MFG_CLK_TP")
		)
	)
	(footprint ""
		(layer "B.Cu")
		(at 65.913 -48.514)
		(property "Reference" "TP7"
			(at 0 0 0)
			(layer "B.SilkS")
			(hide yes)
			(effects
				(font
					(size 1.27 1.27)
				)
				(justify mirror)
			)
		)
		(property "Value" "TPAD28-1-GP-U"
			(at -0.0508 -1.9304 0)
			(unlocked yes)
			(layer "B.Fab")
			(hide yes)
			(effects
				(font
					(size 1.016 1.016)
					(thickness 0.1524)
				)
				(justify mirror)
			)
		)
		(property "Device Type" "TPAD28-1-U"
			(at -0.0508 -3.4544 0)
			(unlocked yes)
			(layer "B.Fab")
			(hide yes)
			(effects
				(font
					(size 1.016 1.016)
					(thickness 0.1524)
				)
				(justify mirror)
			)
		)
		(duplicate_pad_numbers_are_jumpers no)
		(fp_poly
			(pts
				(arc
					(start 0.3556 0)
					(mid -0.3556 0)
					(end 0.3556 0)
				)
			)
			(stroke
				(width 0)
				(type default)
			)
			(fill no)
			(layer "B.CrtYd")
		)
		(fp_poly
			(pts
				(arc
					(start 0.9525 0)
					(mid -0.9525 0)
					(end 0.9525 0)
				)
			)
			(stroke
				(width 0)
				(type default)
			)
			(fill no)
			(layer "B.Fab")
		)
		(pad "1" smd circle
			(at 0 0 180)
			(size 0.7112 0.7112)
			(layers "B.Cu" "B.Mask" "B.Paste")
			(net "SSD_A1_MFG_DATA_TP")
		)
	)
	(footprint ""
		(layer "B.Cu")
		(at 65.278 -41.783 -90)
		(property "Reference" "C39"
			(at 0 0 90)
			(layer "B.SilkS")
			(hide yes)
			(effects
				(font
					(size 1.27 1.27)
				)
				(justify mirror)
			)
		)
		(property "Value" "SCD1U16V2KX-3GP"
			(at -1.1811 -2.7051 270)
			(unlocked yes)
			(layer "B.Fab")
			(hide yes)
			(effects
				(font
					(size 1.016 1.016)
					(thickness 0.1524)
				)
				(justify mirror)
			)
		)
		(property "Device Type" "C402H22"
			(at -1.1811 -4.2291 270)
			(unlocked yes)
			(layer "B.Fab")
			(hide yes)
			(effects
				(font
					(size 1.016 1.016)
					(thickness 0.1524)
				)
				(justify mirror)
			)
		)
		(duplicate_pad_numbers_are_jumpers no)
		(fp_rect
			(start 0.4318 0.9525)
			(end -0.4318 -0.9525)
			(stroke
				(width 0)
				(type default)
			)
			(fill no)
			(layer "B.CrtYd")
		)
		(fp_rect
			(start 0.4318 0.9525)
			(end -0.4318 -0.9525)
			(stroke
				(width 0)
				(type default)
			)
			(fill no)
			(layer "B.Fab")
		)
		(pad "1" smd custom
			(at 0 -0.4445 90)
			(size 0.1524 0.1524)
			(layers "B.Cu" "B.Mask" "B.Paste")
			(net "P3V3_DPB")
			(options
				(clearance outline)
				(anchor circle)
			)
			(primitives
				(gr_poly
					(pts
						(arc
							(start 0.3048 0.2032)
							(mid 0.275042 0.275042)
							(end 0.2032 0.3048)
						)
						(arc
							(start -0.2032 0.3048)
							(mid -0.275042 0.275042)
							(end -0.3048 0.2032)
						)
						(arc
							(start -0.3048 -0.2032)
							(mid -0.275042 -0.275042)
							(end -0.2032 -0.3048)
						)
						(arc
							(start 0.2032 -0.3048)
							(mid 0.275042 -0.275042)
							(end 0.3048 -0.2032)
						)
					)
					(width 0)
					(fill yes)
				)
			)
		)
		(pad "2" smd custom
			(at 0 0.4445 90)
			(size 0.1524 0.1524)
			(layers "B.Cu" "B.Mask" "B.Paste")
			(net "GND")
			(options
				(clearance outline)
				(anchor circle)
			)
			(primitives
				(gr_poly
					(pts
						(arc
							(start 0.3048 0.2032)
							(mid 0.275042 0.275042)
							(end 0.2032 0.3048)
						)
						(arc
							(start -0.2032 0.3048)
							(mid -0.275042 0.275042)
							(end -0.3048 0.2032)
						)
						(arc
							(start -0.3048 -0.2032)
							(mid -0.275042 -0.275042)
							(end -0.2032 -0.3048)
						)
						(arc
							(start 0.2032 -0.3048)
							(mid 0.275042 -0.275042)
							(end 0.3048 -0.2032)
						)
					)
					(width 0)
					(fill yes)
				)
			)
		)
	)
	(footprint ""
		(layer "B.Cu")
		(at 26.543 -77.216)
		(property "Reference" "R62"
			(at 0 0 0)
			(layer "B.SilkS")
			(hide yes)
			(effects
				(font
					(size 1.27 1.27)
				)
				(justify mirror)
			)
		)
		(property "Value" "0R2J-2-GP"
			(at -0.064008 -3.993896 0)
			(unlocked yes)
			(layer "B.Fab")
			(hide yes)
			(effects
				(font
					(size 1.016 1.016)
					(thickness 0.1524)
				)
				(justify mirror)
			)
		)
		(property "Device Type" "R402H16"
			(at -0.064008 -5.517896 0)
			(unlocked yes)
			(layer "B.Fab")
			(hide yes)
			(effects
				(font
					(size 1.016 1.016)
					(thickness 0.1524)
				)
				(justify mirror)
			)
		)
		(duplicate_pad_numbers_are_jumpers no)
		(fp_line
			(start -0.508 -0.9398)
			(end 0.508 -0.9398)
			(stroke
				(width 0.1524)
				(type default)
			)
			(layer "B.SilkS")
		)
		(fp_line
			(start 0.508 -0.9398)
			(end 0.508 0.9398)
			(stroke
				(width 0.1524)
				(type default)
			)
			(layer "B.SilkS")
		)
		(fp_rect
			(start 0.508 0.9398)
			(end -0.508 -0.9398)
			(stroke
				(width 0)
				(type default)
			)
			(fill no)
			(layer "B.CrtYd")
		)
		(fp_rect
			(start 0.508 0.9398)
			(end -0.508 -0.9398)
			(stroke
				(width 0)
				(type default)
			)
			(fill no)
			(layer "B.Fab")
		)
		(pad "1" smd custom
			(at 0 -0.4445 180)
			(size 0.1397 0.1397)
			(layers "B.Cu" "B.Mask" "B.Paste")
			(net "Z50_SSD_B1_SMB_DATA_R")
			(options
				(clearance outline)
				(anchor circle)
			)
			(primitives
				(gr_poly
					(pts
						(arc
							(start -0.1778 0.2794)
							(mid -0.249642 0.249642)
							(end -0.2794 0.1778)
						)
						(arc
							(start -0.2794 -0.1778)
							(mid -0.249642 -0.249642)
							(end -0.1778 -0.2794)
						)
						(arc
							(start 0.1778 -0.2794)
							(mid 0.249642 -0.249642)
							(end 0.2794 -0.1778)
						)
						(arc
							(start 0.2794 0.1778)
							(mid 0.249642 0.249642)
							(end 0.1778 0.2794)
						)
					)
					(width 0)
					(fill yes)
				)
			)
		)
		(pad "2" smd custom
			(at 0 0.4445 180)
			(size 0.1397 0.1397)
			(layers "B.Cu" "B.Mask" "B.Paste")
			(net "Z50_SSD_B1_SMB_DATA")
			(options
				(clearance outline)
				(anchor circle)
			)
			(primitives
				(gr_poly
					(pts
						(arc
							(start -0.1778 0.2794)
							(mid -0.249642 0.249642)
							(end -0.2794 0.1778)
						)
						(arc
							(start -0.2794 -0.1778)
							(mid -0.249642 -0.249642)
							(end -0.1778 -0.2794)
						)
						(arc
							(start 0.1778 -0.2794)
							(mid 0.249642 -0.249642)
							(end 0.2794 -0.1778)
						)
						(arc
							(start 0.2794 0.1778)
							(mid 0.249642 0.249642)
							(end 0.1778 0.2794)
						)
					)
					(width 0)
					(fill yes)
				)
			)
		)
	)
	(footprint ""
		(layer "B.Cu")
		(at 62.738 -38.735 90)
		(property "Reference" "R5"
			(at 0 0 90)
			(layer "B.SilkS")
			(hide yes)
			(effects
				(font
					(size 1.27 1.27)
				)
				(justify mirror)
			)
		)
		(property "Value" "0R2J-2-GP"
			(at -0.064008 -3.993896 90)
			(unlocked yes)
			(layer "B.Fab")
			(hide yes)
			(effects
				(font
					(size 1.016 1.016)
					(thickness 0.1524)
				)
				(justify mirror)
			)
		)
		(property "Device Type" "R402H16"
			(at -0.064008 -5.517896 90)
			(unlocked yes)
			(layer "B.Fab")
			(hide yes)
			(effects
				(font
					(size 1.016 1.016)
					(thickness 0.1524)
				)
				(justify mirror)
			)
		)
		(duplicate_pad_numbers_are_jumpers no)
		(fp_line
			(start 0.508 -0.9398)
			(end 0.508 0.9398)
			(stroke
				(width 0.1524)
				(type default)
			)
			(layer "B.SilkS")
		)
		(fp_line
			(start -0.508 -0.9398)
			(end 0.508 -0.9398)
			(stroke
				(width 0.1524)
				(type default)
			)
			(layer "B.SilkS")
		)
		(fp_rect
			(start 0.508 0.9398)
			(end -0.508 -0.9398)
			(stroke
				(width 0)
				(type default)
			)
			(fill no)
			(layer "B.CrtYd")
		)
		(fp_rect
			(start 0.508 0.9398)
			(end -0.508 -0.9398)
			(stroke
				(width 0)
				(type default)
			)
			(fill no)
			(layer "B.Fab")
		)
		(pad "1" smd custom
			(at 0 -0.4445 270)
			(size 0.1397 0.1397)
			(layers "B.Cu" "B.Mask" "B.Paste")
			(net "Z50_SMB_DATA")
			(options
				(clearance outline)
				(anchor circle)
			)
			(primitives
				(gr_poly
					(pts
						(arc
							(start -0.1778 0.2794)
							(mid -0.249642 0.249642)
							(end -0.2794 0.1778)
						)
						(arc
							(start -0.2794 -0.1778)
							(mid -0.249642 -0.249642)
							(end -0.1778 -0.2794)
						)
						(arc
							(start 0.1778 -0.2794)
							(mid 0.249642 -0.249642)
							(end 0.2794 -0.1778)
						)
						(arc
							(start 0.2794 0.1778)
							(mid 0.249642 0.249642)
							(end 0.1778 0.2794)
						)
					)
					(width 0)
					(fill yes)
				)
			)
		)
		(pad "2" smd custom
			(at 0 0.4445 270)
			(size 0.1397 0.1397)
			(layers "B.Cu" "B.Mask" "B.Paste")
			(net "Z50_TEMP_1_DATA")
			(options
				(clearance outline)
				(anchor circle)
			)
			(primitives
				(gr_poly
					(pts
						(arc
							(start -0.1778 0.2794)
							(mid -0.249642 0.249642)
							(end -0.2794 0.1778)
						)
						(arc
							(start -0.2794 -0.1778)
							(mid -0.249642 -0.249642)
							(end -0.1778 -0.2794)
						)
						(arc
							(start 0.1778 -0.2794)
							(mid 0.249642 -0.249642)
							(end 0.2794 -0.1778)
						)
						(arc
							(start 0.2794 0.1778)
							(mid 0.249642 0.249642)
							(end 0.1778 0.2794)
						)
					)
					(width 0)
					(fill yes)
				)
			)
		)
	)
	(footprint ""
		(layer "B.Cu")
		(at 25.019 -81.534 -90)
		(property "Reference" "R25"
			(at 0 0 90)
			(layer "B.SilkS")
			(hide yes)
			(effects
				(font
					(size 1.27 1.27)
				)
				(justify mirror)
			)
		)
		(property "Value" "4K7R2F-GP"
			(at -0.064008 -3.993896 270)
			(unlocked yes)
			(layer "B.Fab")
			(hide yes)
			(effects
				(font
					(size 1.016 1.016)
					(thickness 0.1524)
				)
				(justify mirror)
			)
		)
		(property "Device Type" "R402H16"
			(at -0.064008 -5.517896 270)
			(unlocked yes)
			(layer "B.Fab")
			(hide yes)
			(effects
				(font
					(size 1.016 1.016)
					(thickness 0.1524)
				)
				(justify mirror)
			)
		)
		(duplicate_pad_numbers_are_jumpers no)
		(fp_line
			(start -0.508 -0.9398)
			(end 0.508 -0.9398)
			(stroke
				(width 0.1524)
				(type default)
			)
			(layer "B.SilkS")
		)
		(fp_line
			(start 0.508 -0.9398)
			(end 0.508 0.9398)
			(stroke
				(width 0.1524)
				(type default)
			)
			(layer "B.SilkS")
		)
		(fp_rect
			(start 0.508 0.9398)
			(end -0.508 -0.9398)
			(stroke
				(width 0)
				(type default)
			)
			(fill no)
			(layer "B.CrtYd")
		)
		(fp_rect
			(start 0.508 0.9398)
			(end -0.508 -0.9398)
			(stroke
				(width 0)
				(type default)
			)
			(fill no)
			(layer "B.Fab")
		)
		(pad "1" smd custom
			(at 0 -0.4445 90)
			(size 0.1397 0.1397)
			(layers "B.Cu" "B.Mask" "B.Paste")
			(net "Z50_SMB_SWITCH_ADDRESS_A1")
			(options
				(clearance outline)
				(anchor circle)
			)
			(primitives
				(gr_poly
					(pts
						(arc
							(start -0.1778 0.2794)
							(mid -0.249642 0.249642)
							(end -0.2794 0.1778)
						)
						(arc
							(start -0.2794 -0.1778)
							(mid -0.249642 -0.249642)
							(end -0.1778 -0.2794)
						)
						(arc
							(start 0.1778 -0.2794)
							(mid 0.249642 -0.249642)
							(end 0.2794 -0.1778)
						)
						(arc
							(start 0.2794 0.1778)
							(mid 0.249642 0.249642)
							(end 0.1778 0.2794)
						)
					)
					(width 0)
					(fill yes)
				)
			)
		)
		(pad "2" smd custom
			(at 0 0.4445 90)
			(size 0.1397 0.1397)
			(layers "B.Cu" "B.Mask" "B.Paste")
			(net "GND")
			(options
				(clearance outline)
				(anchor circle)
			)
			(primitives
				(gr_poly
					(pts
						(arc
							(start -0.1778 0.2794)
							(mid -0.249642 0.249642)
							(end -0.2794 0.1778)
						)
						(arc
							(start -0.2794 -0.1778)
							(mid -0.249642 -0.249642)
							(end -0.1778 -0.2794)
						)
						(arc
							(start 0.1778 -0.2794)
							(mid 0.249642 -0.249642)
							(end 0.2794 -0.1778)
						)
						(arc
							(start 0.2794 0.1778)
							(mid 0.249642 0.249642)
							(end 0.1778 0.2794)
						)
					)
					(width 0)
					(fill yes)
				)
			)
		)
	)
	(footprint ""
		(layer "B.Cu")
		(at 65.278 -40.767 -90)
		(property "Reference" "R21"
			(at 0 0 90)
			(layer "B.SilkS")
			(hide yes)
			(effects
				(font
					(size 1.27 1.27)
				)
				(justify mirror)
			)
		)
		(property "Value" "4K7R2F-GP"
			(at -0.064008 -3.993896 270)
			(unlocked yes)
			(layer "B.Fab")
			(hide yes)
			(effects
				(font
					(size 1.016 1.016)
					(thickness 0.1524)
				)
				(justify mirror)
			)
		)
		(property "Device Type" "R402H16"
			(at -0.064008 -5.517896 270)
			(unlocked yes)
			(layer "B.Fab")
			(hide yes)
			(effects
				(font
					(size 1.016 1.016)
					(thickness 0.1524)
				)
				(justify mirror)
			)
		)
		(duplicate_pad_numbers_are_jumpers no)
		(fp_line
			(start -0.508 -0.9398)
			(end 0.508 -0.9398)
			(stroke
				(width 0.1524)
				(type default)
			)
			(layer "B.SilkS")
		)
		(fp_line
			(start 0.508 -0.9398)
			(end 0.508 0.9398)
			(stroke
				(width 0.1524)
				(type default)
			)
			(layer "B.SilkS")
		)
		(fp_rect
			(start 0.508 0.9398)
			(end -0.508 -0.9398)
			(stroke
				(width 0)
				(type default)
			)
			(fill no)
			(layer "B.CrtYd")
		)
		(fp_rect
			(start 0.508 0.9398)
			(end -0.508 -0.9398)
			(stroke
				(width 0)
				(type default)
			)
			(fill no)
			(layer "B.Fab")
		)
		(pad "1" smd custom
			(at 0 -0.4445 90)
			(size 0.1397 0.1397)
			(layers "B.Cu" "B.Mask" "B.Paste")
			(net "P3V3_DPB")
			(options
				(clearance outline)
				(anchor circle)
			)
			(primitives
				(gr_poly
					(pts
						(arc
							(start -0.1778 0.2794)
							(mid -0.249642 0.249642)
							(end -0.2794 0.1778)
						)
						(arc
							(start -0.2794 -0.1778)
							(mid -0.249642 -0.249642)
							(end -0.1778 -0.2794)
						)
						(arc
							(start 0.1778 -0.2794)
							(mid 0.249642 -0.249642)
							(end 0.2794 -0.1778)
						)
						(arc
							(start 0.2794 0.1778)
							(mid 0.249642 0.249642)
							(end 0.1778 0.2794)
						)
					)
					(width 0)
					(fill yes)
				)
			)
		)
		(pad "2" smd custom
			(at 0 0.4445 90)
			(size 0.1397 0.1397)
			(layers "B.Cu" "B.Mask" "B.Paste")
			(net "Z50_TEMP_1_ALERT#")
			(options
				(clearance outline)
				(anchor circle)
			)
			(primitives
				(gr_poly
					(pts
						(arc
							(start -0.1778 0.2794)
							(mid -0.249642 0.249642)
							(end -0.2794 0.1778)
						)
						(arc
							(start -0.2794 -0.1778)
							(mid -0.249642 -0.249642)
							(end -0.1778 -0.2794)
						)
						(arc
							(start 0.1778 -0.2794)
							(mid 0.249642 -0.249642)
							(end 0.2794 -0.1778)
						)
						(arc
							(start 0.2794 0.1778)
							(mid 0.249642 0.249642)
							(end 0.1778 0.2794)
						)
					)
					(width 0)
					(fill yes)
				)
			)
		)
	)
	(footprint ""
		(layer "B.Cu")
		(at 59.260994 -42.164 180)
		(property "Reference" "R6"
			(at 0 0 0)
			(layer "B.SilkS")
			(hide yes)
			(effects
				(font
					(size 1.27 1.27)
				)
				(justify mirror)
			)
		)
		(property "Value" "4K7R2F-GP"
			(at -0.064008 -3.993896 180)
			(unlocked yes)
			(layer "B.Fab")
			(hide yes)
			(effects
				(font
					(size 1.016 1.016)
					(thickness 0.1524)
				)
				(justify mirror)
			)
		)
		(property "Device Type" "R402H16"
			(at -0.064008 -5.517896 180)
			(unlocked yes)
			(layer "B.Fab")
			(hide yes)
			(effects
				(font
					(size 1.016 1.016)
					(thickness 0.1524)
				)
				(justify mirror)
			)
		)
		(duplicate_pad_numbers_are_jumpers no)
		(fp_line
			(start 0.508 -0.9398)
			(end 0.508 0.9398)
			(stroke
				(width 0.1524)
				(type default)
			)
			(layer "B.SilkS")
		)
		(fp_line
			(start -0.508 -0.9398)
			(end 0.508 -0.9398)
			(stroke
				(width 0.1524)
				(type default)
			)
			(layer "B.SilkS")
		)
		(fp_rect
			(start 0.508 0.9398)
			(end -0.508 -0.9398)
			(stroke
				(width 0)
				(type default)
			)
			(fill no)
			(layer "B.CrtYd")
		)
		(fp_rect
			(start 0.508 0.9398)
			(end -0.508 -0.9398)
			(stroke
				(width 0)
				(type default)
			)
			(fill no)
			(layer "B.Fab")
		)
		(pad "1" smd custom
			(at 0 -0.4445)
			(size 0.1397 0.1397)
			(layers "B.Cu" "B.Mask" "B.Paste")
			(net "P3V3_DPB")
			(options
				(clearance outline)
				(anchor circle)
			)
			(primitives
				(gr_poly
					(pts
						(arc
							(start -0.1778 0.2794)
							(mid -0.249642 0.249642)
							(end -0.2794 0.1778)
						)
						(arc
							(start -0.2794 -0.1778)
							(mid -0.249642 -0.249642)
							(end -0.1778 -0.2794)
						)
						(arc
							(start 0.1778 -0.2794)
							(mid 0.249642 -0.249642)
							(end 0.2794 -0.1778)
						)
						(arc
							(start 0.2794 0.1778)
							(mid 0.249642 0.249642)
							(end 0.1778 0.2794)
						)
					)
					(width 0)
					(fill yes)
				)
			)
		)
		(pad "2" smd custom
			(at 0 0.4445)
			(size 0.1397 0.1397)
			(layers "B.Cu" "B.Mask" "B.Paste")
			(net "Z50_TEMP_1_A2")
			(options
				(clearance outline)
				(anchor circle)
			)
			(primitives
				(gr_poly
					(pts
						(arc
							(start -0.1778 0.2794)
							(mid -0.249642 0.249642)
							(end -0.2794 0.1778)
						)
						(arc
							(start -0.2794 -0.1778)
							(mid -0.249642 -0.249642)
							(end -0.1778 -0.2794)
						)
						(arc
							(start 0.1778 -0.2794)
							(mid 0.249642 -0.249642)
							(end 0.2794 -0.1778)
						)
						(arc
							(start 0.2794 0.1778)
							(mid 0.249642 0.249642)
							(end 0.1778 0.2794)
						)
					)
					(width 0)
					(fill yes)
				)
			)
		)
	)
	(footprint ""
		(layer "B.Cu")
		(at 58.244994 -38.354)
		(property "Reference" "R12"
			(at 0 0 0)
			(layer "B.SilkS")
			(hide yes)
			(effects
				(font
					(size 1.27 1.27)
				)
				(justify mirror)
			)
		)
		(property "Value" "4K7R2F-GP"
			(at -0.064008 -3.993896 0)
			(unlocked yes)
			(layer "B.Fab")
			(hide yes)
			(effects
				(font
					(size 1.016 1.016)
					(thickness 0.1524)
				)
				(justify mirror)
			)
		)
		(property "Device Type" "R402H16"
			(at -0.064008 -5.517896 0)
			(unlocked yes)
			(layer "B.Fab")
			(hide yes)
			(effects
				(font
					(size 1.016 1.016)
					(thickness 0.1524)
				)
				(justify mirror)
			)
		)
		(duplicate_pad_numbers_are_jumpers no)
		(fp_line
			(start -0.508 -0.9398)
			(end 0.508 -0.9398)
			(stroke
				(width 0.1524)
				(type default)
			)
			(layer "B.SilkS")
		)
		(fp_line
			(start 0.508 -0.9398)
			(end 0.508 0.9398)
			(stroke
				(width 0.1524)
				(type default)
			)
			(layer "B.SilkS")
		)
		(fp_rect
			(start 0.508 0.9398)
			(end -0.508 -0.9398)
			(stroke
				(width 0)
				(type default)
			)
			(fill no)
			(layer "B.CrtYd")
		)
		(fp_rect
			(start 0.508 0.9398)
			(end -0.508 -0.9398)
			(stroke
				(width 0)
				(type default)
			)
			(fill no)
			(layer "B.Fab")
		)
		(pad "1" smd custom
			(at 0 -0.4445 180)
			(size 0.1397 0.1397)
			(layers "B.Cu" "B.Mask" "B.Paste")
			(net "Z50_TEMP_1_A0")
			(options
				(clearance outline)
				(anchor circle)
			)
			(primitives
				(gr_poly
					(pts
						(arc
							(start -0.1778 0.2794)
							(mid -0.249642 0.249642)
							(end -0.2794 0.1778)
						)
						(arc
							(start -0.2794 -0.1778)
							(mid -0.249642 -0.249642)
							(end -0.1778 -0.2794)
						)
						(arc
							(start 0.1778 -0.2794)
							(mid 0.249642 -0.249642)
							(end 0.2794 -0.1778)
						)
						(arc
							(start 0.2794 0.1778)
							(mid 0.249642 0.249642)
							(end 0.1778 0.2794)
						)
					)
					(width 0)
					(fill yes)
				)
			)
		)
		(pad "2" smd custom
			(at 0 0.4445 180)
			(size 0.1397 0.1397)
			(layers "B.Cu" "B.Mask" "B.Paste")
			(net "GND")
			(options
				(clearance outline)
				(anchor circle)
			)
			(primitives
				(gr_poly
					(pts
						(arc
							(start -0.1778 0.2794)
							(mid -0.249642 0.249642)
							(end -0.2794 0.1778)
						)
						(arc
							(start -0.2794 -0.1778)
							(mid -0.249642 -0.249642)
							(end -0.1778 -0.2794)
						)
						(arc
							(start 0.1778 -0.2794)
							(mid 0.249642 -0.249642)
							(end 0.2794 -0.1778)
						)
						(arc
							(start 0.2794 0.1778)
							(mid 0.249642 0.249642)
							(end 0.1778 0.2794)
						)
					)
					(width 0)
					(fill yes)
				)
			)
		)
	)
	(footprint ""
		(layer "B.Cu")
		(at 28.829 -86.233)
		(property "Reference" "R50"
			(at 0 0 0)
			(layer "B.SilkS")
			(hide yes)
			(effects
				(font
					(size 1.27 1.27)
				)
				(justify mirror)
			)
		)
		(property "Value" "47KR2F-GP"
			(at -0.064008 -3.993896 0)
			(unlocked yes)
			(layer "B.Fab")
			(hide yes)
			(effects
				(font
					(size 1.016 1.016)
					(thickness 0.1524)
				)
				(justify mirror)
			)
		)
		(property "Device Type" "R402H16"
			(at -0.064008 -5.517896 0)
			(unlocked yes)
			(layer "B.Fab")
			(hide yes)
			(effects
				(font
					(size 1.016 1.016)
					(thickness 0.1524)
				)
				(justify mirror)
			)
		)
		(duplicate_pad_numbers_are_jumpers no)
		(fp_line
			(start -0.508 -0.9398)
			(end 0.508 -0.9398)
			(stroke
				(width 0.1524)
				(type default)
			)
			(layer "B.SilkS")
		)
		(fp_line
			(start 0.508 -0.9398)
			(end 0.508 0.9398)
			(stroke
				(width 0.1524)
				(type default)
			)
			(layer "B.SilkS")
		)
		(fp_rect
			(start 0.508 0.9398)
			(end -0.508 -0.9398)
			(stroke
				(width 0)
				(type default)
			)
			(fill no)
			(layer "B.CrtYd")
		)
		(fp_rect
			(start 0.508 0.9398)
			(end -0.508 -0.9398)
			(stroke
				(width 0)
				(type default)
			)
			(fill no)
			(layer "B.Fab")
		)
		(pad "1" smd custom
			(at 0 -0.4445 180)
			(size 0.1397 0.1397)
			(layers "B.Cu" "B.Mask" "B.Paste")
			(net "P3V3_DPB")
			(options
				(clearance outline)
				(anchor circle)
			)
			(primitives
				(gr_poly
					(pts
						(arc
							(start -0.1778 0.2794)
							(mid -0.249642 0.249642)
							(end -0.2794 0.1778)
						)
						(arc
							(start -0.2794 -0.1778)
							(mid -0.249642 -0.249642)
							(end -0.1778 -0.2794)
						)
						(arc
							(start 0.1778 -0.2794)
							(mid 0.249642 -0.249642)
							(end 0.2794 -0.1778)
						)
						(arc
							(start 0.2794 0.1778)
							(mid 0.249642 0.249642)
							(end 0.1778 0.2794)
						)
					)
					(width 0)
					(fill yes)
				)
			)
		)
		(pad "2" smd custom
			(at 0 0.4445 180)
			(size 0.1397 0.1397)
			(layers "B.Cu" "B.Mask" "B.Paste")
			(net "Z50_SMB_CLK")
			(options
				(clearance outline)
				(anchor circle)
			)
			(primitives
				(gr_poly
					(pts
						(arc
							(start -0.1778 0.2794)
							(mid -0.249642 0.249642)
							(end -0.2794 0.1778)
						)
						(arc
							(start -0.2794 -0.1778)
							(mid -0.249642 -0.249642)
							(end -0.1778 -0.2794)
						)
						(arc
							(start 0.1778 -0.2794)
							(mid 0.249642 -0.249642)
							(end 0.2794 -0.1778)
						)
						(arc
							(start 0.2794 0.1778)
							(mid 0.249642 0.249642)
							(end 0.1778 0.2794)
						)
					)
					(width 0)
					(fill yes)
				)
			)
		)
	)
	(footprint ""
		(layer "B.Cu")
		(at 27.686 -86.233)
		(property "Reference" "R51"
			(at 0 0 0)
			(layer "B.SilkS")
			(hide yes)
			(effects
				(font
					(size 1.27 1.27)
				)
				(justify mirror)
			)
		)
		(property "Value" "47KR2F-GP"
			(at -0.064008 -3.993896 0)
			(unlocked yes)
			(layer "B.Fab")
			(hide yes)
			(effects
				(font
					(size 1.016 1.016)
					(thickness 0.1524)
				)
				(justify mirror)
			)
		)
		(property "Device Type" "R402H16"
			(at -0.064008 -5.517896 0)
			(unlocked yes)
			(layer "B.Fab")
			(hide yes)
			(effects
				(font
					(size 1.016 1.016)
					(thickness 0.1524)
				)
				(justify mirror)
			)
		)
		(duplicate_pad_numbers_are_jumpers no)
		(fp_line
			(start -0.508 -0.9398)
			(end 0.508 -0.9398)
			(stroke
				(width 0.1524)
				(type default)
			)
			(layer "B.SilkS")
		)
		(fp_line
			(start 0.508 -0.9398)
			(end 0.508 0.9398)
			(stroke
				(width 0.1524)
				(type default)
			)
			(layer "B.SilkS")
		)
		(fp_rect
			(start 0.508 0.9398)
			(end -0.508 -0.9398)
			(stroke
				(width 0)
				(type default)
			)
			(fill no)
			(layer "B.CrtYd")
		)
		(fp_rect
			(start 0.508 0.9398)
			(end -0.508 -0.9398)
			(stroke
				(width 0)
				(type default)
			)
			(fill no)
			(layer "B.Fab")
		)
		(pad "1" smd custom
			(at 0 -0.4445 180)
			(size 0.1397 0.1397)
			(layers "B.Cu" "B.Mask" "B.Paste")
			(net "P3V3_DPB")
			(options
				(clearance outline)
				(anchor circle)
			)
			(primitives
				(gr_poly
					(pts
						(arc
							(start -0.1778 0.2794)
							(mid -0.249642 0.249642)
							(end -0.2794 0.1778)
						)
						(arc
							(start -0.2794 -0.1778)
							(mid -0.249642 -0.249642)
							(end -0.1778 -0.2794)
						)
						(arc
							(start 0.1778 -0.2794)
							(mid 0.249642 -0.249642)
							(end 0.2794 -0.1778)
						)
						(arc
							(start 0.2794 0.1778)
							(mid 0.249642 0.249642)
							(end 0.1778 0.2794)
						)
					)
					(width 0)
					(fill yes)
				)
			)
		)
		(pad "2" smd custom
			(at 0 0.4445 180)
			(size 0.1397 0.1397)
			(layers "B.Cu" "B.Mask" "B.Paste")
			(net "Z50_SMB_DATA")
			(options
				(clearance outline)
				(anchor circle)
			)
			(primitives
				(gr_poly
					(pts
						(arc
							(start -0.1778 0.2794)
							(mid -0.249642 0.249642)
							(end -0.2794 0.1778)
						)
						(arc
							(start -0.2794 -0.1778)
							(mid -0.249642 -0.249642)
							(end -0.1778 -0.2794)
						)
						(arc
							(start 0.1778 -0.2794)
							(mid 0.249642 -0.249642)
							(end 0.2794 -0.1778)
						)
						(arc
							(start 0.2794 0.1778)
							(mid 0.249642 0.249642)
							(end 0.1778 0.2794)
						)
					)
					(width 0)
					(fill yes)
				)
			)
		)
	)
	(footprint ""
		(layer "B.Cu")
		(at 25.527 -77.216)
		(property "Reference" "R64"
			(at 0 0 0)
			(layer "B.SilkS")
			(hide yes)
			(effects
				(font
					(size 1.27 1.27)
				)
				(justify mirror)
			)
		)
		(property "Value" "0R2J-2-GP"
			(at -0.064008 -3.993896 0)
			(unlocked yes)
			(layer "B.Fab")
			(hide yes)
			(effects
				(font
					(size 1.016 1.016)
					(thickness 0.1524)
				)
				(justify mirror)
			)
		)
		(property "Device Type" "R402H16"
			(at -0.064008 -5.517896 0)
			(unlocked yes)
			(layer "B.Fab")
			(hide yes)
			(effects
				(font
					(size 1.016 1.016)
					(thickness 0.1524)
				)
				(justify mirror)
			)
		)
		(duplicate_pad_numbers_are_jumpers no)
		(fp_line
			(start -0.508 -0.9398)
			(end 0.508 -0.9398)
			(stroke
				(width 0.1524)
				(type default)
			)
			(layer "B.SilkS")
		)
		(fp_line
			(start 0.508 -0.9398)
			(end 0.508 0.9398)
			(stroke
				(width 0.1524)
				(type default)
			)
			(layer "B.SilkS")
		)
		(fp_rect
			(start 0.508 0.9398)
			(end -0.508 -0.9398)
			(stroke
				(width 0)
				(type default)
			)
			(fill no)
			(layer "B.CrtYd")
		)
		(fp_rect
			(start 0.508 0.9398)
			(end -0.508 -0.9398)
			(stroke
				(width 0)
				(type default)
			)
			(fill no)
			(layer "B.Fab")
		)
		(pad "1" smd custom
			(at 0 -0.4445 180)
			(size 0.1397 0.1397)
			(layers "B.Cu" "B.Mask" "B.Paste")
			(net "Z50_SSD_B1_SMB_CLK_R")
			(options
				(clearance outline)
				(anchor circle)
			)
			(primitives
				(gr_poly
					(pts
						(arc
							(start -0.1778 0.2794)
							(mid -0.249642 0.249642)
							(end -0.2794 0.1778)
						)
						(arc
							(start -0.2794 -0.1778)
							(mid -0.249642 -0.249642)
							(end -0.1778 -0.2794)
						)
						(arc
							(start 0.1778 -0.2794)
							(mid 0.249642 -0.249642)
							(end 0.2794 -0.1778)
						)
						(arc
							(start 0.2794 0.1778)
							(mid 0.249642 0.249642)
							(end 0.1778 0.2794)
						)
					)
					(width 0)
					(fill yes)
				)
			)
		)
		(pad "2" smd custom
			(at 0 0.4445 180)
			(size 0.1397 0.1397)
			(layers "B.Cu" "B.Mask" "B.Paste")
			(net "Z50_SSD_B1_SMB_CLK")
			(options
				(clearance outline)
				(anchor circle)
			)
			(primitives
				(gr_poly
					(pts
						(arc
							(start -0.1778 0.2794)
							(mid -0.249642 0.249642)
							(end -0.2794 0.1778)
						)
						(arc
							(start -0.2794 -0.1778)
							(mid -0.249642 -0.249642)
							(end -0.1778 -0.2794)
						)
						(arc
							(start 0.1778 -0.2794)
							(mid 0.249642 -0.249642)
							(end 0.2794 -0.1778)
						)
						(arc
							(start 0.2794 0.1778)
							(mid 0.249642 0.249642)
							(end 0.1778 0.2794)
						)
					)
					(width 0)
					(fill yes)
				)
			)
		)
	)
	(footprint ""
		(layer "B.Cu")
		(at 71.755 -41.402)
		(property "Reference" "R23"
			(at 0 0 0)
			(layer "B.SilkS")
			(hide yes)
			(effects
				(font
					(size 1.27 1.27)
				)
				(justify mirror)
			)
		)
		(property "Value" "47KR2F-GP"
			(at -0.064008 -3.993896 0)
			(unlocked yes)
			(layer "B.Fab")
			(hide yes)
			(effects
				(font
					(size 1.016 1.016)
					(thickness 0.1524)
				)
				(justify mirror)
			)
		)
		(property "Device Type" "R402H16"
			(at -0.064008 -5.517896 0)
			(unlocked yes)
			(layer "B.Fab")
			(hide yes)
			(effects
				(font
					(size 1.016 1.016)
					(thickness 0.1524)
				)
				(justify mirror)
			)
		)
		(duplicate_pad_numbers_are_jumpers no)
		(fp_line
			(start -0.508 -0.9398)
			(end 0.508 -0.9398)
			(stroke
				(width 0.1524)
				(type default)
			)
			(layer "B.SilkS")
		)
		(fp_line
			(start 0.508 -0.9398)
			(end 0.508 0.9398)
			(stroke
				(width 0.1524)
				(type default)
			)
			(layer "B.SilkS")
		)
		(fp_rect
			(start 0.508 0.9398)
			(end -0.508 -0.9398)
			(stroke
				(width 0)
				(type default)
			)
			(fill no)
			(layer "B.CrtYd")
		)
		(fp_rect
			(start 0.508 0.9398)
			(end -0.508 -0.9398)
			(stroke
				(width 0)
				(type default)
			)
			(fill no)
			(layer "B.Fab")
		)
		(pad "1" smd custom
			(at 0 -0.4445 180)
			(size 0.1397 0.1397)
			(layers "B.Cu" "B.Mask" "B.Paste")
			(net "P3V3_DPB")
			(options
				(clearance outline)
				(anchor circle)
			)
			(primitives
				(gr_poly
					(pts
						(arc
							(start -0.1778 0.2794)
							(mid -0.249642 0.249642)
							(end -0.2794 0.1778)
						)
						(arc
							(start -0.2794 -0.1778)
							(mid -0.249642 -0.249642)
							(end -0.1778 -0.2794)
						)
						(arc
							(start 0.1778 -0.2794)
							(mid 0.249642 -0.249642)
							(end 0.2794 -0.1778)
						)
						(arc
							(start 0.2794 0.1778)
							(mid 0.249642 0.249642)
							(end 0.1778 0.2794)
						)
					)
					(width 0)
					(fill yes)
				)
			)
		)
		(pad "2" smd custom
			(at 0 0.4445 180)
			(size 0.1397 0.1397)
			(layers "B.Cu" "B.Mask" "B.Paste")
			(net "Z50_SSD_A_ACT#")
			(options
				(clearance outline)
				(anchor circle)
			)
			(primitives
				(gr_poly
					(pts
						(arc
							(start -0.1778 0.2794)
							(mid -0.249642 0.249642)
							(end -0.2794 0.1778)
						)
						(arc
							(start -0.2794 -0.1778)
							(mid -0.249642 -0.249642)
							(end -0.1778 -0.2794)
						)
						(arc
							(start 0.1778 -0.2794)
							(mid 0.249642 -0.249642)
							(end 0.2794 -0.1778)
						)
						(arc
							(start 0.2794 0.1778)
							(mid 0.249642 0.249642)
							(end 0.1778 0.2794)
						)
					)
					(width 0)
					(fill yes)
				)
			)
		)
	)
	(footprint ""
		(layer "B.Cu")
		(at 69.469 -40.386)
		(property "Reference" "U3"
			(at 0 0 0)
			(layer "B.SilkS")
			(hide yes)
			(effects
				(font
					(size 1.27 1.27)
				)
				(justify mirror)
			)
		)
		(property "Value" "74LVC1G32DC-1GP"
			(at 2.3368 -8.6868 0)
			(unlocked yes)
			(layer "B.Fab")
			(hide yes)
			(effects
				(font
					(size 1.016 1.016)
					(thickness 0.1524)
				)
				(justify mirror)
			)
		)
		(property "Device Type" "SC70-5H44"
			(at 2.3114 -10.414 0)
			(unlocked yes)
			(layer "B.Fab")
			(hide yes)
			(effects
				(font
					(size 1.016 1.016)
					(thickness 0.1524)
				)
				(justify mirror)
			)
		)
		(duplicate_pad_numbers_are_jumpers no)
		(fp_line
			(start -1.3843 -1.8034)
			(end -1.3843 -1.1176)
			(stroke
				(width 0.3302)
				(type default)
			)
			(layer "B.SilkS")
		)
		(fp_line
			(start -1.27 -1.7018)
			(end -1.27 1.7018)
			(stroke
				(width 0.1524)
				(type default)
			)
			(layer "B.SilkS")
		)
		(fp_line
			(start -1.27 1.7018)
			(end 1.27 1.7018)
			(stroke
				(width 0.1524)
				(type default)
			)
			(layer "B.SilkS")
		)
		(fp_line
			(start -0.6604 -1.8034)
			(end -1.3843 -1.8034)
			(stroke
				(width 0.3302)
				(type default)
			)
			(layer "B.SilkS")
		)
		(fp_line
			(start 1.27 -1.7018)
			(end -1.27 -1.7018)
			(stroke
				(width 0.1524)
				(type default)
			)
			(layer "B.SilkS")
		)
		(fp_line
			(start 1.27 1.7018)
			(end 1.27 -1.7018)
			(stroke
				(width 0.1524)
				(type default)
			)
			(layer "B.SilkS")
		)
		(fp_rect
			(start 1.524 1.9558)
			(end -1.524 -1.9558)
			(stroke
				(width 0)
				(type default)
			)
			(fill no)
			(layer "B.CrtYd")
		)
		(fp_poly
			(pts
				(xy 1.524 -1.9558) (xy -1.524 -1.9558) (xy -1.524 1.9558) (xy 1.524 1.9558)
			)
			(stroke
				(width 0)
				(type default)
			)
			(fill no)
			(layer "B.Fab")
		)
		(pad "1" smd rect
			(at -0.65024 -0.8255 180)
			(size 0.4064 1.2192)
			(layers "B.Cu" "B.Mask" "B.Paste")
			(net "Z50_SSD_A_ACT#")
		)
		(pad "2" smd rect
			(at 0 -0.8255 180)
			(size 0.4064 1.2192)
			(layers "B.Cu" "B.Mask" "B.Paste")
			(net "Z50_SSD_B_ACT#")
		)
		(pad "3" smd rect
			(at 0.65024 -0.8255 180)
			(size 0.4064 1.2192)
			(layers "B.Cu" "B.Mask" "B.Paste")
			(net "GND")
		)
		(pad "4" smd rect
			(at 0.65024 0.8255 180)
			(size 0.4064 1.2192)
			(layers "B.Cu" "B.Mask" "B.Paste")
			(net "Z50_SSD_ACT#")
		)
		(pad "5" smd rect
			(at -0.65024 0.8255 180)
			(size 0.4064 1.2192)
			(layers "B.Cu" "B.Mask" "B.Paste")
			(net "P3V3_DPB")
		)
	)
	(footprint ""
		(layer "B.Cu")
		(at 52.705 -78.613 90)
		(property "Reference" "PR25"
			(at 0 0 90)
			(layer "B.SilkS")
			(hide yes)
			(effects
				(font
					(size 1.27 1.27)
				)
				(justify mirror)
			)
		)
		(property "Value" "10KR2F-2-GP"
			(at -0.064008 -3.993896 90)
			(unlocked yes)
			(layer "B.Fab")
			(hide yes)
			(effects
				(font
					(size 1.016 1.016)
					(thickness 0.1524)
				)
				(justify mirror)
			)
		)
		(property "Device Type" "R402H16"
			(at -0.064008 -5.517896 90)
			(unlocked yes)
			(layer "B.Fab")
			(hide yes)
			(effects
				(font
					(size 1.016 1.016)
					(thickness 0.1524)
				)
				(justify mirror)
			)
		)
		(duplicate_pad_numbers_are_jumpers no)
		(fp_line
			(start 0.508 -0.9398)
			(end 0.508 0.9398)
			(stroke
				(width 0.1524)
				(type default)
			)
			(layer "B.SilkS")
		)
		(fp_line
			(start -0.508 -0.9398)
			(end 0.508 -0.9398)
			(stroke
				(width 0.1524)
				(type default)
			)
			(layer "B.SilkS")
		)
		(fp_rect
			(start 0.508 0.9398)
			(end -0.508 -0.9398)
			(stroke
				(width 0)
				(type default)
			)
			(fill no)
			(layer "B.CrtYd")
		)
		(fp_rect
			(start 0.508 0.9398)
			(end -0.508 -0.9398)
			(stroke
				(width 0)
				(type default)
			)
			(fill no)
			(layer "B.Fab")
		)
		(pad "1" smd custom
			(at 0 -0.4445 270)
			(size 0.1397 0.1397)
			(layers "B.Cu" "B.Mask" "B.Paste")
			(net "P3V3_DEV_PWRGD")
			(options
				(clearance outline)
				(anchor circle)
			)
			(primitives
				(gr_poly
					(pts
						(arc
							(start -0.1778 0.2794)
							(mid -0.249642 0.249642)
							(end -0.2794 0.1778)
						)
						(arc
							(start -0.2794 -0.1778)
							(mid -0.249642 -0.249642)
							(end -0.1778 -0.2794)
						)
						(arc
							(start 0.1778 -0.2794)
							(mid 0.249642 -0.249642)
							(end 0.2794 -0.1778)
						)
						(arc
							(start 0.2794 0.1778)
							(mid 0.249642 0.249642)
							(end 0.1778 0.2794)
						)
					)
					(width 0)
					(fill yes)
				)
			)
		)
		(pad "2" smd custom
			(at 0 0.4445 270)
			(size 0.1397 0.1397)
			(layers "B.Cu" "B.Mask" "B.Paste")
			(net "P3V3_DEV_VREG")
			(options
				(clearance outline)
				(anchor circle)
			)
			(primitives
				(gr_poly
					(pts
						(arc
							(start -0.1778 0.2794)
							(mid -0.249642 0.249642)
							(end -0.2794 0.1778)
						)
						(arc
							(start -0.2794 -0.1778)
							(mid -0.249642 -0.249642)
							(end -0.1778 -0.2794)
						)
						(arc
							(start 0.1778 -0.2794)
							(mid 0.249642 -0.249642)
							(end 0.2794 -0.1778)
						)
						(arc
							(start 0.2794 0.1778)
							(mid 0.249642 0.249642)
							(end 0.1778 0.2794)
						)
					)
					(width 0)
					(fill yes)
				)
			)
		)
	)
	(footprint ""
		(layer "B.Cu")
		(at 60.579 -62.738 -90)
		(property "Reference" "C16"
			(at 0 0 90)
			(layer "B.SilkS")
			(hide yes)
			(effects
				(font
					(size 1.27 1.27)
				)
				(justify mirror)
			)
		)
		(property "Value" "SC10U6D3V5KX-4GP"
			(at 0.0762 -6.1214 270)
			(unlocked yes)
			(layer "B.Fab")
			(hide yes)
			(effects
				(font
					(size 1.016 1.016)
					(thickness 0.1524)
				)
				(justify mirror)
			)
		)
		(property "Device Type" "C805H58"
			(at 0.0762 -8.1534 270)
			(unlocked yes)
			(layer "B.Fab")
			(hide yes)
			(effects
				(font
					(size 1.016 1.016)
					(thickness 0.1524)
				)
				(justify mirror)
			)
		)
		(duplicate_pad_numbers_are_jumpers no)
		(fp_line
			(start -0.635 0)
			(end 0.635 0)
			(stroke
				(width 0.508)
				(type default)
			)
			(layer "B.SilkS")
		)
		(fp_rect
			(start 0.9652 1.778)
			(end -0.9652 -1.778)
			(stroke
				(width 0)
				(type default)
			)
			(fill no)
			(layer "B.CrtYd")
		)
		(fp_poly
			(pts
				(xy 0.9652 -1.778) (xy -0.9652 -1.778) (xy -0.9652 1.778) (xy 0.9652 1.778)
			)
			(stroke
				(width 0)
				(type default)
			)
			(fill no)
			(layer "B.Fab")
		)
		(pad "1" smd rect
			(at 0 -0.9652 90)
			(size 1.397 1.143)
			(layers "B.Cu" "B.Mask" "B.Paste")
			(net "P3V3_PWR")
		)
		(pad "2" smd rect
			(at 0 0.9652 90)
			(size 1.397 1.143)
			(layers "B.Cu" "B.Mask" "B.Paste")
			(net "GND")
		)
	)
	(footprint ""
		(layer "B.Cu")
		(at 65.151 -24.511 -90)
		(property "Reference" "R37"
			(at 0 0 90)
			(layer "B.SilkS")
			(hide yes)
			(effects
				(font
					(size 1.27 1.27)
				)
				(justify mirror)
			)
		)
		(property "Value" "47KR2F-GP"
			(at -0.064008 -3.993896 270)
			(unlocked yes)
			(layer "B.Fab")
			(hide yes)
			(effects
				(font
					(size 1.016 1.016)
					(thickness 0.1524)
				)
				(justify mirror)
			)
		)
		(property "Device Type" "R402H16"
			(at -0.064008 -5.517896 270)
			(unlocked yes)
			(layer "B.Fab")
			(hide yes)
			(effects
				(font
					(size 1.016 1.016)
					(thickness 0.1524)
				)
				(justify mirror)
			)
		)
		(duplicate_pad_numbers_are_jumpers no)
		(fp_line
			(start -0.508 -0.9398)
			(end 0.508 -0.9398)
			(stroke
				(width 0.1524)
				(type default)
			)
			(layer "B.SilkS")
		)
		(fp_line
			(start 0.508 -0.9398)
			(end 0.508 0.9398)
			(stroke
				(width 0.1524)
				(type default)
			)
			(layer "B.SilkS")
		)
		(fp_rect
			(start 0.508 0.9398)
			(end -0.508 -0.9398)
			(stroke
				(width 0)
				(type default)
			)
			(fill no)
			(layer "B.CrtYd")
		)
		(fp_rect
			(start 0.508 0.9398)
			(end -0.508 -0.9398)
			(stroke
				(width 0)
				(type default)
			)
			(fill no)
			(layer "B.Fab")
		)
		(pad "1" smd custom
			(at 0 -0.4445 90)
			(size 0.1397 0.1397)
			(layers "B.Cu" "B.Mask" "B.Paste")
			(net "Z50_SSD_B1_ALERT#")
			(options
				(clearance outline)
				(anchor circle)
			)
			(primitives
				(gr_poly
					(pts
						(arc
							(start -0.1778 0.2794)
							(mid -0.249642 0.249642)
							(end -0.2794 0.1778)
						)
						(arc
							(start -0.2794 -0.1778)
							(mid -0.249642 -0.249642)
							(end -0.1778 -0.2794)
						)
						(arc
							(start 0.1778 -0.2794)
							(mid 0.249642 -0.249642)
							(end 0.2794 -0.1778)
						)
						(arc
							(start 0.2794 0.1778)
							(mid 0.249642 0.249642)
							(end 0.1778 0.2794)
						)
					)
					(width 0)
					(fill yes)
				)
			)
		)
		(pad "2" smd custom
			(at 0 0.4445 90)
			(size 0.1397 0.1397)
			(layers "B.Cu" "B.Mask" "B.Paste")
			(net "P1V8_PWR")
			(options
				(clearance outline)
				(anchor circle)
			)
			(primitives
				(gr_poly
					(pts
						(arc
							(start -0.1778 0.2794)
							(mid -0.249642 0.249642)
							(end -0.2794 0.1778)
						)
						(arc
							(start -0.2794 -0.1778)
							(mid -0.249642 -0.249642)
							(end -0.1778 -0.2794)
						)
						(arc
							(start 0.1778 -0.2794)
							(mid 0.249642 -0.249642)
							(end 0.2794 -0.1778)
						)
						(arc
							(start 0.2794 0.1778)
							(mid 0.249642 0.249642)
							(end 0.1778 0.2794)
						)
					)
					(width 0)
					(fill yes)
				)
			)
		)
	)
	(footprint ""
		(layer "B.Cu")
		(at 65.151 -50.038 90)
		(property "Reference" "R43"
			(at 0 0 90)
			(layer "B.SilkS")
			(hide yes)
			(effects
				(font
					(size 1.27 1.27)
				)
				(justify mirror)
			)
		)
		(property "Value" "4K7R2F-GP"
			(at -0.064008 -3.993896 90)
			(unlocked yes)
			(layer "B.Fab")
			(hide yes)
			(effects
				(font
					(size 1.016 1.016)
					(thickness 0.1524)
				)
				(justify mirror)
			)
		)
		(property "Device Type" "R402H16"
			(at -0.064008 -5.517896 90)
			(unlocked yes)
			(layer "B.Fab")
			(hide yes)
			(effects
				(font
					(size 1.016 1.016)
					(thickness 0.1524)
				)
				(justify mirror)
			)
		)
		(duplicate_pad_numbers_are_jumpers no)
		(fp_line
			(start 0.508 -0.9398)
			(end 0.508 0.9398)
			(stroke
				(width 0.1524)
				(type default)
			)
			(layer "B.SilkS")
		)
		(fp_line
			(start -0.508 -0.9398)
			(end 0.508 -0.9398)
			(stroke
				(width 0.1524)
				(type default)
			)
			(layer "B.SilkS")
		)
		(fp_rect
			(start 0.508 0.9398)
			(end -0.508 -0.9398)
			(stroke
				(width 0)
				(type default)
			)
			(fill no)
			(layer "B.CrtYd")
		)
		(fp_rect
			(start 0.508 0.9398)
			(end -0.508 -0.9398)
			(stroke
				(width 0)
				(type default)
			)
			(fill no)
			(layer "B.Fab")
		)
		(pad "1" smd custom
			(at 0 -0.4445 270)
			(size 0.1397 0.1397)
			(layers "B.Cu" "B.Mask" "B.Paste")
			(net "P3V3_PWR")
			(options
				(clearance outline)
				(anchor circle)
			)
			(primitives
				(gr_poly
					(pts
						(arc
							(start -0.1778 0.2794)
							(mid -0.249642 0.249642)
							(end -0.2794 0.1778)
						)
						(arc
							(start -0.2794 -0.1778)
							(mid -0.249642 -0.249642)
							(end -0.1778 -0.2794)
						)
						(arc
							(start 0.1778 -0.2794)
							(mid 0.249642 -0.249642)
							(end 0.2794 -0.1778)
						)
						(arc
							(start 0.2794 0.1778)
							(mid 0.249642 0.249642)
							(end 0.1778 0.2794)
						)
					)
					(width 0)
					(fill yes)
				)
			)
		)
		(pad "2" smd custom
			(at 0 0.4445 270)
			(size 0.1397 0.1397)
			(layers "B.Cu" "B.Mask" "B.Paste")
			(net "Z50_SSD_A1_CLKREQ#")
			(options
				(clearance outline)
				(anchor circle)
			)
			(primitives
				(gr_poly
					(pts
						(arc
							(start -0.1778 0.2794)
							(mid -0.249642 0.249642)
							(end -0.2794 0.1778)
						)
						(arc
							(start -0.2794 -0.1778)
							(mid -0.249642 -0.249642)
							(end -0.1778 -0.2794)
						)
						(arc
							(start 0.1778 -0.2794)
							(mid 0.249642 -0.249642)
							(end 0.2794 -0.1778)
						)
						(arc
							(start 0.2794 0.1778)
							(mid 0.249642 0.249642)
							(end 0.1778 0.2794)
						)
					)
					(width 0)
					(fill yes)
				)
			)
		)
	)
	(footprint ""
		(layer "B.Cu")
		(at 29.845 -86.233 180)
		(property "Reference" "R30"
			(at 0 0 0)
			(layer "B.SilkS")
			(hide yes)
			(effects
				(font
					(size 1.27 1.27)
				)
				(justify mirror)
			)
		)
		(property "Value" "47KR2F-GP"
			(at -0.064008 -3.993896 180)
			(unlocked yes)
			(layer "B.Fab")
			(hide yes)
			(effects
				(font
					(size 1.016 1.016)
					(thickness 0.1524)
				)
				(justify mirror)
			)
		)
		(property "Device Type" "R402H16"
			(at -0.064008 -5.517896 180)
			(unlocked yes)
			(layer "B.Fab")
			(hide yes)
			(effects
				(font
					(size 1.016 1.016)
					(thickness 0.1524)
				)
				(justify mirror)
			)
		)
		(duplicate_pad_numbers_are_jumpers no)
		(fp_line
			(start 0.508 -0.9398)
			(end 0.508 0.9398)
			(stroke
				(width 0.1524)
				(type default)
			)
			(layer "B.SilkS")
		)
		(fp_line
			(start -0.508 -0.9398)
			(end 0.508 -0.9398)
			(stroke
				(width 0.1524)
				(type default)
			)
			(layer "B.SilkS")
		)
		(fp_rect
			(start 0.508 0.9398)
			(end -0.508 -0.9398)
			(stroke
				(width 0)
				(type default)
			)
			(fill no)
			(layer "B.CrtYd")
		)
		(fp_rect
			(start 0.508 0.9398)
			(end -0.508 -0.9398)
			(stroke
				(width 0)
				(type default)
			)
			(fill no)
			(layer "B.Fab")
		)
		(pad "1" smd custom
			(at 0 -0.4445)
			(size 0.1397 0.1397)
			(layers "B.Cu" "B.Mask" "B.Paste")
			(net "Z50_SSD_B1_SMB_CLK_R")
			(options
				(clearance outline)
				(anchor circle)
			)
			(primitives
				(gr_poly
					(pts
						(arc
							(start -0.1778 0.2794)
							(mid -0.249642 0.249642)
							(end -0.2794 0.1778)
						)
						(arc
							(start -0.2794 -0.1778)
							(mid -0.249642 -0.249642)
							(end -0.1778 -0.2794)
						)
						(arc
							(start 0.1778 -0.2794)
							(mid 0.249642 -0.249642)
							(end 0.2794 -0.1778)
						)
						(arc
							(start 0.2794 0.1778)
							(mid 0.249642 0.249642)
							(end 0.1778 0.2794)
						)
					)
					(width 0)
					(fill yes)
				)
			)
		)
		(pad "2" smd custom
			(at 0 0.4445)
			(size 0.1397 0.1397)
			(layers "B.Cu" "B.Mask" "B.Paste")
			(net "P3V3_DPB")
			(options
				(clearance outline)
				(anchor circle)
			)
			(primitives
				(gr_poly
					(pts
						(arc
							(start -0.1778 0.2794)
							(mid -0.249642 0.249642)
							(end -0.2794 0.1778)
						)
						(arc
							(start -0.2794 -0.1778)
							(mid -0.249642 -0.249642)
							(end -0.1778 -0.2794)
						)
						(arc
							(start 0.1778 -0.2794)
							(mid 0.249642 -0.249642)
							(end 0.2794 -0.1778)
						)
						(arc
							(start 0.2794 0.1778)
							(mid 0.249642 0.249642)
							(end 0.1778 0.2794)
						)
					)
					(width 0)
					(fill yes)
				)
			)
		)
	)
	(footprint ""
		(layer "B.Cu")
		(at 53.594 -81.28 90)
		(property "Reference" "PC40"
			(at 0 0 90)
			(layer "B.SilkS")
			(hide yes)
			(effects
				(font
					(size 1.27 1.27)
				)
				(justify mirror)
			)
		)
		(property "Value" "SCD1U50V3KX-GP"
			(at 0 -2.8194 90)
			(unlocked yes)
			(layer "B.Fab")
			(hide yes)
			(effects
				(font
					(size 1.016 1.016)
					(thickness 0.1524)
				)
				(justify mirror)
			)
		)
		(property "Device Type" "C603H36"
			(at 0 -4.3434 90)
			(unlocked yes)
			(layer "B.Fab")
			(hide yes)
			(effects
				(font
					(size 1.016 1.016)
					(thickness 0.1524)
				)
				(justify mirror)
			)
		)
		(duplicate_pad_numbers_are_jumpers no)
		(fp_line
			(start -0.508 0)
			(end 0.508 0)
			(stroke
				(width 0.2032)
				(type default)
			)
			(layer "B.SilkS")
		)
		(fp_rect
			(start 0.5842 1.3335)
			(end -0.5842 -1.3335)
			(stroke
				(width 0)
				(type default)
			)
			(fill no)
			(layer "B.CrtYd")
		)
		(fp_rect
			(start 0.5842 1.3335)
			(end -0.5842 -1.3335)
			(stroke
				(width 0)
				(type default)
			)
			(fill no)
			(layer "B.Fab")
		)
		(pad "1" smd custom
			(at 0 -0.762 270)
			(size 0.2159 0.2159)
			(layers "B.Cu" "B.Mask" "B.Paste")
			(net "P3V3_DEV_VBST_RC")
			(options
				(clearance outline)
				(anchor circle)
			)
			(primitives
				(gr_poly
					(pts
						(arc
							(start -0.3302 0.4318)
							(mid -0.402042 0.402042)
							(end -0.4318 0.3302)
						)
						(arc
							(start -0.4318 -0.3302)
							(mid -0.402042 -0.402042)
							(end -0.3302 -0.4318)
						)
						(arc
							(start 0.3302 -0.4318)
							(mid 0.402042 -0.402042)
							(end 0.4318 -0.3302)
						)
						(arc
							(start 0.4318 0.3302)
							(mid 0.402042 0.402042)
							(end 0.3302 0.4318)
						)
					)
					(width 0)
					(fill yes)
				)
			)
		)
		(pad "2" smd custom
			(at 0 0.762 270)
			(size 0.2159 0.2159)
			(layers "B.Cu" "B.Mask" "B.Paste")
			(net "P3V3_DEV_LL")
			(options
				(clearance outline)
				(anchor circle)
			)
			(primitives
				(gr_poly
					(pts
						(arc
							(start -0.3302 0.4318)
							(mid -0.402042 0.402042)
							(end -0.4318 0.3302)
						)
						(arc
							(start -0.4318 -0.3302)
							(mid -0.402042 -0.402042)
							(end -0.3302 -0.4318)
						)
						(arc
							(start 0.3302 -0.4318)
							(mid 0.402042 -0.402042)
							(end 0.4318 -0.3302)
						)
						(arc
							(start 0.4318 0.3302)
							(mid 0.402042 0.402042)
							(end 0.3302 0.4318)
						)
					)
					(width 0)
					(fill yes)
				)
			)
		)
	)
	(footprint ""
		(layer "B.Cu")
		(at 24.511 -77.216)
		(property "Reference" "R63"
			(at 0 0 0)
			(layer "B.SilkS")
			(hide yes)
			(effects
				(font
					(size 1.27 1.27)
				)
				(justify mirror)
			)
		)
		(property "Value" "0R2J-2-GP"
			(at -0.064008 -3.993896 0)
			(unlocked yes)
			(layer "B.Fab")
			(hide yes)
			(effects
				(font
					(size 1.016 1.016)
					(thickness 0.1524)
				)
				(justify mirror)
			)
		)
		(property "Device Type" "R402H16"
			(at -0.064008 -5.517896 0)
			(unlocked yes)
			(layer "B.Fab")
			(hide yes)
			(effects
				(font
					(size 1.016 1.016)
					(thickness 0.1524)
				)
				(justify mirror)
			)
		)
		(duplicate_pad_numbers_are_jumpers no)
		(fp_line
			(start -0.508 -0.9398)
			(end 0.508 -0.9398)
			(stroke
				(width 0.1524)
				(type default)
			)
			(layer "B.SilkS")
		)
		(fp_line
			(start 0.508 -0.9398)
			(end 0.508 0.9398)
			(stroke
				(width 0.1524)
				(type default)
			)
			(layer "B.SilkS")
		)
		(fp_rect
			(start 0.508 0.9398)
			(end -0.508 -0.9398)
			(stroke
				(width 0)
				(type default)
			)
			(fill no)
			(layer "B.CrtYd")
		)
		(fp_rect
			(start 0.508 0.9398)
			(end -0.508 -0.9398)
			(stroke
				(width 0)
				(type default)
			)
			(fill no)
			(layer "B.Fab")
		)
		(pad "1" smd custom
			(at 0 -0.4445 180)
			(size 0.1397 0.1397)
			(layers "B.Cu" "B.Mask" "B.Paste")
			(net "Z50_SSD_A1_SMB_CLK_R")
			(options
				(clearance outline)
				(anchor circle)
			)
			(primitives
				(gr_poly
					(pts
						(arc
							(start -0.1778 0.2794)
							(mid -0.249642 0.249642)
							(end -0.2794 0.1778)
						)
						(arc
							(start -0.2794 -0.1778)
							(mid -0.249642 -0.249642)
							(end -0.1778 -0.2794)
						)
						(arc
							(start 0.1778 -0.2794)
							(mid 0.249642 -0.249642)
							(end 0.2794 -0.1778)
						)
						(arc
							(start 0.2794 0.1778)
							(mid 0.249642 0.249642)
							(end 0.1778 0.2794)
						)
					)
					(width 0)
					(fill yes)
				)
			)
		)
		(pad "2" smd custom
			(at 0 0.4445 180)
			(size 0.1397 0.1397)
			(layers "B.Cu" "B.Mask" "B.Paste")
			(net "Z50_SSD_A1_SMB_CLK")
			(options
				(clearance outline)
				(anchor circle)
			)
			(primitives
				(gr_poly
					(pts
						(arc
							(start -0.1778 0.2794)
							(mid -0.249642 0.249642)
							(end -0.2794 0.1778)
						)
						(arc
							(start -0.2794 -0.1778)
							(mid -0.249642 -0.249642)
							(end -0.1778 -0.2794)
						)
						(arc
							(start 0.1778 -0.2794)
							(mid 0.249642 -0.249642)
							(end 0.2794 -0.1778)
						)
						(arc
							(start 0.2794 0.1778)
							(mid 0.249642 0.249642)
							(end 0.1778 0.2794)
						)
					)
					(width 0)
					(fill yes)
				)
			)
		)
	)
	(footprint ""
		(layer "B.Cu")
		(at 43.766994 -76.2 180)
		(property "Reference" "PR31"
			(at 0 0 0)
			(layer "B.SilkS")
			(hide yes)
			(effects
				(font
					(size 1.27 1.27)
				)
				(justify mirror)
			)
		)
		(property "Value" "121KR2F-L-GP"
			(at -0.064008 -3.993896 180)
			(unlocked yes)
			(layer "B.Fab")
			(hide yes)
			(effects
				(font
					(size 1.016 1.016)
					(thickness 0.1524)
				)
				(justify mirror)
			)
		)
		(property "Device Type" "R402H16"
			(at -0.064008 -5.517896 180)
			(unlocked yes)
			(layer "B.Fab")
			(hide yes)
			(effects
				(font
					(size 1.016 1.016)
					(thickness 0.1524)
				)
				(justify mirror)
			)
		)
		(duplicate_pad_numbers_are_jumpers no)
		(fp_line
			(start 0.508 -0.9398)
			(end 0.508 0.9398)
			(stroke
				(width 0.1524)
				(type default)
			)
			(layer "B.SilkS")
		)
		(fp_line
			(start -0.508 -0.9398)
			(end 0.508 -0.9398)
			(stroke
				(width 0.1524)
				(type default)
			)
			(layer "B.SilkS")
		)
		(fp_rect
			(start 0.508 0.9398)
			(end -0.508 -0.9398)
			(stroke
				(width 0)
				(type default)
			)
			(fill no)
			(layer "B.CrtYd")
		)
		(fp_rect
			(start 0.508 0.9398)
			(end -0.508 -0.9398)
			(stroke
				(width 0)
				(type default)
			)
			(fill no)
			(layer "B.Fab")
		)
		(pad "1" smd custom
			(at 0 -0.4445)
			(size 0.1397 0.1397)
			(layers "B.Cu" "B.Mask" "B.Paste")
			(net "AGND_P3V3_DEV")
			(options
				(clearance outline)
				(anchor circle)
			)
			(primitives
				(gr_poly
					(pts
						(arc
							(start -0.1778 0.2794)
							(mid -0.249642 0.249642)
							(end -0.2794 0.1778)
						)
						(arc
							(start -0.2794 -0.1778)
							(mid -0.249642 -0.249642)
							(end -0.1778 -0.2794)
						)
						(arc
							(start 0.1778 -0.2794)
							(mid 0.249642 -0.249642)
							(end 0.2794 -0.1778)
						)
						(arc
							(start 0.2794 0.1778)
							(mid 0.249642 0.249642)
							(end 0.1778 0.2794)
						)
					)
					(width 0)
					(fill yes)
				)
			)
		)
		(pad "2" smd custom
			(at 0 0.4445)
			(size 0.1397 0.1397)
			(layers "B.Cu" "B.Mask" "B.Paste")
			(net "P3V3_DEV_TRIP")
			(options
				(clearance outline)
				(anchor circle)
			)
			(primitives
				(gr_poly
					(pts
						(arc
							(start -0.1778 0.2794)
							(mid -0.249642 0.249642)
							(end -0.2794 0.1778)
						)
						(arc
							(start -0.2794 -0.1778)
							(mid -0.249642 -0.249642)
							(end -0.1778 -0.2794)
						)
						(arc
							(start 0.1778 -0.2794)
							(mid 0.249642 -0.249642)
							(end 0.2794 -0.1778)
						)
						(arc
							(start 0.2794 0.1778)
							(mid 0.249642 0.249642)
							(end 0.1778 0.2794)
						)
					)
					(width 0)
					(fill yes)
				)
			)
		)
	)
	(footprint ""
		(layer "B.Cu")
		(at 67.183 -39.37)
		(property "Reference" "C41"
			(at 0 0 0)
			(layer "B.SilkS")
			(hide yes)
			(effects
				(font
					(size 1.27 1.27)
				)
				(justify mirror)
			)
		)
		(property "Value" "SCD1U16V2KX-3GP"
			(at -1.1811 -2.7051 0)
			(unlocked yes)
			(layer "B.Fab")
			(hide yes)
			(effects
				(font
					(size 1.016 1.016)
					(thickness 0.1524)
				)
				(justify mirror)
			)
		)
		(property "Device Type" "C402H22"
			(at -1.1811 -4.2291 0)
			(unlocked yes)
			(layer "B.Fab")
			(hide yes)
			(effects
				(font
					(size 1.016 1.016)
					(thickness 0.1524)
				)
				(justify mirror)
			)
		)
		(duplicate_pad_numbers_are_jumpers no)
		(fp_rect
			(start 0.4318 0.9525)
			(end -0.4318 -0.9525)
			(stroke
				(width 0)
				(type default)
			)
			(fill no)
			(layer "B.CrtYd")
		)
		(fp_rect
			(start 0.4318 0.9525)
			(end -0.4318 -0.9525)
			(stroke
				(width 0)
				(type default)
			)
			(fill no)
			(layer "B.Fab")
		)
		(pad "1" smd custom
			(at 0 -0.4445 180)
			(size 0.1524 0.1524)
			(layers "B.Cu" "B.Mask" "B.Paste")
			(net "P3V3_DPB")
			(options
				(clearance outline)
				(anchor circle)
			)
			(primitives
				(gr_poly
					(pts
						(arc
							(start 0.3048 0.2032)
							(mid 0.275042 0.275042)
							(end 0.2032 0.3048)
						)
						(arc
							(start -0.2032 0.3048)
							(mid -0.275042 0.275042)
							(end -0.3048 0.2032)
						)
						(arc
							(start -0.3048 -0.2032)
							(mid -0.275042 -0.275042)
							(end -0.2032 -0.3048)
						)
						(arc
							(start 0.2032 -0.3048)
							(mid 0.275042 -0.275042)
							(end 0.3048 -0.2032)
						)
					)
					(width 0)
					(fill yes)
				)
			)
		)
		(pad "2" smd custom
			(at 0 0.4445 180)
			(size 0.1524 0.1524)
			(layers "B.Cu" "B.Mask" "B.Paste")
			(net "GND")
			(options
				(clearance outline)
				(anchor circle)
			)
			(primitives
				(gr_poly
					(pts
						(arc
							(start 0.3048 0.2032)
							(mid 0.275042 0.275042)
							(end 0.2032 0.3048)
						)
						(arc
							(start -0.2032 0.3048)
							(mid -0.275042 0.275042)
							(end -0.3048 0.2032)
						)
						(arc
							(start -0.3048 -0.2032)
							(mid -0.275042 -0.275042)
							(end -0.2032 -0.3048)
						)
						(arc
							(start 0.2032 -0.3048)
							(mid 0.275042 -0.275042)
							(end 0.3048 -0.2032)
						)
					)
					(width 0)
					(fill yes)
				)
			)
		)
	)
	(footprint ""
		(layer "B.Cu")
		(at 49.608994 -80.518 -90)
		(property "Reference" "PR36"
			(at 0 0 90)
			(layer "B.SilkS")
			(hide yes)
			(effects
				(font
					(size 1.27 1.27)
				)
				(justify mirror)
			)
		)
		(property "Value" "0R2J-2-GP"
			(at -0.064008 -3.993896 270)
			(unlocked yes)
			(layer "B.Fab")
			(hide yes)
			(effects
				(font
					(size 1.016 1.016)
					(thickness 0.1524)
				)
				(justify mirror)
			)
		)
		(property "Device Type" "R402H16"
			(at -0.064008 -5.517896 270)
			(unlocked yes)
			(layer "B.Fab")
			(hide yes)
			(effects
				(font
					(size 1.016 1.016)
					(thickness 0.1524)
				)
				(justify mirror)
			)
		)
		(duplicate_pad_numbers_are_jumpers no)
		(fp_line
			(start -0.508 -0.9398)
			(end 0.508 -0.9398)
			(stroke
				(width 0.1524)
				(type default)
			)
			(layer "B.SilkS")
		)
		(fp_line
			(start 0.508 -0.9398)
			(end 0.508 0.9398)
			(stroke
				(width 0.1524)
				(type default)
			)
			(layer "B.SilkS")
		)
		(fp_rect
			(start 0.508 0.9398)
			(end -0.508 -0.9398)
			(stroke
				(width 0)
				(type default)
			)
			(fill no)
			(layer "B.CrtYd")
		)
		(fp_rect
			(start 0.508 0.9398)
			(end -0.508 -0.9398)
			(stroke
				(width 0)
				(type default)
			)
			(fill no)
			(layer "B.Fab")
		)
		(pad "1" smd custom
			(at 0 -0.4445 90)
			(size 0.1397 0.1397)
			(layers "B.Cu" "B.Mask" "B.Paste")
			(net "P3V3_DEV_ROVP")
			(options
				(clearance outline)
				(anchor circle)
			)
			(primitives
				(gr_poly
					(pts
						(arc
							(start -0.1778 0.2794)
							(mid -0.249642 0.249642)
							(end -0.2794 0.1778)
						)
						(arc
							(start -0.2794 -0.1778)
							(mid -0.249642 -0.249642)
							(end -0.1778 -0.2794)
						)
						(arc
							(start 0.1778 -0.2794)
							(mid 0.249642 -0.249642)
							(end 0.2794 -0.1778)
						)
						(arc
							(start 0.2794 0.1778)
							(mid 0.249642 0.249642)
							(end 0.1778 0.2794)
						)
					)
					(width 0)
					(fill yes)
				)
			)
		)
		(pad "2" smd custom
			(at 0 0.4445 90)
			(size 0.1397 0.1397)
			(layers "B.Cu" "B.Mask" "B.Paste")
			(net "AGND_P3V3_DEV")
			(options
				(clearance outline)
				(anchor circle)
			)
			(primitives
				(gr_poly
					(pts
						(arc
							(start -0.1778 0.2794)
							(mid -0.249642 0.249642)
							(end -0.2794 0.1778)
						)
						(arc
							(start -0.2794 -0.1778)
							(mid -0.249642 -0.249642)
							(end -0.1778 -0.2794)
						)
						(arc
							(start 0.1778 -0.2794)
							(mid 0.249642 -0.249642)
							(end 0.2794 -0.1778)
						)
						(arc
							(start 0.2794 0.1778)
							(mid 0.249642 0.249642)
							(end 0.1778 0.2794)
						)
					)
					(width 0)
					(fill yes)
				)
			)
		)
	)
	(footprint ""
		(layer "B.Cu")
		(at 60.579 -18.034 -90)
		(property "Reference" "C36"
			(at 0 0 90)
			(layer "B.SilkS")
			(hide yes)
			(effects
				(font
					(size 1.27 1.27)
				)
				(justify mirror)
			)
		)
		(property "Value" "SC10U6D3V5KX-4GP"
			(at 0.0762 -6.1214 270)
			(unlocked yes)
			(layer "B.Fab")
			(hide yes)
			(effects
				(font
					(size 1.016 1.016)
					(thickness 0.1524)
				)
				(justify mirror)
			)
		)
		(property "Device Type" "C805H58"
			(at 0.0762 -8.1534 270)
			(unlocked yes)
			(layer "B.Fab")
			(hide yes)
			(effects
				(font
					(size 1.016 1.016)
					(thickness 0.1524)
				)
				(justify mirror)
			)
		)
		(duplicate_pad_numbers_are_jumpers no)
		(fp_line
			(start -0.635 0)
			(end 0.635 0)
			(stroke
				(width 0.508)
				(type default)
			)
			(layer "B.SilkS")
		)
		(fp_rect
			(start 0.9652 1.778)
			(end -0.9652 -1.778)
			(stroke
				(width 0)
				(type default)
			)
			(fill no)
			(layer "B.CrtYd")
		)
		(fp_poly
			(pts
				(xy 0.9652 -1.778) (xy -0.9652 -1.778) (xy -0.9652 1.778) (xy 0.9652 1.778)
			)
			(stroke
				(width 0)
				(type default)
			)
			(fill no)
			(layer "B.Fab")
		)
		(pad "1" smd rect
			(at 0 -0.9652 90)
			(size 1.397 1.143)
			(layers "B.Cu" "B.Mask" "B.Paste")
			(net "P3V3_PWR")
		)
		(pad "2" smd rect
			(at 0 0.9652 90)
			(size 1.397 1.143)
			(layers "B.Cu" "B.Mask" "B.Paste")
			(net "GND")
		)
	)
	(footprint ""
		(layer "B.Cu")
		(at 30.861 -74.422 90)
		(property "Reference" "R54"
			(at 0 0 90)
			(layer "B.SilkS")
			(hide yes)
			(effects
				(font
					(size 1.27 1.27)
				)
				(justify mirror)
			)
		)
		(property "Value" "10KR2F-2-GP"
			(at -0.064008 -3.993896 90)
			(unlocked yes)
			(layer "B.Fab")
			(hide yes)
			(effects
				(font
					(size 1.016 1.016)
					(thickness 0.1524)
				)
				(justify mirror)
			)
		)
		(property "Device Type" "R402H16"
			(at -0.064008 -5.517896 90)
			(unlocked yes)
			(layer "B.Fab")
			(hide yes)
			(effects
				(font
					(size 1.016 1.016)
					(thickness 0.1524)
				)
				(justify mirror)
			)
		)
		(duplicate_pad_numbers_are_jumpers no)
		(fp_line
			(start 0.508 -0.9398)
			(end 0.508 0.9398)
			(stroke
				(width 0.1524)
				(type default)
			)
			(layer "B.SilkS")
		)
		(fp_line
			(start -0.508 -0.9398)
			(end 0.508 -0.9398)
			(stroke
				(width 0.1524)
				(type default)
			)
			(layer "B.SilkS")
		)
		(fp_rect
			(start 0.508 0.9398)
			(end -0.508 -0.9398)
			(stroke
				(width 0)
				(type default)
			)
			(fill no)
			(layer "B.CrtYd")
		)
		(fp_rect
			(start 0.508 0.9398)
			(end -0.508 -0.9398)
			(stroke
				(width 0)
				(type default)
			)
			(fill no)
			(layer "B.Fab")
		)
		(pad "1" smd custom
			(at 0 -0.4445 270)
			(size 0.1397 0.1397)
			(layers "B.Cu" "B.Mask" "B.Paste")
			(net "P3V3_PWR")
			(options
				(clearance outline)
				(anchor circle)
			)
			(primitives
				(gr_poly
					(pts
						(arc
							(start -0.1778 0.2794)
							(mid -0.249642 0.249642)
							(end -0.2794 0.1778)
						)
						(arc
							(start -0.2794 -0.1778)
							(mid -0.249642 -0.249642)
							(end -0.1778 -0.2794)
						)
						(arc
							(start 0.1778 -0.2794)
							(mid 0.249642 -0.249642)
							(end 0.2794 -0.1778)
						)
						(arc
							(start 0.2794 0.1778)
							(mid 0.249642 0.249642)
							(end 0.1778 0.2794)
						)
					)
					(width 0)
					(fill yes)
				)
			)
		)
		(pad "2" smd custom
			(at 0 0.4445 270)
			(size 0.1397 0.1397)
			(layers "B.Cu" "B.Mask" "B.Paste")
			(net "SSD_B1_SMB_OE")
			(options
				(clearance outline)
				(anchor circle)
			)
			(primitives
				(gr_poly
					(pts
						(arc
							(start -0.1778 0.2794)
							(mid -0.249642 0.249642)
							(end -0.2794 0.1778)
						)
						(arc
							(start -0.2794 -0.1778)
							(mid -0.249642 -0.249642)
							(end -0.1778 -0.2794)
						)
						(arc
							(start 0.1778 -0.2794)
							(mid 0.249642 -0.249642)
							(end 0.2794 -0.1778)
						)
						(arc
							(start 0.2794 0.1778)
							(mid 0.249642 0.249642)
							(end 0.1778 0.2794)
						)
					)
					(width 0)
					(fill yes)
				)
			)
		)
	)
	(footprint ""
		(layer "B.Cu")
		(at 65.151 -52.07 -90)
		(property "Reference" "R33"
			(at 0 0 90)
			(layer "B.SilkS")
			(hide yes)
			(effects
				(font
					(size 1.27 1.27)
				)
				(justify mirror)
			)
		)
		(property "Value" "47KR2F-GP"
			(at -0.064008 -3.993896 270)
			(unlocked yes)
			(layer "B.Fab")
			(hide yes)
			(effects
				(font
					(size 1.016 1.016)
					(thickness 0.1524)
				)
				(justify mirror)
			)
		)
		(property "Device Type" "R402H16"
			(at -0.064008 -5.517896 270)
			(unlocked yes)
			(layer "B.Fab")
			(hide yes)
			(effects
				(font
					(size 1.016 1.016)
					(thickness 0.1524)
				)
				(justify mirror)
			)
		)
		(duplicate_pad_numbers_are_jumpers no)
		(fp_line
			(start -0.508 -0.9398)
			(end 0.508 -0.9398)
			(stroke
				(width 0.1524)
				(type default)
			)
			(layer "B.SilkS")
		)
		(fp_line
			(start 0.508 -0.9398)
			(end 0.508 0.9398)
			(stroke
				(width 0.1524)
				(type default)
			)
			(layer "B.SilkS")
		)
		(fp_rect
			(start 0.508 0.9398)
			(end -0.508 -0.9398)
			(stroke
				(width 0)
				(type default)
			)
			(fill no)
			(layer "B.CrtYd")
		)
		(fp_rect
			(start 0.508 0.9398)
			(end -0.508 -0.9398)
			(stroke
				(width 0)
				(type default)
			)
			(fill no)
			(layer "B.Fab")
		)
		(pad "1" smd custom
			(at 0 -0.4445 90)
			(size 0.1397 0.1397)
			(layers "B.Cu" "B.Mask" "B.Paste")
			(net "Z50_SSD_A1_ALERT#")
			(options
				(clearance outline)
				(anchor circle)
			)
			(primitives
				(gr_poly
					(pts
						(arc
							(start -0.1778 0.2794)
							(mid -0.249642 0.249642)
							(end -0.2794 0.1778)
						)
						(arc
							(start -0.2794 -0.1778)
							(mid -0.249642 -0.249642)
							(end -0.1778 -0.2794)
						)
						(arc
							(start 0.1778 -0.2794)
							(mid 0.249642 -0.249642)
							(end 0.2794 -0.1778)
						)
						(arc
							(start 0.2794 0.1778)
							(mid 0.249642 0.249642)
							(end 0.1778 0.2794)
						)
					)
					(width 0)
					(fill yes)
				)
			)
		)
		(pad "2" smd custom
			(at 0 0.4445 90)
			(size 0.1397 0.1397)
			(layers "B.Cu" "B.Mask" "B.Paste")
			(net "P1V8_PWR")
			(options
				(clearance outline)
				(anchor circle)
			)
			(primitives
				(gr_poly
					(pts
						(arc
							(start -0.1778 0.2794)
							(mid -0.249642 0.249642)
							(end -0.2794 0.1778)
						)
						(arc
							(start -0.2794 -0.1778)
							(mid -0.249642 -0.249642)
							(end -0.1778 -0.2794)
						)
						(arc
							(start 0.1778 -0.2794)
							(mid 0.249642 -0.249642)
							(end 0.2794 -0.1778)
						)
						(arc
							(start 0.2794 0.1778)
							(mid 0.249642 0.249642)
							(end 0.1778 0.2794)
						)
					)
					(width 0)
					(fill yes)
				)
			)
		)
	)
	(footprint ""
		(layer "B.Cu")
		(at 58.244994 -42.164)
		(property "Reference" "R10"
			(at 0 0 0)
			(layer "B.SilkS")
			(hide yes)
			(effects
				(font
					(size 1.27 1.27)
				)
				(justify mirror)
			)
		)
		(property "Value" "4K7R2F-GP"
			(at -0.064008 -3.993896 0)
			(unlocked yes)
			(layer "B.Fab")
			(hide yes)
			(effects
				(font
					(size 1.016 1.016)
					(thickness 0.1524)
				)
				(justify mirror)
			)
		)
		(property "Device Type" "R402H16"
			(at -0.064008 -5.517896 0)
			(unlocked yes)
			(layer "B.Fab")
			(hide yes)
			(effects
				(font
					(size 1.016 1.016)
					(thickness 0.1524)
				)
				(justify mirror)
			)
		)
		(duplicate_pad_numbers_are_jumpers no)
		(fp_line
			(start -0.508 -0.9398)
			(end 0.508 -0.9398)
			(stroke
				(width 0.1524)
				(type default)
			)
			(layer "B.SilkS")
		)
		(fp_line
			(start 0.508 -0.9398)
			(end 0.508 0.9398)
			(stroke
				(width 0.1524)
				(type default)
			)
			(layer "B.SilkS")
		)
		(fp_rect
			(start 0.508 0.9398)
			(end -0.508 -0.9398)
			(stroke
				(width 0)
				(type default)
			)
			(fill no)
			(layer "B.CrtYd")
		)
		(fp_rect
			(start 0.508 0.9398)
			(end -0.508 -0.9398)
			(stroke
				(width 0)
				(type default)
			)
			(fill no)
			(layer "B.Fab")
		)
		(pad "1" smd custom
			(at 0 -0.4445 180)
			(size 0.1397 0.1397)
			(layers "B.Cu" "B.Mask" "B.Paste")
			(net "Z50_TEMP_1_A2")
			(options
				(clearance outline)
				(anchor circle)
			)
			(primitives
				(gr_poly
					(pts
						(arc
							(start -0.1778 0.2794)
							(mid -0.249642 0.249642)
							(end -0.2794 0.1778)
						)
						(arc
							(start -0.2794 -0.1778)
							(mid -0.249642 -0.249642)
							(end -0.1778 -0.2794)
						)
						(arc
							(start 0.1778 -0.2794)
							(mid 0.249642 -0.249642)
							(end 0.2794 -0.1778)
						)
						(arc
							(start 0.2794 0.1778)
							(mid 0.249642 0.249642)
							(end 0.1778 0.2794)
						)
					)
					(width 0)
					(fill yes)
				)
			)
		)
		(pad "2" smd custom
			(at 0 0.4445 180)
			(size 0.1397 0.1397)
			(layers "B.Cu" "B.Mask" "B.Paste")
			(net "GND")
			(options
				(clearance outline)
				(anchor circle)
			)
			(primitives
				(gr_poly
					(pts
						(arc
							(start -0.1778 0.2794)
							(mid -0.249642 0.249642)
							(end -0.2794 0.1778)
						)
						(arc
							(start -0.2794 -0.1778)
							(mid -0.249642 -0.249642)
							(end -0.1778 -0.2794)
						)
						(arc
							(start 0.1778 -0.2794)
							(mid 0.249642 -0.249642)
							(end 0.2794 -0.1778)
						)
						(arc
							(start 0.2794 0.1778)
							(mid 0.249642 0.249642)
							(end 0.1778 0.2794)
						)
					)
					(width 0)
					(fill yes)
				)
			)
		)
	)
	(footprint ""
		(layer "B.Cu")
		(at 44.782994 -76.2 180)
		(property "Reference" "PR35"
			(at 0 0 0)
			(layer "B.SilkS")
			(hide yes)
			(effects
				(font
					(size 1.27 1.27)
				)
				(justify mirror)
			)
		)
		(property "Value" "619KR2F-GP"
			(at -0.064008 -3.993896 180)
			(unlocked yes)
			(layer "B.Fab")
			(hide yes)
			(effects
				(font
					(size 1.016 1.016)
					(thickness 0.1524)
				)
				(justify mirror)
			)
		)
		(property "Device Type" "R402H16"
			(at -0.064008 -5.517896 180)
			(unlocked yes)
			(layer "B.Fab")
			(hide yes)
			(effects
				(font
					(size 1.016 1.016)
					(thickness 0.1524)
				)
				(justify mirror)
			)
		)
		(duplicate_pad_numbers_are_jumpers no)
		(fp_line
			(start 0.508 -0.9398)
			(end 0.508 0.9398)
			(stroke
				(width 0.1524)
				(type default)
			)
			(layer "B.SilkS")
		)
		(fp_line
			(start -0.508 -0.9398)
			(end 0.508 -0.9398)
			(stroke
				(width 0.1524)
				(type default)
			)
			(layer "B.SilkS")
		)
		(fp_rect
			(start 0.508 0.9398)
			(end -0.508 -0.9398)
			(stroke
				(width 0)
				(type default)
			)
			(fill no)
			(layer "B.CrtYd")
		)
		(fp_rect
			(start 0.508 0.9398)
			(end -0.508 -0.9398)
			(stroke
				(width 0)
				(type default)
			)
			(fill no)
			(layer "B.Fab")
		)
		(pad "1" smd custom
			(at 0 -0.4445)
			(size 0.1397 0.1397)
			(layers "B.Cu" "B.Mask" "B.Paste")
			(net "AGND_P3V3_DEV")
			(options
				(clearance outline)
				(anchor circle)
			)
			(primitives
				(gr_poly
					(pts
						(arc
							(start -0.1778 0.2794)
							(mid -0.249642 0.249642)
							(end -0.2794 0.1778)
						)
						(arc
							(start -0.2794 -0.1778)
							(mid -0.249642 -0.249642)
							(end -0.1778 -0.2794)
						)
						(arc
							(start 0.1778 -0.2794)
							(mid 0.249642 -0.249642)
							(end 0.2794 -0.1778)
						)
						(arc
							(start 0.2794 0.1778)
							(mid 0.249642 0.249642)
							(end 0.1778 0.2794)
						)
					)
					(width 0)
					(fill yes)
				)
			)
		)
		(pad "2" smd custom
			(at 0 0.4445)
			(size 0.1397 0.1397)
			(layers "B.Cu" "B.Mask" "B.Paste")
			(net "P3V3_DEV_RF")
			(options
				(clearance outline)
				(anchor circle)
			)
			(primitives
				(gr_poly
					(pts
						(arc
							(start -0.1778 0.2794)
							(mid -0.249642 0.249642)
							(end -0.2794 0.1778)
						)
						(arc
							(start -0.2794 -0.1778)
							(mid -0.249642 -0.249642)
							(end -0.1778 -0.2794)
						)
						(arc
							(start 0.1778 -0.2794)
							(mid 0.249642 -0.249642)
							(end 0.2794 -0.1778)
						)
						(arc
							(start 0.2794 0.1778)
							(mid 0.249642 0.249642)
							(end 0.1778 0.2794)
						)
					)
					(width 0)
					(fill yes)
				)
			)
		)
	)
	(footprint ""
		(layer "B.Cu")
		(at 79.149956 -27.595068 90)
		(property "Reference" "SKT1"
			(at 0 0 90)
			(layer "B.SilkS")
			(hide yes)
			(effects
				(font
					(size 1.27 1.27)
				)
				(justify mirror)
			)
		)
		(property "Value" "SKT-SAS28-P15-PCIE25-2-GP"
			(at -10.668 -4.2672 90)
			(unlocked yes)
			(layer "B.Fab")
			(hide yes)
			(effects
				(font
					(size 1.016 1.016)
					(thickness 0.1524)
				)
				(justify mirror)
			)
		)
		(property "Device Type" "78758-0001"
			(at -10.668 -5.7912 90)
			(unlocked yes)
			(layer "B.Fab")
			(hide yes)
			(effects
				(font
					(size 1.016 1.016)
					(thickness 0.1524)
				)
				(justify mirror)
			)
		)
		(duplicate_pad_numbers_are_jumpers no)
		(fp_line
			(start 21.6154 -2.6416)
			(end 21.6154 1.7526)
			(stroke
				(width 0.1524)
				(type default)
			)
			(layer "B.SilkS")
		)
		(fp_line
			(start 16.4592 -2.6416)
			(end 21.6154 -2.6416)
			(stroke
				(width 0.1524)
				(type default)
			)
			(layer "B.SilkS")
		)
		(fp_line
			(start -16.4592 -2.6416)
			(end -16.4592 -1.5113)
			(stroke
				(width 0.1524)
				(type default)
			)
			(layer "B.SilkS")
		)
		(fp_line
			(start -21.6154 -2.6416)
			(end -16.4592 -2.6416)
			(stroke
				(width 0.1524)
				(type default)
			)
			(layer "B.SilkS")
		)
		(fp_line
			(start 16.4592 -1.5113)
			(end 16.4592 -2.6416)
			(stroke
				(width 0.1524)
				(type default)
			)
			(layer "B.SilkS")
		)
		(fp_line
			(start -16.4592 -1.5113)
			(end 16.4592 -1.5113)
			(stroke
				(width 0.1524)
				(type default)
			)
			(layer "B.SilkS")
		)
		(fp_line
			(start 24.3713 1.7526)
			(end 24.3713 3.5052)
			(stroke
				(width 0.1524)
				(type default)
			)
			(layer "B.SilkS")
		)
		(fp_line
			(start 21.6154 1.7526)
			(end 24.3713 1.7526)
			(stroke
				(width 0.1524)
				(type default)
			)
			(layer "B.SilkS")
		)
		(fp_line
			(start -21.6154 1.7526)
			(end -21.6154 -2.6416)
			(stroke
				(width 0.1524)
				(type default)
			)
			(layer "B.SilkS")
		)
		(fp_line
			(start -24.3713 1.7526)
			(end -21.6154 1.7526)
			(stroke
				(width 0.1524)
				(type default)
			)
			(layer "B.SilkS")
		)
		(fp_line
			(start 21.165058 1.89992)
			(end 16.914876 1.89992)
			(stroke
				(width 0.1524)
				(type default)
			)
			(layer "B.SilkS")
		)
		(fp_line
			(start -16.914876 1.89992)
			(end -21.165058 1.89992)
			(stroke
				(width 0.1524)
				(type default)
			)
			(layer "B.SilkS")
		)
		(fp_line
			(start 16.415004 2.400046)
			(end 16.415004 3.700018)
			(stroke
				(width 0.1524)
				(type default)
			)
			(layer "B.SilkS")
		)
		(fp_line
			(start -21.66493 2.400046)
			(end -21.66493 9.59993)
			(stroke
				(width 0.1524)
				(type default)
			)
			(layer "B.SilkS")
		)
		(fp_line
			(start 26.3779 3.5052)
			(end 26.3779 8.001)
			(stroke
				(width 0.1524)
				(type default)
			)
			(layer "B.SilkS")
		)
		(fp_line
			(start 24.3713 3.5052)
			(end 26.3779 3.5052)
			(stroke
				(width 0.1524)
				(type default)
			)
			(layer "B.SilkS")
		)
		(fp_line
			(start -24.3713 3.5052)
			(end -24.3713 1.7526)
			(stroke
				(width 0.1524)
				(type default)
			)
			(layer "B.SilkS")
		)
		(fp_line
			(start -26.3779 3.5052)
			(end -24.3713 3.5052)
			(stroke
				(width 0.1524)
				(type default)
			)
			(layer "B.SilkS")
		)
		(fp_line
			(start -16.415004 3.700018)
			(end -16.415004 2.400046)
			(stroke
				(width 0.1524)
				(type default)
			)
			(layer "B.SilkS")
		)
		(fp_line
			(start 15.914878 4.19989)
			(end -15.914878 4.19989)
			(stroke
				(width 0.1524)
				(type default)
			)
			(layer "B.SilkS")
		)
		(fp_line
			(start 26.3779 8.001)
			(end 24.3713 8.001)
			(stroke
				(width 0.1524)
				(type default)
			)
			(layer "B.SilkS")
		)
		(fp_line
			(start 24.3713 8.001)
			(end 24.3713 9.59993)
			(stroke
				(width 0.1524)
				(type default)
			)
			(layer "B.SilkS")
		)
		(fp_line
			(start -24.3713 8.001)
			(end -26.3779 8.001)
			(stroke
				(width 0.1524)
				(type default)
			)
			(layer "B.SilkS")
		)
		(fp_line
			(start -26.3779 8.001)
			(end -26.3779 3.5052)
			(stroke
				(width 0.1524)
				(type default)
			)
			(layer "B.SilkS")
		)
		(fp_line
			(start 24.3713 9.59993)
			(end 21.66493 9.59993)
			(stroke
				(width 0.1524)
				(type default)
			)
			(layer "B.SilkS")
		)
		(fp_line
			(start 21.66493 9.59993)
			(end 21.66493 2.400046)
			(stroke
				(width 0.1524)
				(type default)
			)
			(layer "B.SilkS")
		)
		(fp_line
			(start -21.66493 9.59993)
			(end -24.3713 9.59993)
			(stroke
				(width 0.1524)
				(type default)
			)
			(layer "B.SilkS")
		)
		(fp_line
			(start -24.3713 9.59993)
			(end -24.3713 8.001)
			(stroke
				(width 0.1524)
				(type default)
			)
			(layer "B.SilkS")
		)
		(fp_arc
			(start 21.165058 1.89992)
			(mid 21.518554 2.046484)
			(end 21.66493 2.400046)
			(stroke
				(width 0.1524)
				(type default)
			)
			(layer "B.SilkS")
		)
		(fp_arc
			(start -16.914876 1.89992)
			(mid -16.561423 2.046507)
			(end -16.415004 2.400046)
			(stroke
				(width 0.1524)
				(type default)
			)
			(layer "B.SilkS")
		)
		(fp_arc
			(start 16.415004 2.400046)
			(mid 16.561397 2.046491)
			(end 16.914876 1.89992)
			(stroke
				(width 0.1524)
				(type default)
			)
			(layer "B.SilkS")
		)
		(fp_arc
			(start -21.66493 2.400046)
			(mid -21.518539 2.046479)
			(end -21.165058 1.89992)
			(stroke
				(width 0.1524)
				(type default)
			)
			(layer "B.SilkS")
		)
		(fp_arc
			(start 16.415004 3.700018)
			(mid 16.268514 4.053587)
			(end 15.914878 4.19989)
			(stroke
				(width 0.1524)
				(type default)
			)
			(layer "B.SilkS")
		)
		(fp_arc
			(start -15.914878 4.19989)
			(mid -16.268519 4.053582)
			(end -16.415004 3.700018)
			(stroke
				(width 0.1524)
				(type default)
			)
			(layer "B.SilkS")
		)
		(fp_poly
			(pts
				(xy 24.1173 9.6012) (xy 24.1173 6.858) (xy 25.3111 6.858) (xy 25.3111 4.6482) (xy 24.1173 4.6482)
				(xy 24.1173 2.0066) (xy 21.3614 2.0066) (xy 21.3614 -2.3876) (xy 16.7132 -2.3876) (xy 16.7132 -1.2573)
				(xy -16.7132 -1.2573) (xy -16.7132 -2.3876) (xy -21.3614 -2.3876) (xy -21.3614 2.0066) (xy -24.1173 2.0066)
				(xy -24.1173 4.6482) (xy -25.3111 4.6482) (xy -25.3111 6.858) (xy -24.1173 6.858) (xy -24.1173 9.6012)
			)
			(stroke
				(width 0)
				(type default)
			)
			(fill no)
			(layer "B.CrtYd")
		)
		(fp_poly
			(pts
				(xy 25.1333 10.6172) (xy 25.1333 8.255) (xy 26.6319 8.255) (xy 26.6319 3.2512) (xy 25.1333 3.2512)
				(xy 25.1333 0.9906) (xy 22.3774 0.9906) (xy 22.3774 -3.4036) (xy 15.6972 -3.4036) (xy 15.6972 -2.2733)
				(xy -15.6972 -2.2733) (xy -15.6972 -3.4036) (xy -22.3774 -3.4036) (xy -22.3774 0.9906) (xy -25.1333 0.9906)
				(xy -25.1333 3.2512) (xy -26.6319 3.2512) (xy -26.6319 8.255) (xy -25.1333 8.255) (xy -25.1333 10.6172)
				(xy 0.7493 10.6172) (xy 0.7493 9.6012) (xy -24.1173 9.6012) (xy -24.1173 6.858) (xy -25.3111 6.858)
				(xy -25.3111 4.6482) (xy -24.1173 4.6482) (xy -24.1173 2.0066) (xy -21.3614 2.0066) (xy -21.3614 -2.3876)
				(xy -16.7132 -2.3876) (xy -16.7132 -1.2573) (xy 16.7132 -1.2573) (xy 16.7132 -2.3876) (xy 21.3614 -2.3876)
				(xy 21.3614 2.0066) (xy 24.1173 2.0066) (xy 24.1173 4.6482) (xy 25.3111 4.6482) (xy 25.3111 6.858)
				(xy 24.1173 6.858) (xy 24.1173 9.6012) (xy 0.762 9.6012) (xy 0.762 10.6172)
			)
			(stroke
				(width 0)
				(type default)
			)
			(fill no)
			(layer "B.CrtYd")
		)
		(fp_poly
			(pts
				(xy 25.1333 10.6172) (xy 25.1333 8.255) (xy 26.6319 8.255) (xy 26.6319 3.2512) (xy 25.1333 3.2512)
				(xy 25.1333 0.9906) (xy 22.3774 0.9906) (xy 22.3774 -3.4036) (xy 15.6972 -3.4036) (xy 15.6972 -2.2733)
				(xy -15.6972 -2.2733) (xy -15.6972 -3.4036) (xy -22.3774 -3.4036) (xy -22.3774 0.9906) (xy -25.1333 0.9906)
				(xy -25.1333 3.2512) (xy -26.6319 3.2512) (xy -26.6319 8.255) (xy -25.1333 8.255) (xy -25.1333 10.6172)
			)
			(stroke
				(width 0)
				(type default)
			)
			(fill no)
			(layer "B.Fab")
		)
		(fp_text user "Slit"
			(at 2.413 6.4008 90)
			(unlocked yes)
			(layer "B.SilkS")
			(effects
				(font
					(size 1.016 1.016)
					(thickness 0.1524)
				)
				(justify left mirror)
			)
		)
		(pad "" np_thru_hole circle
			(at -19.500088 0 270)
			(size 0.254 0.254)
			(drill 1.6002)
			(layers "*.Cu" "*.Mask")
			(clearance 1.0287)
			(thermal_gap 1.0287)
		)
		(pad "" np_thru_hole circle
			(at 19.500088 0 270)
			(size 0.254 0.254)
			(drill 1.651)
			(layers "*.Cu" "*.Mask")
			(clearance 1.0541)
			(thermal_gap 1.0541)
		)
		(pad "E1" smd rect
			(at 7.055104 -0.379984 270)
			(size 0.508 1.7526)
			(layers "B.Cu" "B.Mask" "B.Paste")
			(net "D85_PCIE_B_REFCLK_P")
		)
		(pad "E2" smd rect
			(at 6.255004 -0.379984 270)
			(size 0.508 1.7526)
			(layers "B.Cu" "B.Mask" "B.Paste")
			(net "D85_PCIE_B_REFCLK_N")
		)
		(pad "E3" smd rect
			(at 5.455158 -0.379984 270)
			(size 0.508 1.7526)
			(layers "B.Cu" "B.Mask" "B.Paste")
			(net "P3V3_DPB")
		)
		(pad "E4" smd rect
			(at 4.655058 -0.379984 270)
			(size 0.508 1.7526)
			(layers "B.Cu" "B.Mask" "B.Paste")
			(net "Z50_DEV_RST#")
		)
		(pad "E5" smd rect
			(at 3.855212 -0.379984 270)
			(size 0.508 1.7526)
			(layers "B.Cu" "B.Mask" "B.Paste")
			(net "Z50_DEV_RST#")
		)
		(pad "E6" smd rect
			(at 3.055112 -0.379984 270)
			(size 0.508 1.7526)
			(layers "B.Cu" "B.Mask" "B.Paste")
			(net "Net_165")
		)
		(pad "E7" smd rect
			(at 15.48003 2.23012 270)
			(size 0.508 1.7526)
			(layers "B.Cu" "B.Mask" "B.Paste")
			(net "D85_PCIE_A_REFCLK_P")
		)
		(pad "E8" smd rect
			(at 14.67993 2.23012 270)
			(size 0.508 1.7526)
			(layers "B.Cu" "B.Mask" "B.Paste")
			(net "D85_PCIE_A_REFCLK_N")
		)
		(pad "E9" smd rect
			(at 13.880084 2.23012 270)
			(size 0.508 1.7526)
			(layers "B.Cu" "B.Mask" "B.Paste")
			(net "GND")
		)
		(pad "E10" smd rect
			(at 13.079984 2.23012 270)
			(size 0.508 1.7526)
			(layers "B.Cu" "B.Mask" "B.Paste")
			(net "D85_PCIE_A_TX0_P")
		)
		(pad "E11" smd rect
			(at 12.279884 2.23012 270)
			(size 0.508 1.7526)
			(layers "B.Cu" "B.Mask" "B.Paste")
			(net "D85_PCIE_A_TX0_N")
		)
		(pad "E12" smd rect
			(at 11.480038 2.23012 270)
			(size 0.508 1.7526)
			(layers "B.Cu" "B.Mask" "B.Paste")
			(net "GND")
		)
		(pad "E13" smd rect
			(at 10.679938 2.23012 270)
			(size 0.508 1.7526)
			(layers "B.Cu" "B.Mask" "B.Paste")
			(net "D85_PCIE_A_RX0_N")
		)
		(pad "E14" smd rect
			(at 9.880092 2.23012 270)
			(size 0.508 1.7526)
			(layers "B.Cu" "B.Mask" "B.Paste")
			(net "D85_PCIE_A_RX0_P")
		)
		(pad "E15" smd rect
			(at 9.079992 2.23012 270)
			(size 0.508 1.7526)
			(layers "B.Cu" "B.Mask" "B.Paste")
			(net "GND")
		)
		(pad "E16" smd rect
			(at 8.279892 2.23012 270)
			(size 0.508 1.7526)
			(layers "B.Cu" "B.Mask" "B.Paste")
			(net "Net_169")
		)
		(pad "E17" smd rect
			(at -9.320022 2.23012 270)
			(size 0.508 1.7526)
			(layers "B.Cu" "B.Mask" "B.Paste")
			(net "D85_PCIE_B_TX1_P")
		)
		(pad "E18" smd rect
			(at -10.120122 2.23012 270)
			(size 0.508 1.7526)
			(layers "B.Cu" "B.Mask" "B.Paste")
			(net "D85_PCIE_B_TX1_N")
		)
		(pad "E19" smd rect
			(at -10.919968 2.23012 270)
			(size 0.508 1.7526)
			(layers "B.Cu" "B.Mask" "B.Paste")
			(net "GND")
		)
		(pad "E20" smd rect
			(at -11.720068 2.23012 270)
			(size 0.508 1.7526)
			(layers "B.Cu" "B.Mask" "B.Paste")
			(net "D85_PCIE_B_RX1_N")
		)
		(pad "E21" smd rect
			(at -12.519914 2.23012 270)
			(size 0.508 1.7526)
			(layers "B.Cu" "B.Mask" "B.Paste")
			(net "D85_PCIE_B_RX1_P")
		)
		(pad "E22" smd rect
			(at -13.320014 2.23012 270)
			(size 0.508 1.7526)
			(layers "B.Cu" "B.Mask" "B.Paste")
			(net "GND")
		)
		(pad "E23" smd rect
			(at -14.120114 2.23012 270)
			(size 0.508 1.7526)
			(layers "B.Cu" "B.Mask" "B.Paste")
			(net "Z50_SMB_CLK")
		)
		(pad "E24" smd rect
			(at -14.91996 2.23012 270)
			(size 0.508 1.7526)
			(layers "B.Cu" "B.Mask" "B.Paste")
			(net "Z50_SMB_DATA")
		)
		(pad "E25" smd rect
			(at -15.72006 2.23012 270)
			(size 0.508 1.7526)
			(layers "B.Cu" "B.Mask" "B.Paste")
			(net "Net_157")
		)
		(pad "G1" smd rect
			(at 24.21509 5.750052 270)
			(size 3.81 3.9878)
			(layers "B.Cu" "B.Mask" "B.Paste")
			(net "GND")
		)
		(pad "G2" smd rect
			(at -24.21509 5.750052 270)
			(size 3.81 3.9878)
			(layers "B.Cu" "B.Mask" "B.Paste")
			(net "GND")
		)
		(pad "P1" smd rect
			(at 1.905 -0.329946 270)
			(size 0.889 1.8542)
			(layers "B.Cu" "B.Mask" "B.Paste")
			(net "Net_162")
		)
		(pad "P2" smd rect
			(at 0.635 -0.329946 270)
			(size 0.889 1.8542)
			(layers "B.Cu" "B.Mask" "B.Paste")
			(net "Net_163")
		)
		(pad "P3" smd rect
			(at -0.635 -0.329946 270)
			(size 0.889 1.8542)
			(layers "B.Cu" "B.Mask" "B.Paste")
			(net "Net_164")
		)
		(pad "P4" smd rect
			(at -1.905 -0.329946 270)
			(size 0.889 1.8542)
			(layers "B.Cu" "B.Mask" "B.Paste")
			(net "Z50_SSD_M2_PRSNT#")
		)
		(pad "P5" smd rect
			(at -3.175 -0.329946 270)
			(size 0.889 1.8542)
			(layers "B.Cu" "B.Mask" "B.Paste")
			(net "GND")
		)
		(pad "P6" smd rect
			(at -4.445 -0.329946 270)
			(size 0.889 1.8542)
			(layers "B.Cu" "B.Mask" "B.Paste")
			(net "GND")
		)
		(pad "P7" smd rect
			(at -5.715 -0.329946 270)
			(size 0.889 1.8542)
			(layers "B.Cu" "B.Mask" "B.Paste")
			(net "Net_159")
		)
		(pad "P8" smd rect
			(at -6.985 -0.329946 270)
			(size 0.889 1.8542)
			(layers "B.Cu" "B.Mask" "B.Paste")
			(net "Net_160")
		)
		(pad "P9" smd rect
			(at -8.255 -0.329946 270)
			(size 0.889 1.8542)
			(layers "B.Cu" "B.Mask" "B.Paste")
			(net "Net_161")
		)
		(pad "P10" smd rect
			(at -9.525 -0.329946 270)
			(size 0.889 1.8542)
			(layers "B.Cu" "B.Mask" "B.Paste")
			(net "Z50_SSD_M2_PRSNT#")
		)
		(pad "P11" smd rect
			(at -10.795 -0.329946 270)
			(size 0.889 1.8542)
			(layers "B.Cu" "B.Mask" "B.Paste")
			(net "Z50_SSD_ACT#")
		)
		(pad "P12" smd rect
			(at -12.065 -0.329946 270)
			(size 0.889 1.8542)
			(layers "B.Cu" "B.Mask" "B.Paste")
			(net "GND")
		)
		(pad "P13" smd rect
			(at -13.335 -0.329946 270)
			(size 0.889 1.8542)
			(layers "B.Cu" "B.Mask" "B.Paste")
			(net "P12V")
		)
		(pad "P14" smd rect
			(at -14.605 -0.329946 270)
			(size 0.889 1.8542)
			(layers "B.Cu" "B.Mask" "B.Paste")
			(net "P12V")
		)
		(pad "P15" smd rect
			(at -15.875 -0.329946 270)
			(size 0.889 1.8542)
			(layers "B.Cu" "B.Mask" "B.Paste")
			(net "P12V")
		)
		(pad "S1" smd rect
			(at 15.875 -0.329946 270)
			(size 0.889 1.8542)
			(layers "B.Cu" "B.Mask" "B.Paste")
			(net "GND")
		)
		(pad "S2" smd rect
			(at 14.605 -0.329946 270)
			(size 0.889 1.8542)
			(layers "B.Cu" "B.Mask" "B.Paste")
			(net "Net_173")
		)
		(pad "S3" smd rect
			(at 13.335 -0.329946 270)
			(size 0.889 1.8542)
			(layers "B.Cu" "B.Mask" "B.Paste")
			(net "Net_174")
		)
		(pad "S4" smd rect
			(at 12.065 -0.329946 270)
			(size 0.889 1.8542)
			(layers "B.Cu" "B.Mask" "B.Paste")
			(net "GND")
		)
		(pad "S5" smd rect
			(at 10.795 -0.329946 270)
			(size 0.889 1.8542)
			(layers "B.Cu" "B.Mask" "B.Paste")
			(net "Net_167")
		)
		(pad "S6" smd rect
			(at 9.525 -0.329946 270)
			(size 0.889 1.8542)
			(layers "B.Cu" "B.Mask" "B.Paste")
			(net "Net_168")
		)
		(pad "S7" smd rect
			(at 8.255 -0.329946 270)
			(size 0.889 1.8542)
			(layers "B.Cu" "B.Mask" "B.Paste")
			(net "GND")
		)
		(pad "S8" smd rect
			(at 7.480046 2.23012 270)
			(size 0.508 1.7526)
			(layers "B.Cu" "B.Mask" "B.Paste")
			(net "GND")
		)
		(pad "S9" smd rect
			(at 6.679946 2.23012 270)
			(size 0.508 1.7526)
			(layers "B.Cu" "B.Mask" "B.Paste")
			(net "Net_170")
		)
		(pad "S10" smd rect
			(at 5.8801 2.23012 270)
			(size 0.508 1.7526)
			(layers "B.Cu" "B.Mask" "B.Paste")
			(net "Net_171")
		)
		(pad "S11" smd rect
			(at 5.08 2.23012 270)
			(size 0.508 1.7526)
			(layers "B.Cu" "B.Mask" "B.Paste")
			(net "GND")
		)
		(pad "S12" smd rect
			(at 4.2799 2.23012 270)
			(size 0.508 1.7526)
			(layers "B.Cu" "B.Mask" "B.Paste")
			(net "Net_172")
		)
		(pad "S13" smd rect
			(at 3.480054 2.23012 270)
			(size 0.508 1.7526)
			(layers "B.Cu" "B.Mask" "B.Paste")
			(net "Net_166")
		)
		(pad "S14" smd rect
			(at 2.679954 2.23012 270)
			(size 0.508 1.7526)
			(layers "B.Cu" "B.Mask" "B.Paste")
			(net "GND")
		)
		(pad "S15" smd rect
			(at 1.880108 2.23012 270)
			(size 0.508 1.7526)
			(layers "B.Cu" "B.Mask" "B.Paste")
			(net "Net_44")
		)
		(pad "S16" smd rect
			(at 1.080008 2.23012 270)
			(size 0.508 1.7526)
			(layers "B.Cu" "B.Mask" "B.Paste")
			(net "GND")
		)
		(pad "S17" smd rect
			(at 0.279908 2.23012 270)
			(size 0.508 1.7526)
			(layers "B.Cu" "B.Mask" "B.Paste")
			(net "D85_PCIE_A_TX1_P")
		)
		(pad "S18" smd rect
			(at -0.519938 2.23012 270)
			(size 0.508 1.7526)
			(layers "B.Cu" "B.Mask" "B.Paste")
			(net "D85_PCIE_A_TX1_N")
		)
		(pad "S19" smd rect
			(at -1.320038 2.23012 270)
			(size 0.508 1.7526)
			(layers "B.Cu" "B.Mask" "B.Paste")
			(net "GND")
		)
		(pad "S20" smd rect
			(at -2.119884 2.23012 270)
			(size 0.508 1.7526)
			(layers "B.Cu" "B.Mask" "B.Paste")
			(net "D85_PCIE_A_RX1_N")
		)
		(pad "S21" smd rect
			(at -2.919984 2.23012 270)
			(size 0.508 1.7526)
			(layers "B.Cu" "B.Mask" "B.Paste")
			(net "D85_PCIE_A_RX1_P")
		)
		(pad "S22" smd rect
			(at -3.720084 2.23012 270)
			(size 0.508 1.7526)
			(layers "B.Cu" "B.Mask" "B.Paste")
			(net "GND")
		)
		(pad "S23" smd rect
			(at -4.51993 2.23012 270)
			(size 0.508 1.7526)
			(layers "B.Cu" "B.Mask" "B.Paste")
			(net "D85_PCIE_B_TX0_P")
		)
		(pad "S24" smd rect
			(at -5.32003 2.23012 270)
			(size 0.508 1.7526)
			(layers "B.Cu" "B.Mask" "B.Paste")
			(net "D85_PCIE_B_TX0_N")
		)
		(pad "S25" smd rect
			(at -6.119876 2.23012 270)
			(size 0.508 1.7526)
			(layers "B.Cu" "B.Mask" "B.Paste")
			(net "GND")
		)
		(pad "S26" smd rect
			(at -6.919976 2.23012 270)
			(size 0.508 1.7526)
			(layers "B.Cu" "B.Mask" "B.Paste")
			(net "D85_PCIE_B_RX0_N")
		)
		(pad "S27" smd rect
			(at -7.720076 2.23012 270)
			(size 0.508 1.7526)
			(layers "B.Cu" "B.Mask" "B.Paste")
			(net "D85_PCIE_B_RX0_P")
		)
		(pad "S28" smd rect
			(at -8.519922 2.23012 270)
			(size 0.508 1.7526)
			(layers "B.Cu" "B.Mask" "B.Paste")
			(net "GND")
		)
		(zone
			(layers "F.Cu" "B.Cu" "In1.Cu" "In2.Cu" "In3.Cu" "In4.Cu" "In5.Cu" "In6.Cu")
			(hatch none 0.5)
			(connect_pads
				(clearance 0)
			)
			(min_thickness 0.25)
			(keepout
				(tracks not_allowed)
				(vias allowed)
				(pads allowed)
				(copperpour not_allowed)
				(footprints allowed)
			)
			(placement
				(enabled no)
				(sheetname "")
			)
			(fill
				(thermal_gap 0.5)
				(thermal_bridge_width 0.5)
				(island_removal_mode 0)
			)
			(polygon
				(pts
					(arc
						(start 80.254856 -8.09498)
						(mid 78.045056 -8.09498)
						(end 80.254856 -8.09498)
					)
				)
			)
		)
		(zone
			(layers "F.Cu" "B.Cu" "In1.Cu" "In2.Cu" "In3.Cu" "In4.Cu" "In5.Cu" "In6.Cu")
			(hatch none 0.5)
			(connect_pads
				(clearance 0)
			)
			(min_thickness 0.25)
			(keepout
				(tracks not_allowed)
				(vias allowed)
				(pads allowed)
				(copperpour not_allowed)
				(footprints allowed)
			)
			(placement
				(enabled no)
				(sheetname "")
			)
			(fill
				(thermal_gap 0.5)
				(thermal_bridge_width 0.5)
				(island_removal_mode 0)
			)
			(polygon
				(pts
					(arc
						(start 80.280256 -47.095156)
						(mid 78.019656 -47.095156)
						(end 80.280256 -47.095156)
					)
				)
			)
		)
	)
	(footprint ""
		(layer "B.Cu")
		(at 24.13 -71.755 180)
		(property "Reference" "R35"
			(at 0 0 0)
			(layer "B.SilkS")
			(hide yes)
			(effects
				(font
					(size 1.27 1.27)
				)
				(justify mirror)
			)
		)
		(property "Value" "47KR2F-GP"
			(at -0.064008 -3.993896 180)
			(unlocked yes)
			(layer "B.Fab")
			(hide yes)
			(effects
				(font
					(size 1.016 1.016)
					(thickness 0.1524)
				)
				(justify mirror)
			)
		)
		(property "Device Type" "R402H16"
			(at -0.064008 -5.517896 180)
			(unlocked yes)
			(layer "B.Fab")
			(hide yes)
			(effects
				(font
					(size 1.016 1.016)
					(thickness 0.1524)
				)
				(justify mirror)
			)
		)
		(duplicate_pad_numbers_are_jumpers no)
		(fp_line
			(start 0.508 -0.9398)
			(end 0.508 0.9398)
			(stroke
				(width 0.1524)
				(type default)
			)
			(layer "B.SilkS")
		)
		(fp_line
			(start -0.508 -0.9398)
			(end 0.508 -0.9398)
			(stroke
				(width 0.1524)
				(type default)
			)
			(layer "B.SilkS")
		)
		(fp_rect
			(start 0.508 0.9398)
			(end -0.508 -0.9398)
			(stroke
				(width 0)
				(type default)
			)
			(fill no)
			(layer "B.CrtYd")
		)
		(fp_rect
			(start 0.508 0.9398)
			(end -0.508 -0.9398)
			(stroke
				(width 0)
				(type default)
			)
			(fill no)
			(layer "B.Fab")
		)
		(pad "1" smd custom
			(at 0 -0.4445)
			(size 0.1397 0.1397)
			(layers "B.Cu" "B.Mask" "B.Paste")
			(net "Z50_SSD_A1_SMB_CLK")
			(options
				(clearance outline)
				(anchor circle)
			)
			(primitives
				(gr_poly
					(pts
						(arc
							(start -0.1778 0.2794)
							(mid -0.249642 0.249642)
							(end -0.2794 0.1778)
						)
						(arc
							(start -0.2794 -0.1778)
							(mid -0.249642 -0.249642)
							(end -0.1778 -0.2794)
						)
						(arc
							(start 0.1778 -0.2794)
							(mid 0.249642 -0.249642)
							(end 0.2794 -0.1778)
						)
						(arc
							(start 0.2794 0.1778)
							(mid 0.249642 0.249642)
							(end 0.1778 0.2794)
						)
					)
					(width 0)
					(fill yes)
				)
			)
		)
		(pad "2" smd custom
			(at 0 0.4445)
			(size 0.1397 0.1397)
			(layers "B.Cu" "B.Mask" "B.Paste")
			(net "P1V8_PWR")
			(options
				(clearance outline)
				(anchor circle)
			)
			(primitives
				(gr_poly
					(pts
						(arc
							(start -0.1778 0.2794)
							(mid -0.249642 0.249642)
							(end -0.2794 0.1778)
						)
						(arc
							(start -0.2794 -0.1778)
							(mid -0.249642 -0.249642)
							(end -0.1778 -0.2794)
						)
						(arc
							(start 0.1778 -0.2794)
							(mid 0.249642 -0.249642)
							(end 0.2794 -0.1778)
						)
						(arc
							(start 0.2794 0.1778)
							(mid 0.249642 0.249642)
							(end 0.1778 0.2794)
						)
					)
					(width 0)
					(fill yes)
				)
			)
		)
	)
	(footprint ""
		(layer "B.Cu")
		(at 67.183 -41.402 180)
		(property "Reference" "R24"
			(at 0 0 0)
			(layer "B.SilkS")
			(hide yes)
			(effects
				(font
					(size 1.27 1.27)
				)
				(justify mirror)
			)
		)
		(property "Value" "47KR2F-GP"
			(at -0.064008 -3.993896 180)
			(unlocked yes)
			(layer "B.Fab")
			(hide yes)
			(effects
				(font
					(size 1.016 1.016)
					(thickness 0.1524)
				)
				(justify mirror)
			)
		)
		(property "Device Type" "R402H16"
			(at -0.064008 -5.517896 180)
			(unlocked yes)
			(layer "B.Fab")
			(hide yes)
			(effects
				(font
					(size 1.016 1.016)
					(thickness 0.1524)
				)
				(justify mirror)
			)
		)
		(duplicate_pad_numbers_are_jumpers no)
		(fp_line
			(start 0.508 -0.9398)
			(end 0.508 0.9398)
			(stroke
				(width 0.1524)
				(type default)
			)
			(layer "B.SilkS")
		)
		(fp_line
			(start -0.508 -0.9398)
			(end 0.508 -0.9398)
			(stroke
				(width 0.1524)
				(type default)
			)
			(layer "B.SilkS")
		)
		(fp_rect
			(start 0.508 0.9398)
			(end -0.508 -0.9398)
			(stroke
				(width 0)
				(type default)
			)
			(fill no)
			(layer "B.CrtYd")
		)
		(fp_rect
			(start 0.508 0.9398)
			(end -0.508 -0.9398)
			(stroke
				(width 0)
				(type default)
			)
			(fill no)
			(layer "B.Fab")
		)
		(pad "1" smd custom
			(at 0 -0.4445)
			(size 0.1397 0.1397)
			(layers "B.Cu" "B.Mask" "B.Paste")
			(net "P3V3_DPB")
			(options
				(clearance outline)
				(anchor circle)
			)
			(primitives
				(gr_poly
					(pts
						(arc
							(start -0.1778 0.2794)
							(mid -0.249642 0.249642)
							(end -0.2794 0.1778)
						)
						(arc
							(start -0.2794 -0.1778)
							(mid -0.249642 -0.249642)
							(end -0.1778 -0.2794)
						)
						(arc
							(start 0.1778 -0.2794)
							(mid 0.249642 -0.249642)
							(end 0.2794 -0.1778)
						)
						(arc
							(start 0.2794 0.1778)
							(mid 0.249642 0.249642)
							(end 0.1778 0.2794)
						)
					)
					(width 0)
					(fill yes)
				)
			)
		)
		(pad "2" smd custom
			(at 0 0.4445)
			(size 0.1397 0.1397)
			(layers "B.Cu" "B.Mask" "B.Paste")
			(net "Z50_SSD_B_ACT#")
			(options
				(clearance outline)
				(anchor circle)
			)
			(primitives
				(gr_poly
					(pts
						(arc
							(start -0.1778 0.2794)
							(mid -0.249642 0.249642)
							(end -0.2794 0.1778)
						)
						(arc
							(start -0.2794 -0.1778)
							(mid -0.249642 -0.249642)
							(end -0.1778 -0.2794)
						)
						(arc
							(start 0.1778 -0.2794)
							(mid 0.249642 -0.249642)
							(end 0.2794 -0.1778)
						)
						(arc
							(start 0.2794 0.1778)
							(mid 0.249642 0.249642)
							(end 0.1778 0.2794)
						)
					)
					(width 0)
					(fill yes)
				)
			)
		)
	)
	(footprint ""
		(layer "B.Cu")
		(at 37.162994 -79.629 -90)
		(property "Reference" "PR21"
			(at 0 0 90)
			(layer "B.SilkS")
			(hide yes)
			(effects
				(font
					(size 1.27 1.27)
				)
				(justify mirror)
			)
		)
		(property "Value" "2D2R3J-2-GP"
			(at 0.0254 -2.5146 270)
			(unlocked yes)
			(layer "B.Fab")
			(hide yes)
			(effects
				(font
					(size 1.016 1.016)
					(thickness 0.1524)
				)
				(justify mirror)
			)
		)
		(property "Device Type" "R603H22"
			(at 0.0254 -4.0386 270)
			(unlocked yes)
			(layer "B.Fab")
			(hide yes)
			(effects
				(font
					(size 1.016 1.016)
					(thickness 0.1524)
				)
				(justify mirror)
			)
		)
		(duplicate_pad_numbers_are_jumpers no)
		(fp_line
			(start -0.2032 0)
			(end -0.4826 0)
			(stroke
				(width 0.2032)
				(type default)
			)
			(layer "B.SilkS")
		)
		(fp_line
			(start 0.4826 0)
			(end 0.2032 0)
			(stroke
				(width 0.2032)
				(type default)
			)
			(layer "B.SilkS")
		)
		(fp_rect
			(start 0.5842 1.3335)
			(end -0.5842 -1.3335)
			(stroke
				(width 0)
				(type default)
			)
			(fill no)
			(layer "B.CrtYd")
		)
		(fp_rect
			(start 0.5842 1.3335)
			(end -0.5842 -1.3335)
			(stroke
				(width 0)
				(type default)
			)
			(fill no)
			(layer "B.Fab")
		)
		(pad "1" smd custom
			(at 0 -0.762 90)
			(size 0.2159 0.2159)
			(layers "B.Cu" "B.Mask" "B.Paste")
			(net "P3V3_DEV_VDD")
			(options
				(clearance outline)
				(anchor circle)
			)
			(primitives
				(gr_poly
					(pts
						(arc
							(start -0.3302 0.4318)
							(mid -0.402042 0.402042)
							(end -0.4318 0.3302)
						)
						(arc
							(start -0.4318 -0.3302)
							(mid -0.402042 -0.402042)
							(end -0.3302 -0.4318)
						)
						(arc
							(start 0.3302 -0.4318)
							(mid 0.402042 -0.402042)
							(end 0.4318 -0.3302)
						)
						(arc
							(start 0.4318 0.3302)
							(mid 0.402042 0.402042)
							(end 0.3302 0.4318)
						)
					)
					(width 0)
					(fill yes)
				)
			)
		)
		(pad "2" smd custom
			(at 0 0.762 90)
			(size 0.2159 0.2159)
			(layers "B.Cu" "B.Mask" "B.Paste")
			(net "P12V")
			(options
				(clearance outline)
				(anchor circle)
			)
			(primitives
				(gr_poly
					(pts
						(arc
							(start -0.3302 0.4318)
							(mid -0.402042 0.402042)
							(end -0.4318 0.3302)
						)
						(arc
							(start -0.4318 -0.3302)
							(mid -0.402042 -0.402042)
							(end -0.3302 -0.4318)
						)
						(arc
							(start 0.3302 -0.4318)
							(mid 0.402042 -0.402042)
							(end 0.4318 -0.3302)
						)
						(arc
							(start 0.4318 0.3302)
							(mid 0.402042 0.402042)
							(end 0.3302 0.4318)
						)
					)
					(width 0)
					(fill yes)
				)
			)
		)
	)
	(footprint ""
		(layer "B.Cu")
		(at 60.579 -35.179 -90)
		(property "Reference" "C35"
			(at 0 0 90)
			(layer "B.SilkS")
			(hide yes)
			(effects
				(font
					(size 1.27 1.27)
				)
				(justify mirror)
			)
		)
		(property "Value" "SC10U6D3V5KX-4GP"
			(at 0.0762 -6.1214 270)
			(unlocked yes)
			(layer "B.Fab")
			(hide yes)
			(effects
				(font
					(size 1.016 1.016)
					(thickness 0.1524)
				)
				(justify mirror)
			)
		)
		(property "Device Type" "C805H58"
			(at 0.0762 -8.1534 270)
			(unlocked yes)
			(layer "B.Fab")
			(hide yes)
			(effects
				(font
					(size 1.016 1.016)
					(thickness 0.1524)
				)
				(justify mirror)
			)
		)
		(duplicate_pad_numbers_are_jumpers no)
		(fp_line
			(start -0.635 0)
			(end 0.635 0)
			(stroke
				(width 0.508)
				(type default)
			)
			(layer "B.SilkS")
		)
		(fp_rect
			(start 0.9652 1.778)
			(end -0.9652 -1.778)
			(stroke
				(width 0)
				(type default)
			)
			(fill no)
			(layer "B.CrtYd")
		)
		(fp_poly
			(pts
				(xy 0.9652 -1.778) (xy -0.9652 -1.778) (xy -0.9652 1.778) (xy 0.9652 1.778)
			)
			(stroke
				(width 0)
				(type default)
			)
			(fill no)
			(layer "B.Fab")
		)
		(pad "1" smd rect
			(at 0 -0.9652 90)
			(size 1.397 1.143)
			(layers "B.Cu" "B.Mask" "B.Paste")
			(net "P3V3_PWR")
		)
		(pad "2" smd rect
			(at 0 0.9652 90)
			(size 1.397 1.143)
			(layers "B.Cu" "B.Mask" "B.Paste")
			(net "GND")
		)
	)
	(footprint ""
		(layer "B.Cu")
		(at 69.342 -34.417 -90)
		(property "Reference" "R48"
			(at 0 0 90)
			(layer "B.SilkS")
			(hide yes)
			(effects
				(font
					(size 1.27 1.27)
				)
				(justify mirror)
			)
		)
		(property "Value" "47KR2F-GP"
			(at -0.064008 -3.993896 270)
			(unlocked yes)
			(layer "B.Fab")
			(hide yes)
			(effects
				(font
					(size 1.016 1.016)
					(thickness 0.1524)
				)
				(justify mirror)
			)
		)
		(property "Device Type" "R402H16"
			(at -0.064008 -5.517896 270)
			(unlocked yes)
			(layer "B.Fab")
			(hide yes)
			(effects
				(font
					(size 1.016 1.016)
					(thickness 0.1524)
				)
				(justify mirror)
			)
		)
		(duplicate_pad_numbers_are_jumpers no)
		(fp_line
			(start -0.508 -0.9398)
			(end 0.508 -0.9398)
			(stroke
				(width 0.1524)
				(type default)
			)
			(layer "B.SilkS")
		)
		(fp_line
			(start 0.508 -0.9398)
			(end 0.508 0.9398)
			(stroke
				(width 0.1524)
				(type default)
			)
			(layer "B.SilkS")
		)
		(fp_rect
			(start 0.508 0.9398)
			(end -0.508 -0.9398)
			(stroke
				(width 0)
				(type default)
			)
			(fill no)
			(layer "B.CrtYd")
		)
		(fp_rect
			(start 0.508 0.9398)
			(end -0.508 -0.9398)
			(stroke
				(width 0)
				(type default)
			)
			(fill no)
			(layer "B.Fab")
		)
		(pad "1" smd custom
			(at 0 -0.4445 90)
			(size 0.1397 0.1397)
			(layers "B.Cu" "B.Mask" "B.Paste")
			(net "Z50_SSD_B_ACT#")
			(options
				(clearance outline)
				(anchor circle)
			)
			(primitives
				(gr_poly
					(pts
						(arc
							(start -0.1778 0.2794)
							(mid -0.249642 0.249642)
							(end -0.2794 0.1778)
						)
						(arc
							(start -0.2794 -0.1778)
							(mid -0.249642 -0.249642)
							(end -0.1778 -0.2794)
						)
						(arc
							(start 0.1778 -0.2794)
							(mid 0.249642 -0.249642)
							(end 0.2794 -0.1778)
						)
						(arc
							(start 0.2794 0.1778)
							(mid 0.249642 0.249642)
							(end 0.1778 0.2794)
						)
					)
					(width 0)
					(fill yes)
				)
			)
		)
		(pad "2" smd custom
			(at 0 0.4445 90)
			(size 0.1397 0.1397)
			(layers "B.Cu" "B.Mask" "B.Paste")
			(net "GND")
			(options
				(clearance outline)
				(anchor circle)
			)
			(primitives
				(gr_poly
					(pts
						(arc
							(start -0.1778 0.2794)
							(mid -0.249642 0.249642)
							(end -0.2794 0.1778)
						)
						(arc
							(start -0.2794 -0.1778)
							(mid -0.249642 -0.249642)
							(end -0.1778 -0.2794)
						)
						(arc
							(start 0.1778 -0.2794)
							(mid 0.249642 -0.249642)
							(end 0.2794 -0.1778)
						)
						(arc
							(start 0.2794 0.1778)
							(mid 0.249642 0.249642)
							(end 0.1778 0.2794)
						)
					)
					(width 0)
					(fill yes)
				)
			)
		)
	)
	(footprint ""
		(layer "B.Cu")
		(at 59.260994 -38.354 180)
		(property "Reference" "R8"
			(at 0 0 0)
			(layer "B.SilkS")
			(hide yes)
			(effects
				(font
					(size 1.27 1.27)
				)
				(justify mirror)
			)
		)
		(property "Value" "4K7R2F-GP"
			(at -0.064008 -3.993896 180)
			(unlocked yes)
			(layer "B.Fab")
			(hide yes)
			(effects
				(font
					(size 1.016 1.016)
					(thickness 0.1524)
				)
				(justify mirror)
			)
		)
		(property "Device Type" "R402H16"
			(at -0.064008 -5.517896 180)
			(unlocked yes)
			(layer "B.Fab")
			(hide yes)
			(effects
				(font
					(size 1.016 1.016)
					(thickness 0.1524)
				)
				(justify mirror)
			)
		)
		(duplicate_pad_numbers_are_jumpers no)
		(fp_line
			(start 0.508 -0.9398)
			(end 0.508 0.9398)
			(stroke
				(width 0.1524)
				(type default)
			)
			(layer "B.SilkS")
		)
		(fp_line
			(start -0.508 -0.9398)
			(end 0.508 -0.9398)
			(stroke
				(width 0.1524)
				(type default)
			)
			(layer "B.SilkS")
		)
		(fp_rect
			(start 0.508 0.9398)
			(end -0.508 -0.9398)
			(stroke
				(width 0)
				(type default)
			)
			(fill no)
			(layer "B.CrtYd")
		)
		(fp_rect
			(start 0.508 0.9398)
			(end -0.508 -0.9398)
			(stroke
				(width 0)
				(type default)
			)
			(fill no)
			(layer "B.Fab")
		)
		(pad "1" smd custom
			(at 0 -0.4445)
			(size 0.1397 0.1397)
			(layers "B.Cu" "B.Mask" "B.Paste")
			(net "P3V3_DPB")
			(options
				(clearance outline)
				(anchor circle)
			)
			(primitives
				(gr_poly
					(pts
						(arc
							(start -0.1778 0.2794)
							(mid -0.249642 0.249642)
							(end -0.2794 0.1778)
						)
						(arc
							(start -0.2794 -0.1778)
							(mid -0.249642 -0.249642)
							(end -0.1778 -0.2794)
						)
						(arc
							(start 0.1778 -0.2794)
							(mid 0.249642 -0.249642)
							(end 0.2794 -0.1778)
						)
						(arc
							(start 0.2794 0.1778)
							(mid 0.249642 0.249642)
							(end 0.1778 0.2794)
						)
					)
					(width 0)
					(fill yes)
				)
			)
		)
		(pad "2" smd custom
			(at 0 0.4445)
			(size 0.1397 0.1397)
			(layers "B.Cu" "B.Mask" "B.Paste")
			(net "Z50_TEMP_1_A0")
			(options
				(clearance outline)
				(anchor circle)
			)
			(primitives
				(gr_poly
					(pts
						(arc
							(start -0.1778 0.2794)
							(mid -0.249642 0.249642)
							(end -0.2794 0.1778)
						)
						(arc
							(start -0.2794 -0.1778)
							(mid -0.249642 -0.249642)
							(end -0.1778 -0.2794)
						)
						(arc
							(start 0.1778 -0.2794)
							(mid 0.249642 -0.249642)
							(end 0.2794 -0.1778)
						)
						(arc
							(start 0.2794 0.1778)
							(mid 0.249642 0.249642)
							(end 0.1778 0.2794)
						)
					)
					(width 0)
					(fill yes)
				)
			)
		)
	)
	(footprint ""
		(layer "B.Cu")
		(at 52.783994 -79.756 -90)
		(property "Reference" "PR38"
			(at 0 0 90)
			(layer "B.SilkS")
			(hide yes)
			(effects
				(font
					(size 1.27 1.27)
				)
				(justify mirror)
			)
		)
		(property "Value" "0R3J-0-U-GP"
			(at 0.0254 -2.5146 270)
			(unlocked yes)
			(layer "B.Fab")
			(hide yes)
			(effects
				(font
					(size 1.016 1.016)
					(thickness 0.1524)
				)
				(justify mirror)
			)
		)
		(property "Device Type" "R603H22"
			(at 0.0254 -4.0386 270)
			(unlocked yes)
			(layer "B.Fab")
			(hide yes)
			(effects
				(font
					(size 1.016 1.016)
					(thickness 0.1524)
				)
				(justify mirror)
			)
		)
		(duplicate_pad_numbers_are_jumpers no)
		(fp_line
			(start -0.2032 0)
			(end -0.4826 0)
			(stroke
				(width 0.2032)
				(type default)
			)
			(layer "B.SilkS")
		)
		(fp_line
			(start 0.4826 0)
			(end 0.2032 0)
			(stroke
				(width 0.2032)
				(type default)
			)
			(layer "B.SilkS")
		)
		(fp_rect
			(start 0.5842 1.3335)
			(end -0.5842 -1.3335)
			(stroke
				(width 0)
				(type default)
			)
			(fill no)
			(layer "B.CrtYd")
		)
		(fp_rect
			(start 0.5842 1.3335)
			(end -0.5842 -1.3335)
			(stroke
				(width 0)
				(type default)
			)
			(fill no)
			(layer "B.Fab")
		)
		(pad "1" smd custom
			(at 0 -0.762 90)
			(size 0.2159 0.2159)
			(layers "B.Cu" "B.Mask" "B.Paste")
			(net "P3V3_DEV_VBST_RC")
			(options
				(clearance outline)
				(anchor circle)
			)
			(primitives
				(gr_poly
					(pts
						(arc
							(start -0.3302 0.4318)
							(mid -0.402042 0.402042)
							(end -0.4318 0.3302)
						)
						(arc
							(start -0.4318 -0.3302)
							(mid -0.402042 -0.402042)
							(end -0.3302 -0.4318)
						)
						(arc
							(start 0.3302 -0.4318)
							(mid 0.402042 -0.402042)
							(end 0.4318 -0.3302)
						)
						(arc
							(start 0.4318 0.3302)
							(mid 0.402042 0.402042)
							(end 0.3302 0.4318)
						)
					)
					(width 0)
					(fill yes)
				)
			)
		)
		(pad "2" smd custom
			(at 0 0.762 90)
			(size 0.2159 0.2159)
			(layers "B.Cu" "B.Mask" "B.Paste")
			(net "P3V3_DEV_VBST")
			(options
				(clearance outline)
				(anchor circle)
			)
			(primitives
				(gr_poly
					(pts
						(arc
							(start -0.3302 0.4318)
							(mid -0.402042 0.402042)
							(end -0.4318 0.3302)
						)
						(arc
							(start -0.4318 -0.3302)
							(mid -0.402042 -0.402042)
							(end -0.3302 -0.4318)
						)
						(arc
							(start 0.3302 -0.4318)
							(mid 0.402042 -0.402042)
							(end 0.4318 -0.3302)
						)
						(arc
							(start 0.4318 0.3302)
							(mid 0.402042 0.402042)
							(end 0.3302 0.4318)
						)
					)
					(width 0)
					(fill yes)
				)
			)
		)
	)
	(footprint ""
		(layer "B.Cu")
		(at 69.342 -33.401 -90)
		(property "Reference" "R15"
			(at 0 0 90)
			(layer "B.SilkS")
			(hide yes)
			(effects
				(font
					(size 1.27 1.27)
				)
				(justify mirror)
			)
		)
		(property "Value" "0R2J-2-GP"
			(at -0.064008 -3.993896 270)
			(unlocked yes)
			(layer "B.Fab")
			(hide yes)
			(effects
				(font
					(size 1.016 1.016)
					(thickness 0.1524)
				)
				(justify mirror)
			)
		)
		(property "Device Type" "R402H16"
			(at -0.064008 -5.517896 270)
			(unlocked yes)
			(layer "B.Fab")
			(hide yes)
			(effects
				(font
					(size 1.016 1.016)
					(thickness 0.1524)
				)
				(justify mirror)
			)
		)
		(duplicate_pad_numbers_are_jumpers no)
		(fp_line
			(start -0.508 -0.9398)
			(end 0.508 -0.9398)
			(stroke
				(width 0.1524)
				(type default)
			)
			(layer "B.SilkS")
		)
		(fp_line
			(start 0.508 -0.9398)
			(end 0.508 0.9398)
			(stroke
				(width 0.1524)
				(type default)
			)
			(layer "B.SilkS")
		)
		(fp_rect
			(start 0.508 0.9398)
			(end -0.508 -0.9398)
			(stroke
				(width 0)
				(type default)
			)
			(fill no)
			(layer "B.CrtYd")
		)
		(fp_rect
			(start 0.508 0.9398)
			(end -0.508 -0.9398)
			(stroke
				(width 0)
				(type default)
			)
			(fill no)
			(layer "B.Fab")
		)
		(pad "1" smd custom
			(at 0 -0.4445 90)
			(size 0.1397 0.1397)
			(layers "B.Cu" "B.Mask" "B.Paste")
			(net "Z50_SSD_B_ACT#")
			(options
				(clearance outline)
				(anchor circle)
			)
			(primitives
				(gr_poly
					(pts
						(arc
							(start -0.1778 0.2794)
							(mid -0.249642 0.249642)
							(end -0.2794 0.1778)
						)
						(arc
							(start -0.2794 -0.1778)
							(mid -0.249642 -0.249642)
							(end -0.1778 -0.2794)
						)
						(arc
							(start 0.1778 -0.2794)
							(mid 0.249642 -0.249642)
							(end 0.2794 -0.1778)
						)
						(arc
							(start 0.2794 0.1778)
							(mid 0.249642 0.249642)
							(end 0.1778 0.2794)
						)
					)
					(width 0)
					(fill yes)
				)
			)
		)
		(pad "2" smd custom
			(at 0 0.4445 90)
			(size 0.1397 0.1397)
			(layers "B.Cu" "B.Mask" "B.Paste")
			(net "Z50_SSD_B_R_ACT#")
			(options
				(clearance outline)
				(anchor circle)
			)
			(primitives
				(gr_poly
					(pts
						(arc
							(start -0.1778 0.2794)
							(mid -0.249642 0.249642)
							(end -0.2794 0.1778)
						)
						(arc
							(start -0.2794 -0.1778)
							(mid -0.249642 -0.249642)
							(end -0.1778 -0.2794)
						)
						(arc
							(start 0.1778 -0.2794)
							(mid 0.249642 -0.249642)
							(end 0.2794 -0.1778)
						)
						(arc
							(start 0.2794 0.1778)
							(mid 0.249642 0.249642)
							(end 0.1778 0.2794)
						)
					)
					(width 0)
					(fill yes)
				)
			)
		)
	)
	(footprint ""
		(layer "B.Cu")
		(at 67.691 -60.579 180)
		(property "Reference" "R14"
			(at 0 0 0)
			(layer "B.SilkS")
			(hide yes)
			(effects
				(font
					(size 1.27 1.27)
				)
				(justify mirror)
			)
		)
		(property "Value" "0R2J-2-GP"
			(at -0.064008 -3.993896 180)
			(unlocked yes)
			(layer "B.Fab")
			(hide yes)
			(effects
				(font
					(size 1.016 1.016)
					(thickness 0.1524)
				)
				(justify mirror)
			)
		)
		(property "Device Type" "R402H16"
			(at -0.064008 -5.517896 180)
			(unlocked yes)
			(layer "B.Fab")
			(hide yes)
			(effects
				(font
					(size 1.016 1.016)
					(thickness 0.1524)
				)
				(justify mirror)
			)
		)
		(duplicate_pad_numbers_are_jumpers no)
		(fp_line
			(start 0.508 -0.9398)
			(end 0.508 0.9398)
			(stroke
				(width 0.1524)
				(type default)
			)
			(layer "B.SilkS")
		)
		(fp_line
			(start -0.508 -0.9398)
			(end 0.508 -0.9398)
			(stroke
				(width 0.1524)
				(type default)
			)
			(layer "B.SilkS")
		)
		(fp_rect
			(start 0.508 0.9398)
			(end -0.508 -0.9398)
			(stroke
				(width 0)
				(type default)
			)
			(fill no)
			(layer "B.CrtYd")
		)
		(fp_rect
			(start 0.508 0.9398)
			(end -0.508 -0.9398)
			(stroke
				(width 0)
				(type default)
			)
			(fill no)
			(layer "B.Fab")
		)
		(pad "1" smd custom
			(at 0 -0.4445)
			(size 0.1397 0.1397)
			(layers "B.Cu" "B.Mask" "B.Paste")
			(net "Z50_SSD_A_ACT#")
			(options
				(clearance outline)
				(anchor circle)
			)
			(primitives
				(gr_poly
					(pts
						(arc
							(start -0.1778 0.2794)
							(mid -0.249642 0.249642)
							(end -0.2794 0.1778)
						)
						(arc
							(start -0.2794 -0.1778)
							(mid -0.249642 -0.249642)
							(end -0.1778 -0.2794)
						)
						(arc
							(start 0.1778 -0.2794)
							(mid 0.249642 -0.249642)
							(end 0.2794 -0.1778)
						)
						(arc
							(start 0.2794 0.1778)
							(mid 0.249642 0.249642)
							(end 0.1778 0.2794)
						)
					)
					(width 0)
					(fill yes)
				)
			)
		)
		(pad "2" smd custom
			(at 0 0.4445)
			(size 0.1397 0.1397)
			(layers "B.Cu" "B.Mask" "B.Paste")
			(net "Z50_SSD_A_R_ACT#")
			(options
				(clearance outline)
				(anchor circle)
			)
			(primitives
				(gr_poly
					(pts
						(arc
							(start -0.1778 0.2794)
							(mid -0.249642 0.249642)
							(end -0.2794 0.1778)
						)
						(arc
							(start -0.2794 -0.1778)
							(mid -0.249642 -0.249642)
							(end -0.1778 -0.2794)
						)
						(arc
							(start 0.1778 -0.2794)
							(mid 0.249642 -0.249642)
							(end 0.2794 -0.1778)
						)
						(arc
							(start 0.2794 0.1778)
							(mid 0.249642 0.249642)
							(end 0.1778 0.2794)
						)
					)
					(width 0)
					(fill yes)
				)
			)
		)
	)
	(footprint ""
		(layer "B.Cu")
		(at 27.94 -71.755 180)
		(property "Reference" "R29"
			(at 0 0 0)
			(layer "B.SilkS")
			(hide yes)
			(effects
				(font
					(size 1.27 1.27)
				)
				(justify mirror)
			)
		)
		(property "Value" "47KR2F-GP"
			(at -0.064008 -3.993896 180)
			(unlocked yes)
			(layer "B.Fab")
			(hide yes)
			(effects
				(font
					(size 1.016 1.016)
					(thickness 0.1524)
				)
				(justify mirror)
			)
		)
		(property "Device Type" "R402H16"
			(at -0.064008 -5.517896 180)
			(unlocked yes)
			(layer "B.Fab")
			(hide yes)
			(effects
				(font
					(size 1.016 1.016)
					(thickness 0.1524)
				)
				(justify mirror)
			)
		)
		(duplicate_pad_numbers_are_jumpers no)
		(fp_line
			(start 0.508 -0.9398)
			(end 0.508 0.9398)
			(stroke
				(width 0.1524)
				(type default)
			)
			(layer "B.SilkS")
		)
		(fp_line
			(start -0.508 -0.9398)
			(end 0.508 -0.9398)
			(stroke
				(width 0.1524)
				(type default)
			)
			(layer "B.SilkS")
		)
		(fp_rect
			(start 0.508 0.9398)
			(end -0.508 -0.9398)
			(stroke
				(width 0)
				(type default)
			)
			(fill no)
			(layer "B.CrtYd")
		)
		(fp_rect
			(start 0.508 0.9398)
			(end -0.508 -0.9398)
			(stroke
				(width 0)
				(type default)
			)
			(fill no)
			(layer "B.Fab")
		)
		(pad "1" smd custom
			(at 0 -0.4445)
			(size 0.1397 0.1397)
			(layers "B.Cu" "B.Mask" "B.Paste")
			(net "Z50_SSD_B1_SMB_CLK")
			(options
				(clearance outline)
				(anchor circle)
			)
			(primitives
				(gr_poly
					(pts
						(arc
							(start -0.1778 0.2794)
							(mid -0.249642 0.249642)
							(end -0.2794 0.1778)
						)
						(arc
							(start -0.2794 -0.1778)
							(mid -0.249642 -0.249642)
							(end -0.1778 -0.2794)
						)
						(arc
							(start 0.1778 -0.2794)
							(mid 0.249642 -0.249642)
							(end 0.2794 -0.1778)
						)
						(arc
							(start 0.2794 0.1778)
							(mid 0.249642 0.249642)
							(end 0.1778 0.2794)
						)
					)
					(width 0)
					(fill yes)
				)
			)
		)
		(pad "2" smd custom
			(at 0 0.4445)
			(size 0.1397 0.1397)
			(layers "B.Cu" "B.Mask" "B.Paste")
			(net "P1V8_PWR")
			(options
				(clearance outline)
				(anchor circle)
			)
			(primitives
				(gr_poly
					(pts
						(arc
							(start -0.1778 0.2794)
							(mid -0.249642 0.249642)
							(end -0.2794 0.1778)
						)
						(arc
							(start -0.2794 -0.1778)
							(mid -0.249642 -0.249642)
							(end -0.1778 -0.2794)
						)
						(arc
							(start 0.1778 -0.2794)
							(mid 0.249642 -0.249642)
							(end 0.2794 -0.1778)
						)
						(arc
							(start 0.2794 0.1778)
							(mid 0.249642 0.249642)
							(end 0.1778 0.2794)
						)
					)
					(width 0)
					(fill yes)
				)
			)
		)
	)
	(footprint ""
		(layer "B.Cu")
		(at 25.019 -80.518 -90)
		(property "Reference" "R27"
			(at 0 0 90)
			(layer "B.SilkS")
			(hide yes)
			(effects
				(font
					(size 1.27 1.27)
				)
				(justify mirror)
			)
		)
		(property "Value" "4K7R2F-GP"
			(at -0.064008 -3.993896 270)
			(unlocked yes)
			(layer "B.Fab")
			(hide yes)
			(effects
				(font
					(size 1.016 1.016)
					(thickness 0.1524)
				)
				(justify mirror)
			)
		)
		(property "Device Type" "R402H16"
			(at -0.064008 -5.517896 270)
			(unlocked yes)
			(layer "B.Fab")
			(hide yes)
			(effects
				(font
					(size 1.016 1.016)
					(thickness 0.1524)
				)
				(justify mirror)
			)
		)
		(duplicate_pad_numbers_are_jumpers no)
		(fp_line
			(start -0.508 -0.9398)
			(end 0.508 -0.9398)
			(stroke
				(width 0.1524)
				(type default)
			)
			(layer "B.SilkS")
		)
		(fp_line
			(start 0.508 -0.9398)
			(end 0.508 0.9398)
			(stroke
				(width 0.1524)
				(type default)
			)
			(layer "B.SilkS")
		)
		(fp_rect
			(start 0.508 0.9398)
			(end -0.508 -0.9398)
			(stroke
				(width 0)
				(type default)
			)
			(fill no)
			(layer "B.CrtYd")
		)
		(fp_rect
			(start 0.508 0.9398)
			(end -0.508 -0.9398)
			(stroke
				(width 0)
				(type default)
			)
			(fill no)
			(layer "B.Fab")
		)
		(pad "1" smd custom
			(at 0 -0.4445 90)
			(size 0.1397 0.1397)
			(layers "B.Cu" "B.Mask" "B.Paste")
			(net "Z50_SMB_SWITCH_ADDRESS_A0")
			(options
				(clearance outline)
				(anchor circle)
			)
			(primitives
				(gr_poly
					(pts
						(arc
							(start -0.1778 0.2794)
							(mid -0.249642 0.249642)
							(end -0.2794 0.1778)
						)
						(arc
							(start -0.2794 -0.1778)
							(mid -0.249642 -0.249642)
							(end -0.1778 -0.2794)
						)
						(arc
							(start 0.1778 -0.2794)
							(mid 0.249642 -0.249642)
							(end 0.2794 -0.1778)
						)
						(arc
							(start 0.2794 0.1778)
							(mid 0.249642 0.249642)
							(end 0.1778 0.2794)
						)
					)
					(width 0)
					(fill yes)
				)
			)
		)
		(pad "2" smd custom
			(at 0 0.4445 90)
			(size 0.1397 0.1397)
			(layers "B.Cu" "B.Mask" "B.Paste")
			(net "GND")
			(options
				(clearance outline)
				(anchor circle)
			)
			(primitives
				(gr_poly
					(pts
						(arc
							(start -0.1778 0.2794)
							(mid -0.249642 0.249642)
							(end -0.2794 0.1778)
						)
						(arc
							(start -0.2794 -0.1778)
							(mid -0.249642 -0.249642)
							(end -0.1778 -0.2794)
						)
						(arc
							(start 0.1778 -0.2794)
							(mid 0.249642 -0.249642)
							(end 0.2794 -0.1778)
						)
						(arc
							(start 0.2794 0.1778)
							(mid 0.249642 0.249642)
							(end 0.1778 0.2794)
						)
					)
					(width 0)
					(fill yes)
				)
			)
		)
	)
	(gr_line
		(start 69.3674 -53.584094)
		(end 69.614034 -53.33746)
		(stroke
			(width 0.068326)
			(type default)
		)
		(layer "F.Cu")
	)
	(gr_line
		(start 69.3674 -52.466494)
		(end 69.664326 -52.76342)
		(stroke
			(width 0.068326)
			(type default)
		)
		(layer "F.Cu")
	)
	(gr_line
		(start 69.3674 -25.983946)
		(end 69.614034 -25.737312)
		(stroke
			(width 0.068326)
			(type default)
		)
		(layer "F.Cu")
	)
	(gr_line
		(start 69.3674 -24.866346)
		(end 69.664326 -25.163272)
		(stroke
			(width 0.068326)
			(type default)
		)
		(layer "F.Cu")
	)
	(gr_arc
		(start 69.664326 -52.76342)
		(mid 69.807773 -52.859307)
		(end 69.977 -52.89296)
		(stroke
			(width 0.068326)
			(type default)
		)
		(layer "F.Cu")
	)
	(gr_arc
		(start 69.664326 -25.163272)
		(mid 69.807771 -25.259169)
		(end 69.977 -25.292812)
		(stroke
			(width 0.068326)
			(type default)
		)
		(layer "F.Cu")
	)
	(gr_line
		(start 69.8754 -56.584088)
		(end 70.122034 -56.337454)
		(stroke
			(width 0.068326)
			(type default)
		)
		(layer "F.Cu")
	)
	(gr_line
		(start 69.8754 -55.466488)
		(end 70.172326 -55.763414)
		(stroke
			(width 0.068326)
			(type default)
		)
		(layer "F.Cu")
	)
	(gr_line
		(start 69.8754 -28.98394)
		(end 70.122034 -28.737306)
		(stroke
			(width 0.068326)
			(type default)
		)
		(layer "F.Cu")
	)
	(gr_line
		(start 69.8754 -27.86634)
		(end 70.172326 -28.163266)
		(stroke
			(width 0.068326)
			(type default)
		)
		(layer "F.Cu")
	)
	(gr_arc
		(start 69.977 -53.187092)
		(mid 69.780556 -53.226167)
		(end 69.614034 -53.33746)
		(stroke
			(width 0.068326)
			(type default)
		)
		(layer "F.Cu")
	)
	(gr_arc
		(start 69.977 -25.586944)
		(mid 69.780556 -25.626019)
		(end 69.614034 -25.737312)
		(stroke
			(width 0.068326)
			(type default)
		)
		(layer "F.Cu")
	)
	(gr_arc
		(start 70.172326 -55.763414)
		(mid 70.315773 -55.859302)
		(end 70.485 -55.892954)
		(stroke
			(width 0.068326)
			(type default)
		)
		(layer "F.Cu")
	)
	(gr_arc
		(start 70.172326 -28.163266)
		(mid 70.31577 -28.259164)
		(end 70.485 -28.292806)
		(stroke
			(width 0.068326)
			(type default)
		)
		(layer "F.Cu")
	)
	(gr_arc
		(start 70.485 -56.187086)
		(mid 70.288556 -56.226161)
		(end 70.122034 -56.337454)
		(stroke
			(width 0.068326)
			(type default)
		)
		(layer "F.Cu")
	)
	(gr_arc
		(start 70.485 -28.586938)
		(mid 70.288556 -28.626013)
		(end 70.122034 -28.737306)
		(stroke
			(width 0.068326)
			(type default)
		)
		(layer "F.Cu")
	)
	(gr_arc
		(start 71.497952 -55.892954)
		(mid 71.546467 -55.883313)
		(end 71.587614 -55.85587)
		(stroke
			(width 0.068326)
			(type default)
		)
		(layer "F.Cu")
	)
	(gr_arc
		(start 71.497952 -28.292806)
		(mid 71.546465 -28.283162)
		(end 71.587614 -28.255722)
		(stroke
			(width 0.068326)
			(type default)
		)
		(layer "F.Cu")
	)
	(gr_arc
		(start 71.529956 -52.89296)
		(mid 71.578465 -52.883312)
		(end 71.619618 -52.855876)
		(stroke
			(width 0.068326)
			(type default)
		)
		(layer "F.Cu")
	)
	(gr_arc
		(start 71.529956 -25.292812)
		(mid 71.578468 -25.283167)
		(end 71.619618 -25.255728)
		(stroke
			(width 0.068326)
			(type default)
		)
		(layer "F.Cu")
	)
	(gr_line
		(start 71.587614 -55.85587)
		(end 71.616316 -55.827168)
		(stroke
			(width 0.068326)
			(type default)
		)
		(layer "F.Cu")
	)
	(gr_line
		(start 71.587614 -28.255722)
		(end 71.616316 -28.22702)
		(stroke
			(width 0.068326)
			(type default)
		)
		(layer "F.Cu")
	)
	(gr_arc
		(start 71.598282 -53.224176)
		(mid 71.557131 -53.196743)
		(end 71.50862 -53.187092)
		(stroke
			(width 0.068326)
			(type default)
		)
		(layer "F.Cu")
	)
	(gr_line
		(start 71.598282 -53.224176)
		(end 71.626984 -53.252878)
		(stroke
			(width 0.068326)
			(type default)
		)
		(layer "F.Cu")
	)
	(gr_arc
		(start 71.598282 -25.624028)
		(mid 71.557131 -25.596595)
		(end 71.50862 -25.586944)
		(stroke
			(width 0.068326)
			(type default)
		)
		(layer "F.Cu")
	)
	(gr_line
		(start 71.598282 -25.624028)
		(end 71.626984 -25.65273)
		(stroke
			(width 0.068326)
			(type default)
		)
		(layer "F.Cu")
	)
	(gr_line
		(start 71.619618 -52.855876)
		(end 71.64832 -52.827174)
		(stroke
			(width 0.068326)
			(type default)
		)
		(layer "F.Cu")
	)
	(gr_line
		(start 71.619618 -25.255728)
		(end 71.64832 -25.227026)
		(stroke
			(width 0.068326)
			(type default)
		)
		(layer "F.Cu")
	)
	(gr_arc
		(start 71.626476 -56.22417)
		(mid 71.585325 -56.196737)
		(end 71.536814 -56.187086)
		(stroke
			(width 0.068326)
			(type default)
		)
		(layer "F.Cu")
	)
	(gr_line
		(start 71.626476 -56.22417)
		(end 71.655178 -56.252872)
		(stroke
			(width 0.068326)
			(type default)
		)
		(layer "F.Cu")
	)
	(gr_arc
		(start 71.626476 -28.624022)
		(mid 71.585325 -28.596589)
		(end 71.536814 -28.586938)
		(stroke
			(width 0.068326)
			(type default)
		)
		(layer "F.Cu")
	)
	(gr_line
		(start 71.626476 -28.624022)
		(end 71.655178 -28.652724)
		(stroke
			(width 0.068326)
			(type default)
		)
		(layer "F.Cu")
	)
	(gr_arc
		(start 71.626984 -53.252878)
		(mid 71.66813 -53.280326)
		(end 71.716646 -53.289962)
		(stroke
			(width 0.068326)
			(type default)
		)
		(layer "F.Cu")
	)
	(gr_arc
		(start 71.626984 -25.65273)
		(mid 71.668133 -25.680167)
		(end 71.716646 -25.689814)
		(stroke
			(width 0.068326)
			(type default)
		)
		(layer "F.Cu")
	)
	(gr_arc
		(start 71.655178 -56.252872)
		(mid 71.696324 -56.280323)
		(end 71.74484 -56.289956)
		(stroke
			(width 0.068326)
			(type default)
		)
		(layer "F.Cu")
	)
	(gr_arc
		(start 71.655178 -28.652724)
		(mid 71.696327 -28.680164)
		(end 71.74484 -28.689808)
		(stroke
			(width 0.068326)
			(type default)
		)
		(layer "F.Cu")
	)
	(gr_arc
		(start 71.705978 -55.790084)
		(mid 71.65746 -55.799717)
		(end 71.616316 -55.827168)
		(stroke
			(width 0.068326)
			(type default)
		)
		(layer "F.Cu")
	)
	(gr_line
		(start 71.705978 -55.790084)
		(end 72.725026 -55.790084)
		(stroke
			(width 0.068326)
			(type default)
		)
		(layer "F.Cu")
	)
	(gr_arc
		(start 71.705978 -28.189936)
		(mid 71.65746 -28.199569)
		(end 71.616316 -28.22702)
		(stroke
			(width 0.068326)
			(type default)
		)
		(layer "F.Cu")
	)
	(gr_line
		(start 71.705978 -28.189936)
		(end 72.725026 -28.189936)
		(stroke
			(width 0.068326)
			(type default)
		)
		(layer "F.Cu")
	)
	(gr_line
		(start 71.716646 -53.289962)
		(end 72.725026 -53.289962)
		(stroke
			(width 0.068326)
			(type default)
		)
		(layer "F.Cu")
	)
	(gr_line
		(start 71.716646 -25.689814)
		(end 72.725026 -25.689814)
		(stroke
			(width 0.068326)
			(type default)
		)
		(layer "F.Cu")
	)
	(gr_arc
		(start 71.737982 -52.79009)
		(mid 71.689464 -52.799723)
		(end 71.64832 -52.827174)
		(stroke
			(width 0.068326)
			(type default)
		)
		(layer "F.Cu")
	)
	(gr_line
		(start 71.737982 -52.79009)
		(end 72.725026 -52.79009)
		(stroke
			(width 0.068326)
			(type default)
		)
		(layer "F.Cu")
	)
	(gr_arc
		(start 71.737982 -25.189942)
		(mid 71.689464 -25.199575)
		(end 71.64832 -25.227026)
		(stroke
			(width 0.068326)
			(type default)
		)
		(layer "F.Cu")
	)
	(gr_line
		(start 71.737982 -25.189942)
		(end 72.725026 -25.189942)
		(stroke
			(width 0.068326)
			(type default)
		)
		(layer "F.Cu")
	)
	(gr_line
		(start 71.74484 -56.289956)
		(end 72.725026 -56.289956)
		(stroke
			(width 0.068326)
			(type default)
		)
		(layer "F.Cu")
	)
	(gr_line
		(start 71.74484 -28.689808)
		(end 72.725026 -28.689808)
		(stroke
			(width 0.068326)
			(type default)
		)
		(layer "F.Cu")
	)
	(gr_line
		(start 72.725026 -54.790086)
		(end 73.533 -54.790086)
		(stroke
			(width 0.068326)
			(type default)
		)
		(layer "F.Cu")
	)
	(gr_line
		(start 72.725026 -54.28996)
		(end 73.509378 -54.28996)
		(stroke
			(width 0.068326)
			(type default)
		)
		(layer "F.Cu")
	)
	(gr_line
		(start 72.725026 -51.790092)
		(end 73.533 -51.790092)
		(stroke
			(width 0.068326)
			(type default)
		)
		(layer "F.Cu")
	)
	(gr_line
		(start 72.725026 -51.289966)
		(end 73.509378 -51.289966)
		(stroke
			(width 0.068326)
			(type default)
		)
		(layer "F.Cu")
	)
	(gr_line
		(start 72.725026 -50.289968)
		(end 73.533 -50.289968)
		(stroke
			(width 0.068326)
			(type default)
		)
		(layer "F.Cu")
	)
	(gr_line
		(start 72.725026 -49.790096)
		(end 73.583546 -49.790096)
		(stroke
			(width 0.068326)
			(type default)
		)
		(layer "F.Cu")
	)
	(gr_line
		(start 72.725026 -27.189938)
		(end 73.509632 -27.189938)
		(stroke
			(width 0.068326)
			(type default)
		)
		(layer "F.Cu")
	)
	(gr_line
		(start 72.725026 -26.689812)
		(end 73.509378 -26.689812)
		(stroke
			(width 0.068326)
			(type default)
		)
		(layer "F.Cu")
	)
	(gr_line
		(start 72.725026 -24.189944)
		(end 73.533 -24.189944)
		(stroke
			(width 0.068326)
			(type default)
		)
		(layer "F.Cu")
	)
	(gr_line
		(start 72.725026 -23.689818)
		(end 73.509378 -23.689818)
		(stroke
			(width 0.068326)
			(type default)
		)
		(layer "F.Cu")
	)
	(gr_line
		(start 72.725026 -22.68982)
		(end 73.538842 -22.68982)
		(stroke
			(width 0.068326)
			(type default)
		)
		(layer "F.Cu")
	)
	(gr_line
		(start 72.725026 -22.189948)
		(end 73.53173 -22.189948)
		(stroke
			(width 0.068326)
			(type default)
		)
		(layer "F.Cu")
	)
	(gr_arc
		(start 73.509632 -27.189938)
		(mid 73.576987 -27.17653)
		(end 73.634092 -27.138376)
		(stroke
			(width 0.068326)
			(type default)
		)
		(layer "F.Cu")
	)
	(gr_arc
		(start 73.533 -54.790086)
		(mid 73.585555 -54.779604)
		(end 73.630028 -54.7497)
		(stroke
			(width 0.068326)
			(type default)
		)
		(layer "F.Cu")
	)
	(gr_arc
		(start 73.533 -51.790092)
		(mid 73.585555 -51.77961)
		(end 73.630028 -51.749706)
		(stroke
			(width 0.068326)
			(type default)
		)
		(layer "F.Cu")
	)
	(gr_arc
		(start 73.533 -24.189944)
		(mid 73.585558 -24.179465)
		(end 73.630028 -24.149558)
		(stroke
			(width 0.068326)
			(type default)
		)
		(layer "F.Cu")
	)
	(gr_arc
		(start 73.538842 -22.68982)
		(mid 73.58736 -22.680187)
		(end 73.628504 -22.652736)
		(stroke
			(width 0.068326)
			(type default)
		)
		(layer "F.Cu")
	)
	(gr_arc
		(start 73.583546 -49.790096)
		(mid 73.803604 -49.746301)
		(end 73.9902 -49.621694)
		(stroke
			(width 0.068326)
			(type default)
		)
		(layer "F.Cu")
	)
	(gr_arc
		(start 73.621392 -22.227032)
		(mid 73.580245 -22.19959)
		(end 73.53173 -22.189948)
		(stroke
			(width 0.068326)
			(type default)
		)
		(layer "F.Cu")
	)
	(gr_line
		(start 73.621392 -22.227032)
		(end 73.650094 -22.255734)
		(stroke
			(width 0.068326)
			(type default)
		)
		(layer "F.Cu")
	)
	(gr_line
		(start 73.628504 -22.652736)
		(end 73.657206 -22.624034)
		(stroke
			(width 0.068326)
			(type default)
		)
		(layer "F.Cu")
	)
	(gr_line
		(start 73.630028 -54.7497)
		(end 73.641204 -54.738524)
		(stroke
			(width 0.068326)
			(type default)
		)
		(layer "F.Cu")
	)
	(gr_line
		(start 73.630028 -51.749706)
		(end 73.641204 -51.73853)
		(stroke
			(width 0.068326)
			(type default)
		)
		(layer "F.Cu")
	)
	(gr_line
		(start 73.630028 -24.149558)
		(end 73.641204 -24.138382)
		(stroke
			(width 0.068326)
			(type default)
		)
		(layer "F.Cu")
	)
	(gr_arc
		(start 73.633838 -54.341522)
		(mid 73.576735 -54.303367)
		(end 73.509378 -54.28996)
		(stroke
			(width 0.068326)
			(type default)
		)
		(layer "F.Cu")
	)
	(gr_arc
		(start 73.633838 -54.341522)
		(mid 73.690938 -54.379686)
		(end 73.758298 -54.393084)
		(stroke
			(width 0.068326)
			(type default)
		)
		(layer "F.Cu")
	)
	(gr_arc
		(start 73.633838 -51.341528)
		(mid 73.576735 -51.303373)
		(end 73.509378 -51.289966)
		(stroke
			(width 0.068326)
			(type default)
		)
		(layer "F.Cu")
	)
	(gr_arc
		(start 73.633838 -51.341528)
		(mid 73.690939 -51.37969)
		(end 73.758298 -51.39309)
		(stroke
			(width 0.068326)
			(type default)
		)
		(layer "F.Cu")
	)
	(gr_arc
		(start 73.633838 -26.741374)
		(mid 73.576735 -26.703219)
		(end 73.509378 -26.689812)
		(stroke
			(width 0.068326)
			(type default)
		)
		(layer "F.Cu")
	)
	(gr_arc
		(start 73.633838 -26.741374)
		(mid 73.690936 -26.779548)
		(end 73.758298 -26.792936)
		(stroke
			(width 0.068326)
			(type default)
		)
		(layer "F.Cu")
	)
	(gr_arc
		(start 73.633838 -23.74138)
		(mid 73.576735 -23.703225)
		(end 73.509378 -23.689818)
		(stroke
			(width 0.068326)
			(type default)
		)
		(layer "F.Cu")
	)
	(gr_arc
		(start 73.633838 -23.74138)
		(mid 73.690936 -23.779552)
		(end 73.758298 -23.792942)
		(stroke
			(width 0.068326)
			(type default)
		)
		(layer "F.Cu")
	)
	(gr_arc
		(start 73.650094 -22.255734)
		(mid 73.691245 -22.283167)
		(end 73.739756 -22.292818)
		(stroke
			(width 0.068326)
			(type default)
		)
		(layer "F.Cu")
	)
	(gr_arc
		(start 73.746868 -22.58695)
		(mid 73.698349 -22.596585)
		(end 73.657206 -22.624034)
		(stroke
			(width 0.068326)
			(type default)
		)
		(layer "F.Cu")
	)
	(gr_arc
		(start 73.758044 -27.087068)
		(mid 73.690975 -27.100409)
		(end 73.634092 -27.138376)
		(stroke
			(width 0.068326)
			(type default)
		)
		(layer "F.Cu")
	)
	(gr_arc
		(start 73.76541 -54.687216)
		(mid 73.698229 -54.700561)
		(end 73.641204 -54.738524)
		(stroke
			(width 0.068326)
			(type default)
		)
		(layer "F.Cu")
	)
	(gr_arc
		(start 73.76541 -51.687222)
		(mid 73.698229 -51.700567)
		(end 73.641204 -51.73853)
		(stroke
			(width 0.068326)
			(type default)
		)
		(layer "F.Cu")
	)
	(gr_arc
		(start 73.76541 -24.087074)
		(mid 73.698229 -24.100419)
		(end 73.641204 -24.138382)
		(stroke
			(width 0.068326)
			(type default)
		)
		(layer "F.Cu")
	)
	(gr_arc
		(start 73.9902 -50.434494)
		(mid 73.772747 -50.326973)
		(end 73.533 -50.289968)
		(stroke
			(width 0.068326)
			(type default)
		)
		(layer "F.Cu")
	)
	(gr_arc
		(start 74.0156 -22.292818)
		(mid 74.492493 -22.223566)
		(end 74.93 -22.021546)
		(stroke
			(width 0.068326)
			(type default)
		)
		(layer "F.Cu")
	)
	(gr_arc
		(start 74.93 -22.834346)
		(mid 74.397735 -22.649568)
		(end 73.8378 -22.58695)
		(stroke
			(width 0.068326)
			(type default)
		)
		(layer "F.Cu")
	)
	(gr_arc
		(start 82.001106 -40.127936)
		(mid 82.331717 -40.06223)
		(end 82.611976 -39.874952)
		(stroke
			(width 0.068326)
			(type default)
		)
		(layer "F.Cu")
	)
	(gr_arc
		(start 82.0166 -17.72793)
		(mid 82.332905 -17.665037)
		(end 82.601054 -17.485868)
		(stroke
			(width 0.068326)
			(type default)
		)
		(layer "F.Cu")
	)
	(gr_arc
		(start 82.169 -27.328114)
		(mid 82.344551 -27.293201)
		(end 82.493358 -27.193748)
		(stroke
			(width 0.068326)
			(type default)
		)
		(layer "F.Cu")
	)
	(gr_arc
		(start 82.169 -22.528022)
		(mid 82.344552 -22.49311)
		(end 82.493358 -22.393656)
		(stroke
			(width 0.068326)
			(type default)
		)
		(layer "F.Cu")
	)
	(gr_line
		(start 82.493358 -27.193748)
		(end 82.611976 -27.07513)
		(stroke
			(width 0.068326)
			(type default)
		)
		(layer "F.Cu")
	)
	(gr_arc
		(start 82.493358 -22.95652)
		(mid 82.344541 -22.857084)
		(end 82.169 -22.822154)
		(stroke
			(width 0.068326)
			(type default)
		)
		(layer "F.Cu")
	)
	(gr_line
		(start 82.493358 -22.95652)
		(end 82.611976 -23.075138)
		(stroke
			(width 0.068326)
			(type default)
		)
		(layer "F.Cu")
	)
	(gr_line
		(start 82.493358 -22.393656)
		(end 82.611976 -22.275038)
		(stroke
			(width 0.068326)
			(type default)
		)
		(layer "F.Cu")
	)
	(gr_arc
		(start 82.493612 -27.756866)
		(mid 82.344694 -27.657269)
		(end 82.169 -27.622246)
		(stroke
			(width 0.068326)
			(type default)
		)
		(layer "F.Cu")
	)
	(gr_line
		(start 82.493612 -27.756866)
		(end 82.611976 -27.874976)
		(stroke
			(width 0.068326)
			(type default)
		)
		(layer "F.Cu")
	)
	(gr_arc
		(start 82.601054 -18.264124)
		(mid 82.332904 -18.084952)
		(end 82.0166 -18.022062)
		(stroke
			(width 0.068326)
			(type default)
		)
		(layer "F.Cu")
	)
	(gr_line
		(start 82.601054 -18.264124)
		(end 82.611976 -18.275046)
		(stroke
			(width 0.068326)
			(type default)
		)
		(layer "F.Cu")
	)
	(gr_line
		(start 82.601054 -17.485868)
		(end 82.611976 -17.474946)
		(stroke
			(width 0.068326)
			(type default)
		)
		(layer "F.Cu")
	)
	(gr_arc
		(start 82.611976 -40.675052)
		(mid 82.331706 -40.487782)
		(end 82.001106 -40.422068)
		(stroke
			(width 0.068326)
			(type default)
		)
		(layer "F.Cu")
	)
	(gr_arc
		(start 76.9112 -33.691322)
		(mid 77.064237 -33.985292)
		(end 77.373988 -34.103056)
		(stroke
			(width 0.068326)
			(type default)
		)
		(layer "B.Cu")
	)
	(gr_arc
		(start 77.373988 -34.397188)
		(mid 77.064233 -34.514969)
		(end 76.9112 -34.808922)
		(stroke
			(width 0.068326)
			(type default)
		)
		(layer "B.Cu")
	)
	(gr_arc
		(start 77.376528 -34.103056)
		(mid 77.541771 -34.070187)
		(end 77.681836 -33.976564)
		(stroke
			(width 0.068326)
			(type default)
		)
		(layer "B.Cu")
	)
	(gr_arc
		(start 77.70368 -34.52368)
		(mid 77.563612 -34.430053)
		(end 77.398372 -34.397188)
		(stroke
			(width 0.068326)
			(type default)
		)
		(layer "B.Cu")
	)
	(gr_arc
		(start 77.70368 -34.52368)
		(mid 77.843757 -34.617276)
		(end 78.008988 -34.650172)
		(stroke
			(width 0.068326)
			(type default)
		)
		(layer "B.Cu")
	)
	(gr_arc
		(start 77.987144 -33.850072)
		(mid 77.821927 -33.882984)
		(end 77.681836 -33.976564)
		(stroke
			(width 0.068326)
			(type default)
		)
		(layer "B.Cu")
	)
	(gr_line
		(start 77.987144 -33.850072)
		(end 78.769972 -33.850072)
		(stroke
			(width 0.068326)
			(type default)
		)
		(layer "B.Cu")
	)
	(gr_line
		(start 78.008988 -34.650172)
		(end 78.769972 -34.650172)
		(stroke
			(width 0.068326)
			(type default)
		)
		(layer "B.Cu")
	)
	(gr_line
		(start 81.380076 -43.075098)
		(end 82.611976 -43.075098)
		(stroke
			(width 0.068326)
			(type default)
		)
		(layer "B.Cu")
	)
	(gr_line
		(start 81.380076 -42.274998)
		(end 82.611976 -42.274998)
		(stroke
			(width 0.068326)
			(type default)
		)
		(layer "B.Cu")
	)
	(gr_line
		(start 81.380076 -40.675052)
		(end 82.611976 -40.675052)
		(stroke
			(width 0.068326)
			(type default)
		)
		(layer "B.Cu")
	)
	(gr_line
		(start 81.380076 -39.874952)
		(end 82.611976 -39.874952)
		(stroke
			(width 0.068326)
			(type default)
		)
		(layer "B.Cu")
	)
	(gr_line
		(start 81.380076 -38.275006)
		(end 82.611976 -38.275006)
		(stroke
			(width 0.068326)
			(type default)
		)
		(layer "B.Cu")
	)
	(gr_line
		(start 81.380076 -37.47516)
		(end 82.611976 -37.47516)
		(stroke
			(width 0.068326)
			(type default)
		)
		(layer "B.Cu")
	)
	(gr_line
		(start 81.380076 -27.874976)
		(end 82.611976 -27.874976)
		(stroke
			(width 0.068326)
			(type default)
		)
		(layer "B.Cu")
	)
	(gr_line
		(start 81.380076 -27.07513)
		(end 82.611976 -27.07513)
		(stroke
			(width 0.068326)
			(type default)
		)
		(layer "B.Cu")
	)
	(gr_line
		(start 81.380076 -25.475184)
		(end 82.611976 -25.475184)
		(stroke
			(width 0.068326)
			(type default)
		)
		(layer "B.Cu")
	)
	(gr_line
		(start 81.380076 -24.675084)
		(end 82.611976 -24.675084)
		(stroke
			(width 0.068326)
			(type default)
		)
		(layer "B.Cu")
	)
	(gr_line
		(start 81.380076 -23.075138)
		(end 82.611976 -23.075138)
		(stroke
			(width 0.068326)
			(type default)
		)
		(layer "B.Cu")
	)
	(gr_line
		(start 81.380076 -22.275038)
		(end 82.611976 -22.275038)
		(stroke
			(width 0.068326)
			(type default)
		)
		(layer "B.Cu")
	)
	(gr_line
		(start 81.380076 -20.675092)
		(end 82.611976 -20.675092)
		(stroke
			(width 0.068326)
			(type default)
		)
		(layer "B.Cu")
	)
	(gr_line
		(start 81.380076 -19.874992)
		(end 82.611976 -19.874992)
		(stroke
			(width 0.068326)
			(type default)
		)
		(layer "B.Cu")
	)
	(gr_line
		(start 81.380076 -18.275046)
		(end 82.611976 -18.275046)
		(stroke
			(width 0.068326)
			(type default)
		)
		(layer "B.Cu")
	)
	(gr_line
		(start 81.380076 -17.474946)
		(end 82.611976 -17.474946)
		(stroke
			(width 0.068326)
			(type default)
		)
		(layer "B.Cu")
	)
	(gr_line
		(start 81.380076 -15.875)
		(end 82.611976 -15.875)
		(stroke
			(width 0.068326)
			(type default)
		)
		(layer "B.Cu")
	)
	(gr_line
		(start 81.380076 -15.075154)
		(end 82.611976 -15.075154)
		(stroke
			(width 0.068326)
			(type default)
		)
		(layer "B.Cu")
	)
	(gr_arc
		(start 68.75526 -53.593746)
		(mid 69.367273 -54.20614)
		(end 69.97954 -53.594)
		(stroke
			(width 0.2)
			(type default)
		)
		(layer "In1.Cu")
	)
	(gr_arc
		(start 68.75526 -53.584094)
		(mid 69.3674 -54.196234)
		(end 69.97954 -53.584094)
		(stroke
			(width 0.2)
			(type default)
		)
		(layer "In1.Cu")
	)
	(gr_line
		(start 68.75526 -52.4764)
		(end 68.75526 -53.593746)
		(stroke
			(width 0.2)
			(type default)
		)
		(layer "In1.Cu")
	)
	(gr_line
		(start 68.75526 -52.466494)
		(end 68.75526 -53.584094)
		(stroke
			(width 0.2)
			(type default)
		)
		(layer "In1.Cu")
	)
	(gr_arc
		(start 68.75526 -25.994106)
		(mid 69.3674 -26.606246)
		(end 69.97954 -25.994106)
		(stroke
			(width 0.2)
			(type default)
		)
		(layer "In1.Cu")
	)
	(gr_arc
		(start 68.75526 -25.983946)
		(mid 69.3674 -26.596086)
		(end 69.97954 -25.983946)
		(stroke
			(width 0.2)
			(type default)
		)
		(layer "In1.Cu")
	)
	(gr_line
		(start 68.75526 -24.876506)
		(end 68.75526 -25.994106)
		(stroke
			(width 0.2)
			(type default)
		)
		(layer "In1.Cu")
	)
	(gr_line
		(start 68.75526 -24.866346)
		(end 68.75526 -25.983946)
		(stroke
			(width 0.2)
			(type default)
		)
		(layer "In1.Cu")
	)
	(gr_arc
		(start 69.26326 -56.59374)
		(mid 69.875273 -57.206134)
		(end 70.48754 -56.593994)
		(stroke
			(width 0.2)
			(type default)
		)
		(layer "In1.Cu")
	)
	(gr_arc
		(start 69.26326 -56.584088)
		(mid 69.8754 -57.196228)
		(end 70.48754 -56.584088)
		(stroke
			(width 0.2)
			(type default)
		)
		(layer "In1.Cu")
	)
	(gr_line
		(start 69.26326 -55.476394)
		(end 69.26326 -56.59374)
		(stroke
			(width 0.2)
			(type default)
		)
		(layer "In1.Cu")
	)
	(gr_line
		(start 69.26326 -55.466488)
		(end 69.26326 -56.584088)
		(stroke
			(width 0.2)
			(type default)
		)
		(layer "In1.Cu")
	)
	(gr_arc
		(start 69.26326 -28.9941)
		(mid 69.8754 -29.60624)
		(end 70.48754 -28.9941)
		(stroke
			(width 0.2)
			(type default)
		)
		(layer "In1.Cu")
	)
	(gr_arc
		(start 69.26326 -28.983686)
		(mid 69.875273 -29.59608)
		(end 70.48754 -28.98394)
		(stroke
			(width 0.2)
			(type default)
		)
		(layer "In1.Cu")
	)
	(gr_line
		(start 69.26326 -27.8765)
		(end 69.26326 -28.9941)
		(stroke
			(width 0.2)
			(type default)
		)
		(layer "In1.Cu")
	)
	(gr_line
		(start 69.26326 -27.86634)
		(end 69.26326 -28.983686)
		(stroke
			(width 0.2)
			(type default)
		)
		(layer "In1.Cu")
	)
	(gr_line
		(start 69.97954 -53.594)
		(end 69.97954 -52.4764)
		(stroke
			(width 0.2)
			(type default)
		)
		(layer "In1.Cu")
	)
	(gr_line
		(start 69.97954 -53.584094)
		(end 69.97954 -52.466748)
		(stroke
			(width 0.2)
			(type default)
		)
		(layer "In1.Cu")
	)
	(gr_arc
		(start 69.97954 -52.4764)
		(mid 69.3674 -51.86426)
		(end 68.75526 -52.4764)
		(stroke
			(width 0.2)
			(type default)
		)
		(layer "In1.Cu")
	)
	(gr_arc
		(start 69.97954 -52.466748)
		(mid 69.367527 -51.854354)
		(end 68.75526 -52.466494)
		(stroke
			(width 0.2)
			(type default)
		)
		(layer "In1.Cu")
	)
	(gr_line
		(start 69.97954 -25.994106)
		(end 69.97954 -24.87676)
		(stroke
			(width 0.2)
			(type default)
		)
		(layer "In1.Cu")
	)
	(gr_line
		(start 69.97954 -25.983946)
		(end 69.97954 -24.8666)
		(stroke
			(width 0.2)
			(type default)
		)
		(layer "In1.Cu")
	)
	(gr_arc
		(start 69.97954 -24.87676)
		(mid 69.367527 -24.264366)
		(end 68.75526 -24.876506)
		(stroke
			(width 0.2)
			(type default)
		)
		(layer "In1.Cu")
	)
	(gr_arc
		(start 69.97954 -24.8666)
		(mid 69.367527 -24.254206)
		(end 68.75526 -24.866346)
		(stroke
			(width 0.2)
			(type default)
		)
		(layer "In1.Cu")
	)
	(gr_line
		(start 70.48754 -56.593994)
		(end 70.48754 -55.476394)
		(stroke
			(width 0.2)
			(type default)
		)
		(layer "In1.Cu")
	)
	(gr_line
		(start 70.48754 -56.584088)
		(end 70.48754 -55.466742)
		(stroke
			(width 0.2)
			(type default)
		)
		(layer "In1.Cu")
	)
	(gr_arc
		(start 70.48754 -55.476394)
		(mid 69.8754 -54.864254)
		(end 69.26326 -55.476394)
		(stroke
			(width 0.2)
			(type default)
		)
		(layer "In1.Cu")
	)
	(gr_arc
		(start 70.48754 -55.466742)
		(mid 69.875527 -54.854348)
		(end 69.26326 -55.466488)
		(stroke
			(width 0.2)
			(type default)
		)
		(layer "In1.Cu")
	)
	(gr_line
		(start 70.48754 -28.9941)
		(end 70.48754 -27.876754)
		(stroke
			(width 0.2)
			(type default)
		)
		(layer "In1.Cu")
	)
	(gr_line
		(start 70.48754 -28.98394)
		(end 70.48754 -27.86634)
		(stroke
			(width 0.2)
			(type default)
		)
		(layer "In1.Cu")
	)
	(gr_arc
		(start 70.48754 -27.876754)
		(mid 69.875527 -27.26436)
		(end 69.26326 -27.8765)
		(stroke
			(width 0.2)
			(type default)
		)
		(layer "In1.Cu")
	)
	(gr_arc
		(start 70.48754 -27.86634)
		(mid 69.8754 -27.2542)
		(end 69.26326 -27.86634)
		(stroke
			(width 0.2)
			(type default)
		)
		(layer "In1.Cu")
	)
	(gr_line
		(start 71.950326 -56.637682)
		(end 71.950326 -55.442358)
		(stroke
			(width 0.2)
			(type default)
		)
		(layer "In1.Cu")
	)
	(gr_line
		(start 71.950326 -55.442358)
		(end 73.499726 -55.442358)
		(stroke
			(width 0.2)
			(type default)
		)
		(layer "In1.Cu")
	)
	(gr_line
		(start 71.950326 -55.137558)
		(end 71.950326 -53.942488)
		(stroke
			(width 0.2)
			(type default)
		)
		(layer "In1.Cu")
	)
	(gr_line
		(start 71.950326 -53.942488)
		(end 73.499726 -53.942488)
		(stroke
			(width 0.2)
			(type default)
		)
		(layer "In1.Cu")
	)
	(gr_line
		(start 71.950326 -53.637688)
		(end 71.950326 -52.442364)
		(stroke
			(width 0.2)
			(type default)
		)
		(layer "In1.Cu")
	)
	(gr_line
		(start 71.950326 -52.442364)
		(end 73.499726 -52.442364)
		(stroke
			(width 0.2)
			(type default)
		)
		(layer "In1.Cu")
	)
	(gr_line
		(start 71.950326 -52.137564)
		(end 71.950326 -50.942494)
		(stroke
			(width 0.2)
			(type default)
		)
		(layer "In1.Cu")
	)
	(gr_line
		(start 71.950326 -50.942494)
		(end 73.499726 -50.942494)
		(stroke
			(width 0.2)
			(type default)
		)
		(layer "In1.Cu")
	)
	(gr_line
		(start 71.950326 -50.637694)
		(end 71.950326 -49.44237)
		(stroke
			(width 0.2)
			(type default)
		)
		(layer "In1.Cu")
	)
	(gr_line
		(start 71.950326 -49.44237)
		(end 73.499726 -49.44237)
		(stroke
			(width 0.2)
			(type default)
		)
		(layer "In1.Cu")
	)
	(gr_line
		(start 71.950326 -29.047694)
		(end 71.950326 -27.85237)
		(stroke
			(width 0.2)
			(type default)
		)
		(layer "In1.Cu")
	)
	(gr_line
		(start 71.950326 -27.85237)
		(end 73.499726 -27.85237)
		(stroke
			(width 0.2)
			(type default)
		)
		(layer "In1.Cu")
	)
	(gr_line
		(start 71.950326 -27.54757)
		(end 71.950326 -26.3525)
		(stroke
			(width 0.2)
			(type default)
		)
		(layer "In1.Cu")
	)
	(gr_line
		(start 71.950326 -26.3525)
		(end 73.499726 -26.3525)
		(stroke
			(width 0.2)
			(type default)
		)
		(layer "In1.Cu")
	)
	(gr_line
		(start 71.950326 -26.0477)
		(end 71.950326 -24.852376)
		(stroke
			(width 0.2)
			(type default)
		)
		(layer "In1.Cu")
	)
	(gr_line
		(start 71.950326 -24.852376)
		(end 73.499726 -24.852376)
		(stroke
			(width 0.2)
			(type default)
		)
		(layer "In1.Cu")
	)
	(gr_line
		(start 71.950326 -24.547576)
		(end 71.950326 -23.352506)
		(stroke
			(width 0.2)
			(type default)
		)
		(layer "In1.Cu")
	)
	(gr_line
		(start 71.950326 -23.352506)
		(end 73.499726 -23.352506)
		(stroke
			(width 0.2)
			(type default)
		)
		(layer "In1.Cu")
	)
	(gr_line
		(start 71.950326 -23.037546)
		(end 71.950326 -21.842222)
		(stroke
			(width 0.2)
			(type default)
		)
		(layer "In1.Cu")
	)
	(gr_line
		(start 71.950326 -21.842222)
		(end 73.499726 -21.842222)
		(stroke
			(width 0.2)
			(type default)
		)
		(layer "In1.Cu")
	)
	(gr_arc
		(start 73.47966 -50.434494)
		(mid 73.9902 -50.945034)
		(end 74.50074 -50.434494)
		(stroke
			(width 0.2)
			(type default)
		)
		(layer "In1.Cu")
	)
	(gr_line
		(start 73.47966 -49.621694)
		(end 73.47966 -50.434494)
		(stroke
			(width 0.2)
			(type default)
		)
		(layer "In1.Cu")
	)
	(gr_line
		(start 73.499726 -56.637682)
		(end 71.950326 -56.637682)
		(stroke
			(width 0.2)
			(type default)
		)
		(layer "In1.Cu")
	)
	(gr_line
		(start 73.499726 -55.442358)
		(end 73.499726 -56.637682)
		(stroke
			(width 0.2)
			(type default)
		)
		(layer "In1.Cu")
	)
	(gr_line
		(start 73.499726 -55.137558)
		(end 71.950326 -55.137558)
		(stroke
			(width 0.2)
			(type default)
		)
		(layer "In1.Cu")
	)
	(gr_line
		(start 73.499726 -53.942488)
		(end 73.499726 -55.137558)
		(stroke
			(width 0.2)
			(type default)
		)
		(layer "In1.Cu")
	)
	(gr_line
		(start 73.499726 -53.637688)
		(end 71.950326 -53.637688)
		(stroke
			(width 0.2)
			(type default)
		)
		(layer "In1.Cu")
	)
	(gr_line
		(start 73.499726 -52.442364)
		(end 73.499726 -53.637688)
		(stroke
			(width 0.2)
			(type default)
		)
		(layer "In1.Cu")
	)
	(gr_line
		(start 73.499726 -52.137564)
		(end 71.950326 -52.137564)
		(stroke
			(width 0.2)
			(type default)
		)
		(layer "In1.Cu")
	)
	(gr_line
		(start 73.499726 -50.942494)
		(end 73.499726 -52.137564)
		(stroke
			(width 0.2)
			(type default)
		)
		(layer "In1.Cu")
	)
	(gr_line
		(start 73.499726 -50.637694)
		(end 71.950326 -50.637694)
		(stroke
			(width 0.2)
			(type default)
		)
		(layer "In1.Cu")
	)
	(gr_line
		(start 73.499726 -49.44237)
		(end 73.499726 -50.637694)
		(stroke
			(width 0.2)
			(type default)
		)
		(layer "In1.Cu")
	)
	(gr_line
		(start 73.499726 -29.047694)
		(end 71.950326 -29.047694)
		(stroke
			(width 0.2)
			(type default)
		)
		(layer "In1.Cu")
	)
	(gr_line
		(start 73.499726 -27.85237)
		(end 73.499726 -29.047694)
		(stroke
			(width 0.2)
			(type default)
		)
		(layer "In1.Cu")
	)
	(gr_line
		(start 73.499726 -27.54757)
		(end 71.950326 -27.54757)
		(stroke
			(width 0.2)
			(type default)
		)
		(layer "In1.Cu")
	)
	(gr_line
		(start 73.499726 -26.3525)
		(end 73.499726 -27.54757)
		(stroke
			(width 0.2)
			(type default)
		)
		(layer "In1.Cu")
	)
	(gr_line
		(start 73.499726 -26.0477)
		(end 71.950326 -26.0477)
		(stroke
			(width 0.2)
			(type default)
		)
		(layer "In1.Cu")
	)
	(gr_line
		(start 73.499726 -24.852376)
		(end 73.499726 -26.0477)
		(stroke
			(width 0.2)
			(type default)
		)
		(layer "In1.Cu")
	)
	(gr_line
		(start 73.499726 -24.547576)
		(end 71.950326 -24.547576)
		(stroke
			(width 0.2)
			(type default)
		)
		(layer "In1.Cu")
	)
	(gr_line
		(start 73.499726 -23.352506)
		(end 73.499726 -24.547576)
		(stroke
			(width 0.2)
			(type default)
		)
		(layer "In1.Cu")
	)
	(gr_line
		(start 73.499726 -23.037546)
		(end 71.950326 -23.037546)
		(stroke
			(width 0.2)
			(type default)
		)
		(layer "In1.Cu")
	)
	(gr_line
		(start 73.499726 -21.842222)
		(end 73.499726 -23.037546)
		(stroke
			(width 0.2)
			(type default)
		)
		(layer "In1.Cu")
	)
	(gr_arc
		(start 74.41946 -22.834346)
		(mid 74.93 -23.344886)
		(end 75.44054 -22.834346)
		(stroke
			(width 0.2)
			(type default)
		)
		(layer "In1.Cu")
	)
	(gr_line
		(start 74.41946 -22.021546)
		(end 74.41946 -22.834346)
		(stroke
			(width 0.2)
			(type default)
		)
		(layer "In1.Cu")
	)
	(gr_line
		(start 74.50074 -50.434494)
		(end 74.50074 -49.621948)
		(stroke
			(width 0.2)
			(type default)
		)
		(layer "In1.Cu")
	)
	(gr_arc
		(start 74.50074 -49.621948)
		(mid 73.990327 -49.111154)
		(end 73.47966 -49.621694)
		(stroke
			(width 0.2)
			(type default)
		)
		(layer "In1.Cu")
	)
	(gr_line
		(start 75.44054 -22.834346)
		(end 75.44054 -22.0218)
		(stroke
			(width 0.2)
			(type default)
		)
		(layer "In1.Cu")
	)
	(gr_arc
		(start 75.44054 -22.0218)
		(mid 74.930127 -21.511006)
		(end 74.41946 -22.021546)
		(stroke
			(width 0.2)
			(type default)
		)
		(layer "In1.Cu")
	)
	(gr_arc
		(start 76.29906 -34.808922)
		(mid 76.9112 -35.421062)
		(end 77.52334 -34.808922)
		(stroke
			(width 0.2)
			(type default)
		)
		(layer "In1.Cu")
	)
	(gr_line
		(start 76.29906 -33.691322)
		(end 76.29906 -34.808922)
		(stroke
			(width 0.2)
			(type default)
		)
		(layer "In1.Cu")
	)
	(gr_line
		(start 77.52334 -34.808922)
		(end 77.52334 -33.691576)
		(stroke
			(width 0.2)
			(type default)
		)
		(layer "In1.Cu")
	)
	(gr_arc
		(start 77.52334 -33.691576)
		(mid 76.911327 -33.079182)
		(end 76.29906 -33.691322)
		(stroke
			(width 0.2)
			(type default)
		)
		(layer "In1.Cu")
	)
	(gr_arc
		(start 82.228436 -43.075098)
		(mid 82.611976 -43.458638)
		(end 82.995516 -43.075098)
		(stroke
			(width 0.2)
			(type default)
		)
		(layer "In1.Cu")
	)
	(gr_line
		(start 82.228436 -42.274998)
		(end 82.228436 -43.075098)
		(stroke
			(width 0.2)
			(type default)
		)
		(layer "In1.Cu")
	)
	(gr_arc
		(start 82.228436 -40.675052)
		(mid 82.611976 -41.058592)
		(end 82.995516 -40.675052)
		(stroke
			(width 0.2)
			(type default)
		)
		(layer "In1.Cu")
	)
	(gr_line
		(start 82.228436 -39.874952)
		(end 82.228436 -40.675052)
		(stroke
			(width 0.2)
			(type default)
		)
		(layer "In1.Cu")
	)
	(gr_arc
		(start 82.228436 -38.274752)
		(mid 82.611849 -38.658546)
		(end 82.995516 -38.275006)
		(stroke
			(width 0.2)
			(type default)
		)
		(layer "In1.Cu")
	)
	(gr_line
		(start 82.228436 -37.47516)
		(end 82.228436 -38.274752)
		(stroke
			(width 0.2)
			(type default)
		)
		(layer "In1.Cu")
	)
	(gr_arc
		(start 82.228436 -27.874976)
		(mid 82.611976 -28.258516)
		(end 82.995516 -27.874976)
		(stroke
			(width 0.2)
			(type default)
		)
		(layer "In1.Cu")
	)
	(gr_line
		(start 82.228436 -27.07513)
		(end 82.228436 -27.874976)
		(stroke
			(width 0.2)
			(type default)
		)
		(layer "In1.Cu")
	)
	(gr_arc
		(start 82.228436 -25.475184)
		(mid 82.611976 -25.858724)
		(end 82.995516 -25.475184)
		(stroke
			(width 0.2)
			(type default)
		)
		(layer "In1.Cu")
	)
	(gr_line
		(start 82.228436 -24.675084)
		(end 82.228436 -25.475184)
		(stroke
			(width 0.2)
			(type default)
		)
		(layer "In1.Cu")
	)
	(gr_arc
		(start 82.228436 -23.075138)
		(mid 82.611976 -23.458678)
		(end 82.995516 -23.075138)
		(stroke
			(width 0.2)
			(type default)
		)
		(layer "In1.Cu")
	)
	(gr_line
		(start 82.228436 -22.275038)
		(end 82.228436 -23.075138)
		(stroke
			(width 0.2)
			(type default)
		)
		(layer "In1.Cu")
	)
	(gr_arc
		(start 82.228436 -20.674838)
		(mid 82.611849 -21.058632)
		(end 82.995516 -20.675092)
		(stroke
			(width 0.2)
			(type default)
		)
		(layer "In1.Cu")
	)
	(gr_line
		(start 82.228436 -19.874992)
		(end 82.228436 -20.674838)
		(stroke
			(width 0.2)
			(type default)
		)
		(layer "In1.Cu")
	)
	(gr_arc
		(start 82.228436 -18.275046)
		(mid 82.611976 -18.658586)
		(end 82.995516 -18.275046)
		(stroke
			(width 0.2)
			(type default)
		)
		(layer "In1.Cu")
	)
	(gr_line
		(start 82.228436 -17.474946)
		(end 82.228436 -18.275046)
		(stroke
			(width 0.2)
			(type default)
		)
		(layer "In1.Cu")
	)
	(gr_arc
		(start 82.228436 -15.874746)
		(mid 82.611849 -16.25854)
		(end 82.995516 -15.875)
		(stroke
			(width 0.2)
			(type default)
		)
		(layer "In1.Cu")
	)
	(gr_line
		(start 82.228436 -15.075154)
		(end 82.228436 -15.874746)
		(stroke
			(width 0.2)
			(type default)
		)
		(layer "In1.Cu")
	)
	(gr_line
		(start 82.995516 -43.075098)
		(end 82.995516 -42.275252)
		(stroke
			(width 0.2)
			(type default)
		)
		(layer "In1.Cu")
	)
	(gr_arc
		(start 82.995516 -42.275252)
		(mid 82.612103 -41.891458)
		(end 82.228436 -42.274998)
		(stroke
			(width 0.2)
			(type default)
		)
		(layer "In1.Cu")
	)
	(gr_line
		(start 82.995516 -40.675052)
		(end 82.995516 -39.875206)
		(stroke
			(width 0.2)
			(type default)
		)
		(layer "In1.Cu")
	)
	(gr_arc
		(start 82.995516 -39.875206)
		(mid 82.612103 -39.491412)
		(end 82.228436 -39.874952)
		(stroke
			(width 0.2)
			(type default)
		)
		(layer "In1.Cu")
	)
	(gr_line
		(start 82.995516 -38.275006)
		(end 82.995516 -37.47516)
		(stroke
			(width 0.2)
			(type default)
		)
		(layer "In1.Cu")
	)
	(gr_arc
		(start 82.995516 -37.47516)
		(mid 82.611976 -37.09162)
		(end 82.228436 -37.47516)
		(stroke
			(width 0.2)
			(type default)
		)
		(layer "In1.Cu")
	)
	(gr_line
		(start 82.995516 -27.874976)
		(end 82.995516 -27.075384)
		(stroke
			(width 0.2)
			(type default)
		)
		(layer "In1.Cu")
	)
	(gr_arc
		(start 82.995516 -27.075384)
		(mid 82.612103 -26.69159)
		(end 82.228436 -27.07513)
		(stroke
			(width 0.2)
			(type default)
		)
		(layer "In1.Cu")
	)
	(gr_line
		(start 82.995516 -25.475184)
		(end 82.995516 -24.675338)
		(stroke
			(width 0.2)
			(type default)
		)
		(layer "In1.Cu")
	)
	(gr_arc
		(start 82.995516 -24.675338)
		(mid 82.612103 -24.291544)
		(end 82.228436 -24.675084)
		(stroke
			(width 0.2)
			(type default)
		)
		(layer "In1.Cu")
	)
	(gr_line
		(start 82.995516 -23.075138)
		(end 82.995516 -22.275292)
		(stroke
			(width 0.2)
			(type default)
		)
		(layer "In1.Cu")
	)
	(gr_arc
		(start 82.995516 -22.275292)
		(mid 82.612103 -21.891498)
		(end 82.228436 -22.275038)
		(stroke
			(width 0.2)
			(type default)
		)
		(layer "In1.Cu")
	)
	(gr_line
		(start 82.995516 -20.675092)
		(end 82.995516 -19.874992)
		(stroke
			(width 0.2)
			(type default)
		)
		(layer "In1.Cu")
	)
	(gr_arc
		(start 82.995516 -19.874992)
		(mid 82.611976 -19.491452)
		(end 82.228436 -19.874992)
		(stroke
			(width 0.2)
			(type default)
		)
		(layer "In1.Cu")
	)
	(gr_line
		(start 82.995516 -18.275046)
		(end 82.995516 -17.4752)
		(stroke
			(width 0.2)
			(type default)
		)
		(layer "In1.Cu")
	)
	(gr_arc
		(start 82.995516 -17.4752)
		(mid 82.612103 -17.091406)
		(end 82.228436 -17.474946)
		(stroke
			(width 0.2)
			(type default)
		)
		(layer "In1.Cu")
	)
	(gr_line
		(start 82.995516 -15.875)
		(end 82.995516 -15.075154)
		(stroke
			(width 0.2)
			(type default)
		)
		(layer "In1.Cu")
	)
	(gr_arc
		(start 82.995516 -15.075154)
		(mid 82.611976 -14.691614)
		(end 82.228436 -15.075154)
		(stroke
			(width 0.2)
			(type default)
		)
		(layer "In1.Cu")
	)
	(gr_line
		(start 69.3674 -53.584094)
		(end 69.61378 -53.337968)
		(stroke
			(width 0.066548)
			(type default)
		)
		(layer "In2.Cu")
	)
	(gr_line
		(start 69.3674 -52.466494)
		(end 69.614034 -52.713128)
		(stroke
			(width 0.066548)
			(type default)
		)
		(layer "In2.Cu")
	)
	(gr_line
		(start 69.3674 -25.983946)
		(end 69.61378 -25.73782)
		(stroke
			(width 0.066548)
			(type default)
		)
		(layer "In2.Cu")
	)
	(gr_line
		(start 69.3674 -24.866346)
		(end 69.614034 -25.11298)
		(stroke
			(width 0.066548)
			(type default)
		)
		(layer "In2.Cu")
	)
	(gr_arc
		(start 69.614034 -52.713128)
		(mid 69.780556 -52.824429)
		(end 69.977 -52.863496)
		(stroke
			(width 0.066548)
			(type default)
		)
		(layer "In2.Cu")
	)
	(gr_arc
		(start 69.614034 -25.11298)
		(mid 69.780554 -25.224291)
		(end 69.977 -25.263348)
		(stroke
			(width 0.066548)
			(type default)
		)
		(layer "In2.Cu")
	)
	(gr_line
		(start 69.8754 -56.584088)
		(end 70.12178 -56.337962)
		(stroke
			(width 0.066548)
			(type default)
		)
		(layer "In2.Cu")
	)
	(gr_line
		(start 69.8754 -55.466488)
		(end 70.122034 -55.713122)
		(stroke
			(width 0.066548)
			(type default)
		)
		(layer "In2.Cu")
	)
	(gr_line
		(start 69.8754 -28.98394)
		(end 70.12178 -28.737814)
		(stroke
			(width 0.066548)
			(type default)
		)
		(layer "In2.Cu")
	)
	(gr_line
		(start 69.8754 -27.86634)
		(end 70.122034 -28.112974)
		(stroke
			(width 0.066548)
			(type default)
		)
		(layer "In2.Cu")
	)
	(gr_arc
		(start 69.977 -53.187346)
		(mid 69.780415 -53.226543)
		(end 69.61378 -53.337968)
		(stroke
			(width 0.066548)
			(type default)
		)
		(layer "In2.Cu")
	)
	(gr_arc
		(start 69.977 -25.587198)
		(mid 69.780415 -25.626395)
		(end 69.61378 -25.73782)
		(stroke
			(width 0.066548)
			(type default)
		)
		(layer "In2.Cu")
	)
	(gr_arc
		(start 70.122034 -55.713122)
		(mid 70.288556 -55.824424)
		(end 70.485 -55.86349)
		(stroke
			(width 0.066548)
			(type default)
		)
		(layer "In2.Cu")
	)
	(gr_arc
		(start 70.122034 -28.112974)
		(mid 70.288553 -28.224287)
		(end 70.485 -28.263342)
		(stroke
			(width 0.066548)
			(type default)
		)
		(layer "In2.Cu")
	)
	(gr_arc
		(start 70.485 -56.18734)
		(mid 70.288415 -56.226537)
		(end 70.12178 -56.337962)
		(stroke
			(width 0.066548)
			(type default)
		)
		(layer "In2.Cu")
	)
	(gr_arc
		(start 70.485 -28.587192)
		(mid 70.288415 -28.626389)
		(end 70.12178 -28.737814)
		(stroke
			(width 0.066548)
			(type default)
		)
		(layer "In2.Cu")
	)
	(gr_arc
		(start 82.042 -20.113244)
		(mid 82.348518 -20.052346)
		(end 82.60842 -19.878802)
		(stroke
			(width 0.066548)
			(type default)
		)
		(layer "In2.Cu")
	)
	(gr_arc
		(start 82.169 -37.713158)
		(mid 82.358299 -37.675421)
		(end 82.518758 -37.568124)
		(stroke
			(width 0.066548)
			(type default)
		)
		(layer "In2.Cu")
	)
	(gr_arc
		(start 82.169 -24.913336)
		(mid 82.358157 -24.875714)
		(end 82.518504 -24.768556)
		(stroke
			(width 0.066548)
			(type default)
		)
		(layer "In2.Cu")
	)
	(gr_arc
		(start 82.169254 -15.313152)
		(mid 82.358416 -15.275366)
		(end 82.518758 -15.168118)
		(stroke
			(width 0.066548)
			(type default)
		)
		(layer "In2.Cu")
	)
	(gr_line
		(start 82.518504 -24.768556)
		(end 82.611976 -24.675084)
		(stroke
			(width 0.066548)
			(type default)
		)
		(layer "In2.Cu")
	)
	(gr_arc
		(start 82.518758 -38.182042)
		(mid 82.35842 -38.074785)
		(end 82.169254 -38.037008)
		(stroke
			(width 0.066548)
			(type default)
		)
		(layer "In2.Cu")
	)
	(gr_line
		(start 82.518758 -38.182042)
		(end 82.611976 -38.275006)
		(stroke
			(width 0.066548)
			(type default)
		)
		(layer "In2.Cu")
	)
	(gr_line
		(start 82.518758 -37.568124)
		(end 82.611976 -37.47516)
		(stroke
			(width 0.066548)
			(type default)
		)
		(layer "In2.Cu")
	)
	(gr_arc
		(start 82.518758 -25.38222)
		(mid 82.358303 -25.274914)
		(end 82.169 -25.237186)
		(stroke
			(width 0.066548)
			(type default)
		)
		(layer "In2.Cu")
	)
	(gr_line
		(start 82.518758 -25.38222)
		(end 82.611976 -25.475184)
		(stroke
			(width 0.066548)
			(type default)
		)
		(layer "In2.Cu")
	)
	(gr_arc
		(start 82.518758 -15.782036)
		(mid 82.358303 -15.67473)
		(end 82.169 -15.637002)
		(stroke
			(width 0.066548)
			(type default)
		)
		(layer "In2.Cu")
	)
	(gr_line
		(start 82.518758 -15.782036)
		(end 82.611976 -15.875)
		(stroke
			(width 0.066548)
			(type default)
		)
		(layer "In2.Cu")
	)
	(gr_line
		(start 82.518758 -15.168118)
		(end 82.611976 -15.075154)
		(stroke
			(width 0.066548)
			(type default)
		)
		(layer "In2.Cu")
	)
	(gr_line
		(start 82.60842 -19.878802)
		(end 82.611976 -19.874992)
		(stroke
			(width 0.066548)
			(type default)
		)
		(layer "In2.Cu")
	)
	(gr_arc
		(start 82.608674 -20.67179)
		(mid 82.348682 -20.498069)
		(end 82.042 -20.437094)
		(stroke
			(width 0.066548)
			(type default)
		)
		(layer "In2.Cu")
	)
	(gr_line
		(start 82.608674 -20.67179)
		(end 82.611976 -20.675092)
		(stroke
			(width 0.066548)
			(type default)
		)
		(layer "In2.Cu")
	)
	(gr_line
		(start 58.928 -77.851)
		(end 59.182 -78.105)
		(stroke
			(width 0.381)
			(type default)
		)
		(layer "In3.Cu")
	)
	(gr_line
		(start 58.928 -16.637)
		(end 58.928 -77.851)
		(stroke
			(width 0.381)
			(type default)
		)
		(layer "In3.Cu")
	)
	(gr_line
		(start 59.182 -78.105)
		(end 65.786 -78.105)
		(stroke
			(width 0.381)
			(type default)
		)
		(layer "In3.Cu")
	)
	(gr_line
		(start 59.182 -16.383)
		(end 58.928 -16.637)
		(stroke
			(width 0.381)
			(type default)
		)
		(layer "In3.Cu")
	)
	(gr_line
		(start 62.103 -16.383)
		(end 59.182 -16.383)
		(stroke
			(width 0.381)
			(type default)
		)
		(layer "In3.Cu")
	)
	(gr_line
		(start 65.786 -78.105)
		(end 66.04 -77.851)
		(stroke
			(width 0.381)
			(type default)
		)
		(layer "In3.Cu")
	)
	(gr_line
		(start 65.786 -16.383)
		(end 62.103 -16.383)
		(stroke
			(width 0.381)
			(type default)
		)
		(layer "In3.Cu")
	)
	(gr_line
		(start 66.04 -77.851)
		(end 66.04 -16.637)
		(stroke
			(width 0.381)
			(type default)
		)
		(layer "In3.Cu")
	)
	(gr_line
		(start 66.04 -16.637)
		(end 65.786 -16.383)
		(stroke
			(width 0.381)
			(type default)
		)
		(layer "In3.Cu")
	)
	(gr_arc
		(start 68.75526 -53.593746)
		(mid 69.367273 -54.20614)
		(end 69.97954 -53.594)
		(stroke
			(width 0.2)
			(type default)
		)
		(layer "In3.Cu")
	)
	(gr_arc
		(start 68.75526 -53.584094)
		(mid 69.3674 -54.196234)
		(end 69.97954 -53.584094)
		(stroke
			(width 0.2)
			(type default)
		)
		(layer "In3.Cu")
	)
	(gr_line
		(start 68.75526 -52.4764)
		(end 68.75526 -53.593746)
		(stroke
			(width 0.2)
			(type default)
		)
		(layer "In3.Cu")
	)
	(gr_line
		(start 68.75526 -52.466494)
		(end 68.75526 -53.584094)
		(stroke
			(width 0.2)
			(type default)
		)
		(layer "In3.Cu")
	)
	(gr_arc
		(start 68.75526 -25.994106)
		(mid 69.3674 -26.606246)
		(end 69.97954 -25.994106)
		(stroke
			(width 0.2)
			(type default)
		)
		(layer "In3.Cu")
	)
	(gr_arc
		(start 68.75526 -25.983946)
		(mid 69.3674 -26.596086)
		(end 69.97954 -25.983946)
		(stroke
			(width 0.2)
			(type default)
		)
		(layer "In3.Cu")
	)
	(gr_line
		(start 68.75526 -24.876506)
		(end 68.75526 -25.994106)
		(stroke
			(width 0.2)
			(type default)
		)
		(layer "In3.Cu")
	)
	(gr_line
		(start 68.75526 -24.866346)
		(end 68.75526 -25.983946)
		(stroke
			(width 0.2)
			(type default)
		)
		(layer "In3.Cu")
	)
	(gr_arc
		(start 69.26326 -56.59374)
		(mid 69.875273 -57.206134)
		(end 70.48754 -56.593994)
		(stroke
			(width 0.2)
			(type default)
		)
		(layer "In3.Cu")
	)
	(gr_arc
		(start 69.26326 -56.584088)
		(mid 69.8754 -57.196228)
		(end 70.48754 -56.584088)
		(stroke
			(width 0.2)
			(type default)
		)
		(layer "In3.Cu")
	)
	(gr_line
		(start 69.26326 -55.476394)
		(end 69.26326 -56.59374)
		(stroke
			(width 0.2)
			(type default)
		)
		(layer "In3.Cu")
	)
	(gr_line
		(start 69.26326 -55.466488)
		(end 69.26326 -56.584088)
		(stroke
			(width 0.2)
			(type default)
		)
		(layer "In3.Cu")
	)
	(gr_arc
		(start 69.26326 -28.9941)
		(mid 69.8754 -29.60624)
		(end 70.48754 -28.9941)
		(stroke
			(width 0.2)
			(type default)
		)
		(layer "In3.Cu")
	)
	(gr_arc
		(start 69.26326 -28.983686)
		(mid 69.875273 -29.59608)
		(end 70.48754 -28.98394)
		(stroke
			(width 0.2)
			(type default)
		)
		(layer "In3.Cu")
	)
	(gr_line
		(start 69.26326 -27.8765)
		(end 69.26326 -28.9941)
		(stroke
			(width 0.2)
			(type default)
		)
		(layer "In3.Cu")
	)
	(gr_line
		(start 69.26326 -27.86634)
		(end 69.26326 -28.983686)
		(stroke
			(width 0.2)
			(type default)
		)
		(layer "In3.Cu")
	)
	(gr_line
		(start 69.97954 -53.594)
		(end 69.97954 -52.4764)
		(stroke
			(width 0.2)
			(type default)
		)
		(layer "In3.Cu")
	)
	(gr_line
		(start 69.97954 -53.584094)
		(end 69.97954 -52.466748)
		(stroke
			(width 0.2)
			(type default)
		)
		(layer "In3.Cu")
	)
	(gr_arc
		(start 69.97954 -52.4764)
		(mid 69.3674 -51.86426)
		(end 68.75526 -52.4764)
		(stroke
			(width 0.2)
			(type default)
		)
		(layer "In3.Cu")
	)
	(gr_arc
		(start 69.97954 -52.466748)
		(mid 69.367527 -51.854354)
		(end 68.75526 -52.466494)
		(stroke
			(width 0.2)
			(type default)
		)
		(layer "In3.Cu")
	)
	(gr_line
		(start 69.97954 -25.994106)
		(end 69.97954 -24.87676)
		(stroke
			(width 0.2)
			(type default)
		)
		(layer "In3.Cu")
	)
	(gr_line
		(start 69.97954 -25.983946)
		(end 69.97954 -24.8666)
		(stroke
			(width 0.2)
			(type default)
		)
		(layer "In3.Cu")
	)
	(gr_arc
		(start 69.97954 -24.87676)
		(mid 69.367527 -24.264366)
		(end 68.75526 -24.876506)
		(stroke
			(width 0.2)
			(type default)
		)
		(layer "In3.Cu")
	)
	(gr_arc
		(start 69.97954 -24.8666)
		(mid 69.367527 -24.254206)
		(end 68.75526 -24.866346)
		(stroke
			(width 0.2)
			(type default)
		)
		(layer "In3.Cu")
	)
	(gr_line
		(start 70.48754 -56.593994)
		(end 70.48754 -55.476394)
		(stroke
			(width 0.2)
			(type default)
		)
		(layer "In3.Cu")
	)
	(gr_line
		(start 70.48754 -56.584088)
		(end 70.48754 -55.466742)
		(stroke
			(width 0.2)
			(type default)
		)
		(layer "In3.Cu")
	)
	(gr_arc
		(start 70.48754 -55.476394)
		(mid 69.8754 -54.864254)
		(end 69.26326 -55.476394)
		(stroke
			(width 0.2)
			(type default)
		)
		(layer "In3.Cu")
	)
	(gr_arc
		(start 70.48754 -55.466742)
		(mid 69.875527 -54.854348)
		(end 69.26326 -55.466488)
		(stroke
			(width 0.2)
			(type default)
		)
		(layer "In3.Cu")
	)
	(gr_line
		(start 70.48754 -28.9941)
		(end 70.48754 -27.876754)
		(stroke
			(width 0.2)
			(type default)
		)
		(layer "In3.Cu")
	)
	(gr_line
		(start 70.48754 -28.98394)
		(end 70.48754 -27.86634)
		(stroke
			(width 0.2)
			(type default)
		)
		(layer "In3.Cu")
	)
	(gr_arc
		(start 70.48754 -27.876754)
		(mid 69.875527 -27.26436)
		(end 69.26326 -27.8765)
		(stroke
			(width 0.2)
			(type default)
		)
		(layer "In3.Cu")
	)
	(gr_arc
		(start 70.48754 -27.86634)
		(mid 69.8754 -27.2542)
		(end 69.26326 -27.86634)
		(stroke
			(width 0.2)
			(type default)
		)
		(layer "In3.Cu")
	)
	(gr_arc
		(start 73.47966 -50.434494)
		(mid 73.9902 -50.945034)
		(end 74.50074 -50.434494)
		(stroke
			(width 0.2)
			(type default)
		)
		(layer "In3.Cu")
	)
	(gr_line
		(start 73.47966 -49.621694)
		(end 73.47966 -50.434494)
		(stroke
			(width 0.2)
			(type default)
		)
		(layer "In3.Cu")
	)
	(gr_arc
		(start 74.41946 -22.834346)
		(mid 74.93 -23.344886)
		(end 75.44054 -22.834346)
		(stroke
			(width 0.2)
			(type default)
		)
		(layer "In3.Cu")
	)
	(gr_line
		(start 74.41946 -22.021546)
		(end 74.41946 -22.834346)
		(stroke
			(width 0.2)
			(type default)
		)
		(layer "In3.Cu")
	)
	(gr_line
		(start 74.50074 -50.434494)
		(end 74.50074 -49.621948)
		(stroke
			(width 0.2)
			(type default)
		)
		(layer "In3.Cu")
	)
	(gr_arc
		(start 74.50074 -49.621948)
		(mid 73.990327 -49.111154)
		(end 73.47966 -49.621694)
		(stroke
			(width 0.2)
			(type default)
		)
		(layer "In3.Cu")
	)
	(gr_line
		(start 75.44054 -22.834346)
		(end 75.44054 -22.0218)
		(stroke
			(width 0.2)
			(type default)
		)
		(layer "In3.Cu")
	)
	(gr_arc
		(start 75.44054 -22.0218)
		(mid 74.930127 -21.511006)
		(end 74.41946 -22.021546)
		(stroke
			(width 0.2)
			(type default)
		)
		(layer "In3.Cu")
	)
	(gr_arc
		(start 76.29906 -34.808922)
		(mid 76.9112 -35.421062)
		(end 77.52334 -34.808922)
		(stroke
			(width 0.2)
			(type default)
		)
		(layer "In3.Cu")
	)
	(gr_line
		(start 76.29906 -33.691322)
		(end 76.29906 -34.808922)
		(stroke
			(width 0.2)
			(type default)
		)
		(layer "In3.Cu")
	)
	(gr_line
		(start 77.52334 -34.808922)
		(end 77.52334 -33.691576)
		(stroke
			(width 0.2)
			(type default)
		)
		(layer "In3.Cu")
	)
	(gr_arc
		(start 77.52334 -33.691576)
		(mid 76.911327 -33.079182)
		(end 76.29906 -33.691322)
		(stroke
			(width 0.2)
			(type default)
		)
		(layer "In3.Cu")
	)
	(gr_arc
		(start 82.228436 -43.075098)
		(mid 82.611976 -43.458638)
		(end 82.995516 -43.075098)
		(stroke
			(width 0.2)
			(type default)
		)
		(layer "In3.Cu")
	)
	(gr_line
		(start 82.228436 -42.274998)
		(end 82.228436 -43.075098)
		(stroke
			(width 0.2)
			(type default)
		)
		(layer "In3.Cu")
	)
	(gr_arc
		(start 82.228436 -40.675052)
		(mid 82.611976 -41.058592)
		(end 82.995516 -40.675052)
		(stroke
			(width 0.2)
			(type default)
		)
		(layer "In3.Cu")
	)
	(gr_line
		(start 82.228436 -39.874952)
		(end 82.228436 -40.675052)
		(stroke
			(width 0.2)
			(type default)
		)
		(layer "In3.Cu")
	)
	(gr_arc
		(start 82.228436 -38.274752)
		(mid 82.611849 -38.658546)
		(end 82.995516 -38.275006)
		(stroke
			(width 0.2)
			(type default)
		)
		(layer "In3.Cu")
	)
	(gr_line
		(start 82.228436 -37.47516)
		(end 82.228436 -38.274752)
		(stroke
			(width 0.2)
			(type default)
		)
		(layer "In3.Cu")
	)
	(gr_arc
		(start 82.228436 -27.874976)
		(mid 82.611976 -28.258516)
		(end 82.995516 -27.874976)
		(stroke
			(width 0.2)
			(type default)
		)
		(layer "In3.Cu")
	)
	(gr_line
		(start 82.228436 -27.07513)
		(end 82.228436 -27.874976)
		(stroke
			(width 0.2)
			(type default)
		)
		(layer "In3.Cu")
	)
	(gr_arc
		(start 82.228436 -25.475184)
		(mid 82.611976 -25.858724)
		(end 82.995516 -25.475184)
		(stroke
			(width 0.2)
			(type default)
		)
		(layer "In3.Cu")
	)
	(gr_line
		(start 82.228436 -24.675084)
		(end 82.228436 -25.475184)
		(stroke
			(width 0.2)
			(type default)
		)
		(layer "In3.Cu")
	)
	(gr_arc
		(start 82.228436 -23.075138)
		(mid 82.611976 -23.458678)
		(end 82.995516 -23.075138)
		(stroke
			(width 0.2)
			(type default)
		)
		(layer "In3.Cu")
	)
	(gr_line
		(start 82.228436 -22.275038)
		(end 82.228436 -23.075138)
		(stroke
			(width 0.2)
			(type default)
		)
		(layer "In3.Cu")
	)
	(gr_arc
		(start 82.228436 -20.674838)
		(mid 82.611849 -21.058632)
		(end 82.995516 -20.675092)
		(stroke
			(width 0.2)
			(type default)
		)
		(layer "In3.Cu")
	)
	(gr_line
		(start 82.228436 -19.874992)
		(end 82.228436 -20.674838)
		(stroke
			(width 0.2)
			(type default)
		)
		(layer "In3.Cu")
	)
	(gr_arc
		(start 82.228436 -18.275046)
		(mid 82.611976 -18.658586)
		(end 82.995516 -18.275046)
		(stroke
			(width 0.2)
			(type default)
		)
		(layer "In3.Cu")
	)
	(gr_line
		(start 82.228436 -17.474946)
		(end 82.228436 -18.275046)
		(stroke
			(width 0.2)
			(type default)
		)
		(layer "In3.Cu")
	)
	(gr_arc
		(start 82.228436 -15.874746)
		(mid 82.611849 -16.25854)
		(end 82.995516 -15.875)
		(stroke
			(width 0.2)
			(type default)
		)
		(layer "In3.Cu")
	)
	(gr_line
		(start 82.228436 -15.075154)
		(end 82.228436 -15.874746)
		(stroke
			(width 0.2)
			(type default)
		)
		(layer "In3.Cu")
	)
	(gr_line
		(start 82.995516 -43.075098)
		(end 82.995516 -42.275252)
		(stroke
			(width 0.2)
			(type default)
		)
		(layer "In3.Cu")
	)
	(gr_arc
		(start 82.995516 -42.275252)
		(mid 82.612103 -41.891458)
		(end 82.228436 -42.274998)
		(stroke
			(width 0.2)
			(type default)
		)
		(layer "In3.Cu")
	)
	(gr_line
		(start 82.995516 -40.675052)
		(end 82.995516 -39.875206)
		(stroke
			(width 0.2)
			(type default)
		)
		(layer "In3.Cu")
	)
	(gr_arc
		(start 82.995516 -39.875206)
		(mid 82.612103 -39.491412)
		(end 82.228436 -39.874952)
		(stroke
			(width 0.2)
			(type default)
		)
		(layer "In3.Cu")
	)
	(gr_line
		(start 82.995516 -38.275006)
		(end 82.995516 -37.47516)
		(stroke
			(width 0.2)
			(type default)
		)
		(layer "In3.Cu")
	)
	(gr_arc
		(start 82.995516 -37.47516)
		(mid 82.611976 -37.09162)
		(end 82.228436 -37.47516)
		(stroke
			(width 0.2)
			(type default)
		)
		(layer "In3.Cu")
	)
	(gr_line
		(start 82.995516 -27.874976)
		(end 82.995516 -27.075384)
		(stroke
			(width 0.2)
			(type default)
		)
		(layer "In3.Cu")
	)
	(gr_arc
		(start 82.995516 -27.075384)
		(mid 82.612103 -26.69159)
		(end 82.228436 -27.07513)
		(stroke
			(width 0.2)
			(type default)
		)
		(layer "In3.Cu")
	)
	(gr_line
		(start 82.995516 -25.475184)
		(end 82.995516 -24.675338)
		(stroke
			(width 0.2)
			(type default)
		)
		(layer "In3.Cu")
	)
	(gr_arc
		(start 82.995516 -24.675338)
		(mid 82.612103 -24.291544)
		(end 82.228436 -24.675084)
		(stroke
			(width 0.2)
			(type default)
		)
		(layer "In3.Cu")
	)
	(gr_line
		(start 82.995516 -23.075138)
		(end 82.995516 -22.275292)
		(stroke
			(width 0.2)
			(type default)
		)
		(layer "In3.Cu")
	)
	(gr_arc
		(start 82.995516 -22.275292)
		(mid 82.612103 -21.891498)
		(end 82.228436 -22.275038)
		(stroke
			(width 0.2)
			(type default)
		)
		(layer "In3.Cu")
	)
	(gr_line
		(start 82.995516 -20.675092)
		(end 82.995516 -19.874992)
		(stroke
			(width 0.2)
			(type default)
		)
		(layer "In3.Cu")
	)
	(gr_arc
		(start 82.995516 -19.874992)
		(mid 82.611976 -19.491452)
		(end 82.228436 -19.874992)
		(stroke
			(width 0.2)
			(type default)
		)
		(layer "In3.Cu")
	)
	(gr_line
		(start 82.995516 -18.275046)
		(end 82.995516 -17.4752)
		(stroke
			(width 0.2)
			(type default)
		)
		(layer "In3.Cu")
	)
	(gr_arc
		(start 82.995516 -17.4752)
		(mid 82.612103 -17.091406)
		(end 82.228436 -17.474946)
		(stroke
			(width 0.2)
			(type default)
		)
		(layer "In3.Cu")
	)
	(gr_line
		(start 82.995516 -15.875)
		(end 82.995516 -15.075154)
		(stroke
			(width 0.2)
			(type default)
		)
		(layer "In3.Cu")
	)
	(gr_arc
		(start 82.995516 -15.075154)
		(mid 82.611976 -14.691614)
		(end 82.228436 -15.075154)
		(stroke
			(width 0.2)
			(type default)
		)
		(layer "In3.Cu")
	)
	(gr_line
		(start 58.928 -77.851)
		(end 59.182 -78.105)
		(stroke
			(width 0.381)
			(type default)
		)
		(layer "In4.Cu")
	)
	(gr_line
		(start 58.928 -16.637)
		(end 58.928 -77.851)
		(stroke
			(width 0.381)
			(type default)
		)
		(layer "In4.Cu")
	)
	(gr_line
		(start 59.182 -78.105)
		(end 65.786 -78.105)
		(stroke
			(width 0.381)
			(type default)
		)
		(layer "In4.Cu")
	)
	(gr_line
		(start 59.182 -16.383)
		(end 58.928 -16.637)
		(stroke
			(width 0.381)
			(type default)
		)
		(layer "In4.Cu")
	)
	(gr_line
		(start 62.103 -16.383)
		(end 59.182 -16.383)
		(stroke
			(width 0.381)
			(type default)
		)
		(layer "In4.Cu")
	)
	(gr_line
		(start 65.786 -78.105)
		(end 66.04 -77.851)
		(stroke
			(width 0.381)
			(type default)
		)
		(layer "In4.Cu")
	)
	(gr_line
		(start 65.786 -16.383)
		(end 62.103 -16.383)
		(stroke
			(width 0.381)
			(type default)
		)
		(layer "In4.Cu")
	)
	(gr_line
		(start 66.04 -77.851)
		(end 66.04 -16.637)
		(stroke
			(width 0.381)
			(type default)
		)
		(layer "In4.Cu")
	)
	(gr_line
		(start 66.04 -16.637)
		(end 65.786 -16.383)
		(stroke
			(width 0.381)
			(type default)
		)
		(layer "In4.Cu")
	)
	(gr_arc
		(start 68.75526 -53.593746)
		(mid 69.367273 -54.20614)
		(end 69.97954 -53.594)
		(stroke
			(width 0.2)
			(type default)
		)
		(layer "In4.Cu")
	)
	(gr_arc
		(start 68.75526 -53.584094)
		(mid 69.3674 -54.196234)
		(end 69.97954 -53.584094)
		(stroke
			(width 0.2)
			(type default)
		)
		(layer "In4.Cu")
	)
	(gr_line
		(start 68.75526 -52.4764)
		(end 68.75526 -53.593746)
		(stroke
			(width 0.2)
			(type default)
		)
		(layer "In4.Cu")
	)
	(gr_line
		(start 68.75526 -52.466494)
		(end 68.75526 -53.584094)
		(stroke
			(width 0.2)
			(type default)
		)
		(layer "In4.Cu")
	)
	(gr_arc
		(start 68.75526 -25.994106)
		(mid 69.3674 -26.606246)
		(end 69.97954 -25.994106)
		(stroke
			(width 0.2)
			(type default)
		)
		(layer "In4.Cu")
	)
	(gr_arc
		(start 68.75526 -25.983946)
		(mid 69.3674 -26.596086)
		(end 69.97954 -25.983946)
		(stroke
			(width 0.2)
			(type default)
		)
		(layer "In4.Cu")
	)
	(gr_line
		(start 68.75526 -24.876506)
		(end 68.75526 -25.994106)
		(stroke
			(width 0.2)
			(type default)
		)
		(layer "In4.Cu")
	)
	(gr_line
		(start 68.75526 -24.866346)
		(end 68.75526 -25.983946)
		(stroke
			(width 0.2)
			(type default)
		)
		(layer "In4.Cu")
	)
	(gr_arc
		(start 69.26326 -56.59374)
		(mid 69.875273 -57.206134)
		(end 70.48754 -56.593994)
		(stroke
			(width 0.2)
			(type default)
		)
		(layer "In4.Cu")
	)
	(gr_arc
		(start 69.26326 -56.584088)
		(mid 69.8754 -57.196228)
		(end 70.48754 -56.584088)
		(stroke
			(width 0.2)
			(type default)
		)
		(layer "In4.Cu")
	)
	(gr_line
		(start 69.26326 -55.476394)
		(end 69.26326 -56.59374)
		(stroke
			(width 0.2)
			(type default)
		)
		(layer "In4.Cu")
	)
	(gr_line
		(start 69.26326 -55.466488)
		(end 69.26326 -56.584088)
		(stroke
			(width 0.2)
			(type default)
		)
		(layer "In4.Cu")
	)
	(gr_arc
		(start 69.26326 -28.9941)
		(mid 69.8754 -29.60624)
		(end 70.48754 -28.9941)
		(stroke
			(width 0.2)
			(type default)
		)
		(layer "In4.Cu")
	)
	(gr_arc
		(start 69.26326 -28.983686)
		(mid 69.875273 -29.59608)
		(end 70.48754 -28.98394)
		(stroke
			(width 0.2)
			(type default)
		)
		(layer "In4.Cu")
	)
	(gr_line
		(start 69.26326 -27.8765)
		(end 69.26326 -28.9941)
		(stroke
			(width 0.2)
			(type default)
		)
		(layer "In4.Cu")
	)
	(gr_line
		(start 69.26326 -27.86634)
		(end 69.26326 -28.983686)
		(stroke
			(width 0.2)
			(type default)
		)
		(layer "In4.Cu")
	)
	(gr_line
		(start 69.97954 -53.594)
		(end 69.97954 -52.4764)
		(stroke
			(width 0.2)
			(type default)
		)
		(layer "In4.Cu")
	)
	(gr_line
		(start 69.97954 -53.584094)
		(end 69.97954 -52.466748)
		(stroke
			(width 0.2)
			(type default)
		)
		(layer "In4.Cu")
	)
	(gr_arc
		(start 69.97954 -52.4764)
		(mid 69.3674 -51.86426)
		(end 68.75526 -52.4764)
		(stroke
			(width 0.2)
			(type default)
		)
		(layer "In4.Cu")
	)
	(gr_arc
		(start 69.97954 -52.466748)
		(mid 69.367527 -51.854354)
		(end 68.75526 -52.466494)
		(stroke
			(width 0.2)
			(type default)
		)
		(layer "In4.Cu")
	)
	(gr_line
		(start 69.97954 -25.994106)
		(end 69.97954 -24.87676)
		(stroke
			(width 0.2)
			(type default)
		)
		(layer "In4.Cu")
	)
	(gr_line
		(start 69.97954 -25.983946)
		(end 69.97954 -24.8666)
		(stroke
			(width 0.2)
			(type default)
		)
		(layer "In4.Cu")
	)
	(gr_arc
		(start 69.97954 -24.87676)
		(mid 69.367527 -24.264366)
		(end 68.75526 -24.876506)
		(stroke
			(width 0.2)
			(type default)
		)
		(layer "In4.Cu")
	)
	(gr_arc
		(start 69.97954 -24.8666)
		(mid 69.367527 -24.254206)
		(end 68.75526 -24.866346)
		(stroke
			(width 0.2)
			(type default)
		)
		(layer "In4.Cu")
	)
	(gr_line
		(start 70.48754 -56.593994)
		(end 70.48754 -55.476394)
		(stroke
			(width 0.2)
			(type default)
		)
		(layer "In4.Cu")
	)
	(gr_line
		(start 70.48754 -56.584088)
		(end 70.48754 -55.466742)
		(stroke
			(width 0.2)
			(type default)
		)
		(layer "In4.Cu")
	)
	(gr_arc
		(start 70.48754 -55.476394)
		(mid 69.8754 -54.864254)
		(end 69.26326 -55.476394)
		(stroke
			(width 0.2)
			(type default)
		)
		(layer "In4.Cu")
	)
	(gr_arc
		(start 70.48754 -55.466742)
		(mid 69.875527 -54.854348)
		(end 69.26326 -55.466488)
		(stroke
			(width 0.2)
			(type default)
		)
		(layer "In4.Cu")
	)
	(gr_line
		(start 70.48754 -28.9941)
		(end 70.48754 -27.876754)
		(stroke
			(width 0.2)
			(type default)
		)
		(layer "In4.Cu")
	)
	(gr_line
		(start 70.48754 -28.98394)
		(end 70.48754 -27.86634)
		(stroke
			(width 0.2)
			(type default)
		)
		(layer "In4.Cu")
	)
	(gr_arc
		(start 70.48754 -27.876754)
		(mid 69.875527 -27.26436)
		(end 69.26326 -27.8765)
		(stroke
			(width 0.2)
			(type default)
		)
		(layer "In4.Cu")
	)
	(gr_arc
		(start 70.48754 -27.86634)
		(mid 69.8754 -27.2542)
		(end 69.26326 -27.86634)
		(stroke
			(width 0.2)
			(type default)
		)
		(layer "In4.Cu")
	)
	(gr_arc
		(start 73.47966 -50.434494)
		(mid 73.9902 -50.945034)
		(end 74.50074 -50.434494)
		(stroke
			(width 0.2)
			(type default)
		)
		(layer "In4.Cu")
	)
	(gr_line
		(start 73.47966 -49.621694)
		(end 73.47966 -50.434494)
		(stroke
			(width 0.2)
			(type default)
		)
		(layer "In4.Cu")
	)
	(gr_arc
		(start 74.41946 -22.834346)
		(mid 74.93 -23.344886)
		(end 75.44054 -22.834346)
		(stroke
			(width 0.2)
			(type default)
		)
		(layer "In4.Cu")
	)
	(gr_line
		(start 74.41946 -22.021546)
		(end 74.41946 -22.834346)
		(stroke
			(width 0.2)
			(type default)
		)
		(layer "In4.Cu")
	)
	(gr_line
		(start 74.50074 -50.434494)
		(end 74.50074 -49.621948)
		(stroke
			(width 0.2)
			(type default)
		)
		(layer "In4.Cu")
	)
	(gr_arc
		(start 74.50074 -49.621948)
		(mid 73.990327 -49.111154)
		(end 73.47966 -49.621694)
		(stroke
			(width 0.2)
			(type default)
		)
		(layer "In4.Cu")
	)
	(gr_line
		(start 75.44054 -22.834346)
		(end 75.44054 -22.0218)
		(stroke
			(width 0.2)
			(type default)
		)
		(layer "In4.Cu")
	)
	(gr_arc
		(start 75.44054 -22.0218)
		(mid 74.930127 -21.511006)
		(end 74.41946 -22.021546)
		(stroke
			(width 0.2)
			(type default)
		)
		(layer "In4.Cu")
	)
	(gr_arc
		(start 76.29906 -34.808922)
		(mid 76.9112 -35.421062)
		(end 77.52334 -34.808922)
		(stroke
			(width 0.2)
			(type default)
		)
		(layer "In4.Cu")
	)
	(gr_line
		(start 76.29906 -33.691322)
		(end 76.29906 -34.808922)
		(stroke
			(width 0.2)
			(type default)
		)
		(layer "In4.Cu")
	)
	(gr_line
		(start 77.52334 -34.808922)
		(end 77.52334 -33.691576)
		(stroke
			(width 0.2)
			(type default)
		)
		(layer "In4.Cu")
	)
	(gr_arc
		(start 77.52334 -33.691576)
		(mid 76.911327 -33.079182)
		(end 76.29906 -33.691322)
		(stroke
			(width 0.2)
			(type default)
		)
		(layer "In4.Cu")
	)
	(gr_arc
		(start 82.228436 -43.075098)
		(mid 82.611976 -43.458638)
		(end 82.995516 -43.075098)
		(stroke
			(width 0.2)
			(type default)
		)
		(layer "In4.Cu")
	)
	(gr_line
		(start 82.228436 -42.274998)
		(end 82.228436 -43.075098)
		(stroke
			(width 0.2)
			(type default)
		)
		(layer "In4.Cu")
	)
	(gr_arc
		(start 82.228436 -40.675052)
		(mid 82.611976 -41.058592)
		(end 82.995516 -40.675052)
		(stroke
			(width 0.2)
			(type default)
		)
		(layer "In4.Cu")
	)
	(gr_line
		(start 82.228436 -39.874952)
		(end 82.228436 -40.675052)
		(stroke
			(width 0.2)
			(type default)
		)
		(layer "In4.Cu")
	)
	(gr_arc
		(start 82.228436 -38.274752)
		(mid 82.611849 -38.658546)
		(end 82.995516 -38.275006)
		(stroke
			(width 0.2)
			(type default)
		)
		(layer "In4.Cu")
	)
	(gr_line
		(start 82.228436 -37.47516)
		(end 82.228436 -38.274752)
		(stroke
			(width 0.2)
			(type default)
		)
		(layer "In4.Cu")
	)
	(gr_arc
		(start 82.228436 -27.874976)
		(mid 82.611976 -28.258516)
		(end 82.995516 -27.874976)
		(stroke
			(width 0.2)
			(type default)
		)
		(layer "In4.Cu")
	)
	(gr_line
		(start 82.228436 -27.07513)
		(end 82.228436 -27.874976)
		(stroke
			(width 0.2)
			(type default)
		)
		(layer "In4.Cu")
	)
	(gr_arc
		(start 82.228436 -25.475184)
		(mid 82.611976 -25.858724)
		(end 82.995516 -25.475184)
		(stroke
			(width 0.2)
			(type default)
		)
		(layer "In4.Cu")
	)
	(gr_line
		(start 82.228436 -24.675084)
		(end 82.228436 -25.475184)
		(stroke
			(width 0.2)
			(type default)
		)
		(layer "In4.Cu")
	)
	(gr_arc
		(start 82.228436 -23.075138)
		(mid 82.611976 -23.458678)
		(end 82.995516 -23.075138)
		(stroke
			(width 0.2)
			(type default)
		)
		(layer "In4.Cu")
	)
	(gr_line
		(start 82.228436 -22.275038)
		(end 82.228436 -23.075138)
		(stroke
			(width 0.2)
			(type default)
		)
		(layer "In4.Cu")
	)
	(gr_arc
		(start 82.228436 -20.674838)
		(mid 82.611849 -21.058632)
		(end 82.995516 -20.675092)
		(stroke
			(width 0.2)
			(type default)
		)
		(layer "In4.Cu")
	)
	(gr_line
		(start 82.228436 -19.874992)
		(end 82.228436 -20.674838)
		(stroke
			(width 0.2)
			(type default)
		)
		(layer "In4.Cu")
	)
	(gr_arc
		(start 82.228436 -18.275046)
		(mid 82.611976 -18.658586)
		(end 82.995516 -18.275046)
		(stroke
			(width 0.2)
			(type default)
		)
		(layer "In4.Cu")
	)
	(gr_line
		(start 82.228436 -17.474946)
		(end 82.228436 -18.275046)
		(stroke
			(width 0.2)
			(type default)
		)
		(layer "In4.Cu")
	)
	(gr_arc
		(start 82.228436 -15.874746)
		(mid 82.611849 -16.25854)
		(end 82.995516 -15.875)
		(stroke
			(width 0.2)
			(type default)
		)
		(layer "In4.Cu")
	)
	(gr_line
		(start 82.228436 -15.075154)
		(end 82.228436 -15.874746)
		(stroke
			(width 0.2)
			(type default)
		)
		(layer "In4.Cu")
	)
	(gr_line
		(start 82.995516 -43.075098)
		(end 82.995516 -42.275252)
		(stroke
			(width 0.2)
			(type default)
		)
		(layer "In4.Cu")
	)
	(gr_arc
		(start 82.995516 -42.275252)
		(mid 82.612103 -41.891458)
		(end 82.228436 -42.274998)
		(stroke
			(width 0.2)
			(type default)
		)
		(layer "In4.Cu")
	)
	(gr_line
		(start 82.995516 -40.675052)
		(end 82.995516 -39.875206)
		(stroke
			(width 0.2)
			(type default)
		)
		(layer "In4.Cu")
	)
	(gr_arc
		(start 82.995516 -39.875206)
		(mid 82.612103 -39.491412)
		(end 82.228436 -39.874952)
		(stroke
			(width 0.2)
			(type default)
		)
		(layer "In4.Cu")
	)
	(gr_line
		(start 82.995516 -38.275006)
		(end 82.995516 -37.47516)
		(stroke
			(width 0.2)
			(type default)
		)
		(layer "In4.Cu")
	)
	(gr_arc
		(start 82.995516 -37.47516)
		(mid 82.611976 -37.09162)
		(end 82.228436 -37.47516)
		(stroke
			(width 0.2)
			(type default)
		)
		(layer "In4.Cu")
	)
	(gr_line
		(start 82.995516 -27.874976)
		(end 82.995516 -27.075384)
		(stroke
			(width 0.2)
			(type default)
		)
		(layer "In4.Cu")
	)
	(gr_arc
		(start 82.995516 -27.075384)
		(mid 82.612103 -26.69159)
		(end 82.228436 -27.07513)
		(stroke
			(width 0.2)
			(type default)
		)
		(layer "In4.Cu")
	)
	(gr_line
		(start 82.995516 -25.475184)
		(end 82.995516 -24.675338)
		(stroke
			(width 0.2)
			(type default)
		)
		(layer "In4.Cu")
	)
	(gr_arc
		(start 82.995516 -24.675338)
		(mid 82.612103 -24.291544)
		(end 82.228436 -24.675084)
		(stroke
			(width 0.2)
			(type default)
		)
		(layer "In4.Cu")
	)
	(gr_line
		(start 82.995516 -23.075138)
		(end 82.995516 -22.275292)
		(stroke
			(width 0.2)
			(type default)
		)
		(layer "In4.Cu")
	)
	(gr_arc
		(start 82.995516 -22.275292)
		(mid 82.612103 -21.891498)
		(end 82.228436 -22.275038)
		(stroke
			(width 0.2)
			(type default)
		)
		(layer "In4.Cu")
	)
	(gr_line
		(start 82.995516 -20.675092)
		(end 82.995516 -19.874992)
		(stroke
			(width 0.2)
			(type default)
		)
		(layer "In4.Cu")
	)
	(gr_arc
		(start 82.995516 -19.874992)
		(mid 82.611976 -19.491452)
		(end 82.228436 -19.874992)
		(stroke
			(width 0.2)
			(type default)
		)
		(layer "In4.Cu")
	)
	(gr_line
		(start 82.995516 -18.275046)
		(end 82.995516 -17.4752)
		(stroke
			(width 0.2)
			(type default)
		)
		(layer "In4.Cu")
	)
	(gr_arc
		(start 82.995516 -17.4752)
		(mid 82.612103 -17.091406)
		(end 82.228436 -17.474946)
		(stroke
			(width 0.2)
			(type default)
		)
		(layer "In4.Cu")
	)
	(gr_line
		(start 82.995516 -15.875)
		(end 82.995516 -15.075154)
		(stroke
			(width 0.2)
			(type default)
		)
		(layer "In4.Cu")
	)
	(gr_arc
		(start 82.995516 -15.075154)
		(mid 82.611976 -14.691614)
		(end 82.228436 -15.075154)
		(stroke
			(width 0.2)
			(type default)
		)
		(layer "In4.Cu")
	)
	(gr_line
		(start 72.32015 -48.676306)
		(end 72.32015 -49.501806)
		(stroke
			(width 0.066548)
			(type default)
		)
		(layer "In5.Cu")
	)
	(gr_line
		(start 72.32015 -47.124366)
		(end 72.32015 -47.623476)
		(stroke
			(width 0.066548)
			(type default)
		)
		(layer "In5.Cu")
	)
	(gr_line
		(start 72.52462 -49.995836)
		(end 72.540622 -50.011838)
		(stroke
			(width 0.066548)
			(type default)
		)
		(layer "In5.Cu")
	)
	(gr_arc
		(start 72.540622 -50.011838)
		(mid 72.726035 -50.135708)
		(end 72.944736 -50.179224)
		(stroke
			(width 0.066548)
			(type default)
		)
		(layer "In5.Cu")
	)
	(gr_arc
		(start 72.644 -48.349916)
		(mid 72.669249 -48.454762)
		(end 72.73798 -48.537876)
		(stroke
			(width 0.066548)
			(type default)
		)
		(layer "In5.Cu")
	)
	(gr_arc
		(start 72.644 -46.797976)
		(mid 72.669235 -46.902834)
		(end 72.73798 -46.985936)
		(stroke
			(width 0.066548)
			(type default)
		)
		(layer "In5.Cu")
	)
	(gr_arc
		(start 72.73798 -49.313846)
		(mid 72.806716 -49.230752)
		(end 72.83196 -49.125886)
		(stroke
			(width 0.066548)
			(type default)
		)
		(layer "In5.Cu")
	)
	(gr_arc
		(start 72.73798 -47.761906)
		(mid 72.669167 -47.84497)
		(end 72.644 -47.949866)
		(stroke
			(width 0.066548)
			(type default)
		)
		(layer "In5.Cu")
	)
	(gr_arc
		(start 72.73798 -47.761906)
		(mid 72.806716 -47.678812)
		(end 72.83196 -47.573946)
		(stroke
			(width 0.066548)
			(type default)
		)
		(layer "In5.Cu")
	)
	(gr_arc
		(start 72.83196 -48.725836)
		(mid 72.806805 -48.620926)
		(end 72.73798 -48.537876)
		(stroke
			(width 0.066548)
			(type default)
		)
		(layer "In5.Cu")
	)
	(gr_line
		(start 72.83196 -48.725836)
		(end 72.83196 -49.125886)
		(stroke
			(width 0.066548)
			(type default)
		)
		(layer "In5.Cu")
	)
	(gr_arc
		(start 72.83196 -47.173896)
		(mid 72.806805 -47.068986)
		(end 72.73798 -46.985936)
		(stroke
			(width 0.066548)
			(type default)
		)
		(layer "In5.Cu")
	)
	(gr_line
		(start 72.83196 -47.173896)
		(end 72.83196 -47.573946)
		(stroke
			(width 0.066548)
			(type default)
		)
		(layer "In5.Cu")
	)
	(gr_line
		(start 72.938386 -45.602398)
		(end 73.291192 -45.249592)
		(stroke
			(width 0.066548)
			(type default)
		)
		(layer "In5.Cu")
	)
	(gr_arc
		(start 73.135998 -45.995844)
		(mid 73.028595 -46.006007)
		(end 72.936608 -46.062392)
		(stroke
			(width 0.066548)
			(type default)
		)
		(layer "In5.Cu")
	)
	(gr_arc
		(start 73.135998 -45.995844)
		(mid 73.243398 -45.985667)
		(end 73.335388 -45.929296)
		(stroke
			(width 0.066548)
			(type default)
		)
		(layer "In5.Cu")
	)
	(gr_arc
		(start 73.2028 -49.855374)
		(mid 73.613475 -49.795726)
		(end 73.9902 -49.621694)
		(stroke
			(width 0.066548)
			(type default)
		)
		(layer "In5.Cu")
	)
	(gr_line
		(start 73.335388 -45.929296)
		(end 73.618344 -45.646594)
		(stroke
			(width 0.066548)
			(type default)
		)
		(layer "In5.Cu")
	)
	(gr_arc
		(start 73.618344 -45.646594)
		(mid 73.674592 -45.55458)
		(end 73.684638 -45.447204)
		(stroke
			(width 0.066548)
			(type default)
		)
		(layer "In5.Cu")
	)
	(gr_arc
		(start 73.751186 -45.247814)
		(mid 73.694796 -45.339798)
		(end 73.684638 -45.447204)
		(stroke
			(width 0.066548)
			(type default)
		)
		(layer "In5.Cu")
	)
	(gr_arc
		(start 73.9902 -50.434494)
		(mid 73.524191 -50.24413)
		(end 73.025 -50.179224)
		(stroke
			(width 0.066548)
			(type default)
		)
		(layer "In5.Cu")
	)
	(gr_line
		(start 74.03592 -44.504864)
		(end 74.144124 -44.39666)
		(stroke
			(width 0.066548)
			(type default)
		)
		(layer "In5.Cu")
	)
	(gr_line
		(start 74.144124 -44.39666)
		(end 74.591672 -43.948858)
		(stroke
			(width 0.066548)
			(type default)
		)
		(layer "In5.Cu")
	)
	(gr_arc
		(start 74.233278 -44.898564)
		(mid 74.126002 -44.908575)
		(end 74.034142 -44.964858)
		(stroke
			(width 0.066548)
			(type default)
		)
		(layer "In5.Cu")
	)
	(gr_arc
		(start 74.233278 -44.898564)
		(mid 74.340678 -44.888387)
		(end 74.432668 -44.832016)
		(stroke
			(width 0.066548)
			(type default)
		)
		(layer "In5.Cu")
	)
	(gr_line
		(start 74.432668 -44.832016)
		(end 74.715624 -44.54906)
		(stroke
			(width 0.066548)
			(type default)
		)
		(layer "In5.Cu")
	)
	(gr_arc
		(start 74.715624 -44.54906)
		(mid 74.772027 -44.45708)
		(end 74.782172 -44.34967)
		(stroke
			(width 0.066548)
			(type default)
		)
		(layer "In5.Cu")
	)
	(gr_arc
		(start 74.848466 -44.150534)
		(mid 74.792296 -44.24244)
		(end 74.782172 -44.34967)
		(stroke
			(width 0.066548)
			(type default)
		)
		(layer "In5.Cu")
	)
	(gr_line
		(start 74.929492 -43.611038)
		(end 75.689968 -42.850562)
		(stroke
			(width 0.066548)
			(type default)
		)
		(layer "In5.Cu")
	)
	(gr_line
		(start 74.93 -22.834346)
		(end 75.000358 -22.763988)
		(stroke
			(width 0.066548)
			(type default)
		)
		(layer "In5.Cu")
	)
	(gr_line
		(start 74.93 -22.021546)
		(end 74.991468 -22.083014)
		(stroke
			(width 0.066548)
			(type default)
		)
		(layer "In5.Cu")
	)
	(gr_arc
		(start 74.991468 -22.083014)
		(mid 75.194368 -22.218544)
		(end 75.433682 -22.266148)
		(stroke
			(width 0.066548)
			(type default)
		)
		(layer "In5.Cu")
	)
	(gr_arc
		(start 75.330812 -43.80103)
		(mid 75.223405 -43.811187)
		(end 75.131422 -43.867578)
		(stroke
			(width 0.066548)
			(type default)
		)
		(layer "In5.Cu")
	)
	(gr_arc
		(start 75.330812 -43.80103)
		(mid 75.438187 -43.790982)
		(end 75.530202 -43.734736)
		(stroke
			(width 0.066548)
			(type default)
		)
		(layer "In5.Cu")
	)
	(gr_arc
		(start 75.420474 -22.589998)
		(mid 75.193119 -22.635222)
		(end 75.000358 -22.763988)
		(stroke
			(width 0.066548)
			(type default)
		)
		(layer "In5.Cu")
	)
	(gr_line
		(start 75.530202 -43.734736)
		(end 75.812904 -43.45178)
		(stroke
			(width 0.066548)
			(type default)
		)
		(layer "In5.Cu")
	)
	(gr_arc
		(start 75.812904 -43.45178)
		(mid 75.869307 -43.3598)
		(end 75.879452 -43.25239)
		(stroke
			(width 0.066548)
			(type default)
		)
		(layer "In5.Cu")
	)
	(gr_arc
		(start 75.946 -43.053)
		(mid 75.889601 -43.144983)
		(end 75.879452 -43.25239)
		(stroke
			(width 0.066548)
			(type default)
		)
		(layer "In5.Cu")
	)
	(gr_line
		(start 76.388214 -22.099016)
		(end 77.213968 -22.099016)
		(stroke
			(width 0.066548)
			(type default)
		)
		(layer "In5.Cu")
	)
	(gr_arc
		(start 76.576428 -22.516846)
		(mid 76.493334 -22.44811)
		(end 76.388468 -22.422866)
		(stroke
			(width 0.066548)
			(type default)
		)
		(layer "In5.Cu")
	)
	(gr_arc
		(start 76.576428 -22.516846)
		(mid 76.659487 -22.585672)
		(end 76.764388 -22.610826)
		(stroke
			(width 0.066548)
			(type default)
		)
		(layer "In5.Cu")
	)
	(gr_line
		(start 76.764388 -22.610826)
		(end 77.164438 -22.610826)
		(stroke
			(width 0.066548)
			(type default)
		)
		(layer "In5.Cu")
	)
	(gr_arc
		(start 76.9112 -33.691322)
		(mid 77.340895 -33.984996)
		(end 77.851 -34.088324)
		(stroke
			(width 0.066548)
			(type default)
		)
		(layer "In5.Cu")
	)
	(gr_arc
		(start 77.164438 -22.610826)
		(mid 77.269281 -22.585571)
		(end 77.352398 -22.516846)
		(stroke
			(width 0.066548)
			(type default)
		)
		(layer "In5.Cu")
	)
	(gr_arc
		(start 77.44714 -42.93108)
		(mid 77.364079 -42.862251)
		(end 77.25918 -42.8371)
		(stroke
			(width 0.066548)
			(type default)
		)
		(layer "In5.Cu")
	)
	(gr_arc
		(start 77.44714 -42.93108)
		(mid 77.530234 -42.999816)
		(end 77.6351 -43.02506)
		(stroke
			(width 0.066548)
			(type default)
		)
		(layer "In5.Cu")
	)
	(gr_arc
		(start 77.540358 -22.422866)
		(mid 77.435448 -22.448021)
		(end 77.352398 -22.516846)
		(stroke
			(width 0.066548)
			(type default)
		)
		(layer "In5.Cu")
	)
	(gr_line
		(start 77.58557 -42.51325)
		(end 78.08468 -42.51325)
		(stroke
			(width 0.066548)
			(type default)
		)
		(layer "In5.Cu")
	)
	(gr_arc
		(start 77.6224 -34.412174)
		(mid 77.215219 -34.518089)
		(end 76.9112 -34.808922)
		(stroke
			(width 0.066548)
			(type default)
		)
		(layer "In5.Cu")
	)
	(gr_line
		(start 77.6351 -43.02506)
		(end 78.03515 -43.02506)
		(stroke
			(width 0.066548)
			(type default)
		)
		(layer "In5.Cu")
	)
	(gr_arc
		(start 77.99705 -34.088324)
		(mid 78.10196 -34.063169)
		(end 78.18501 -33.994344)
		(stroke
			(width 0.066548)
			(type default)
		)
		(layer "In5.Cu")
	)
	(gr_arc
		(start 78.03515 -43.02506)
		(mid 78.14006 -42.999905)
		(end 78.22311 -42.93108)
		(stroke
			(width 0.066548)
			(type default)
		)
		(layer "In5.Cu")
	)
	(gr_line
		(start 78.32344 -34.412174)
		(end 78.82255 -34.412174)
		(stroke
			(width 0.066548)
			(type default)
		)
		(layer "In5.Cu")
	)
	(gr_arc
		(start 78.37297 -33.900364)
		(mid 78.268124 -33.925615)
		(end 78.18501 -33.994344)
		(stroke
			(width 0.066548)
			(type default)
		)
		(layer "In5.Cu")
	)
	(gr_line
		(start 78.37297 -33.900364)
		(end 78.77302 -33.900364)
		(stroke
			(width 0.066548)
			(type default)
		)
		(layer "In5.Cu")
	)
	(gr_arc
		(start 78.41107 -42.8371)
		(mid 78.306227 -42.862354)
		(end 78.22311 -42.93108)
		(stroke
			(width 0.066548)
			(type default)
		)
		(layer "In5.Cu")
	)
	(gr_arc
		(start 78.96098 -33.994344)
		(mid 78.87792 -33.925518)
		(end 78.77302 -33.900364)
		(stroke
			(width 0.066548)
			(type default)
		)
		(layer "In5.Cu")
	)
	(gr_arc
		(start 78.96098 -33.994344)
		(mid 79.044074 -34.06308)
		(end 79.14894 -34.088324)
		(stroke
			(width 0.066548)
			(type default)
		)
		(layer "In5.Cu")
	)
	(gr_arc
		(start 78.99908 -42.93108)
		(mid 78.916015 -42.862272)
		(end 78.81112 -42.8371)
		(stroke
			(width 0.066548)
			(type default)
		)
		(layer "In5.Cu")
	)
	(gr_arc
		(start 78.99908 -42.93108)
		(mid 79.082174 -42.999816)
		(end 79.18704 -43.02506)
		(stroke
			(width 0.066548)
			(type default)
		)
		(layer "In5.Cu")
	)
	(gr_line
		(start 79.13751 -42.51325)
		(end 79.63662 -42.51325)
		(stroke
			(width 0.066548)
			(type default)
		)
		(layer "In5.Cu")
	)
	(gr_line
		(start 79.18704 -43.02506)
		(end 79.58709 -43.02506)
		(stroke
			(width 0.066548)
			(type default)
		)
		(layer "In5.Cu")
	)
	(gr_arc
		(start 79.44104 -33.006284)
		(mid 79.466273 -33.111145)
		(end 79.53502 -33.194244)
		(stroke
			(width 0.066548)
			(type default)
		)
		(layer "In5.Cu")
	)
	(gr_line
		(start 79.44104 -32.606234)
		(end 79.44104 -33.006284)
		(stroke
			(width 0.066548)
			(type default)
		)
		(layer "In5.Cu")
	)
	(gr_arc
		(start 79.44104 -31.454344)
		(mid 79.466294 -31.559188)
		(end 79.53502 -31.642304)
		(stroke
			(width 0.066548)
			(type default)
		)
		(layer "In5.Cu")
	)
	(gr_line
		(start 79.44104 -31.054294)
		(end 79.44104 -31.454344)
		(stroke
			(width 0.066548)
			(type default)
		)
		(layer "In5.Cu")
	)
	(gr_arc
		(start 79.44104 -29.902404)
		(mid 79.46628 -30.007259)
		(end 79.53502 -30.090364)
		(stroke
			(width 0.066548)
			(type default)
		)
		(layer "In5.Cu")
	)
	(gr_line
		(start 79.44104 -29.502354)
		(end 79.44104 -29.902404)
		(stroke
			(width 0.066548)
			(type default)
		)
		(layer "In5.Cu")
	)
	(gr_arc
		(start 79.44104 -28.350464)
		(mid 79.466266 -28.45533)
		(end 79.53502 -28.538424)
		(stroke
			(width 0.066548)
			(type default)
		)
		(layer "In5.Cu")
	)
	(gr_line
		(start 79.44104 -27.950414)
		(end 79.44104 -28.350464)
		(stroke
			(width 0.066548)
			(type default)
		)
		(layer "In5.Cu")
	)
	(gr_arc
		(start 79.44104 -26.798524)
		(mid 79.466287 -26.903373)
		(end 79.53502 -26.986484)
		(stroke
			(width 0.066548)
			(type default)
		)
		(layer "In5.Cu")
	)
	(gr_line
		(start 79.44104 -26.398474)
		(end 79.44104 -26.798524)
		(stroke
			(width 0.066548)
			(type default)
		)
		(layer "In5.Cu")
	)
	(gr_arc
		(start 79.44104 -25.246584)
		(mid 79.466273 -25.351445)
		(end 79.53502 -25.434544)
		(stroke
			(width 0.066548)
			(type default)
		)
		(layer "In5.Cu")
	)
	(gr_line
		(start 79.44104 -24.846534)
		(end 79.44104 -25.246584)
		(stroke
			(width 0.066548)
			(type default)
		)
		(layer "In5.Cu")
	)
	(gr_arc
		(start 79.44104 -23.694644)
		(mid 79.466294 -23.799488)
		(end 79.53502 -23.882604)
		(stroke
			(width 0.066548)
			(type default)
		)
		(layer "In5.Cu")
	)
	(gr_line
		(start 79.44104 -23.294594)
		(end 79.44104 -23.694644)
		(stroke
			(width 0.066548)
			(type default)
		)
		(layer "In5.Cu")
	)
	(gr_arc
		(start 79.53502 -32.418274)
		(mid 79.466185 -32.501333)
		(end 79.44104 -32.606234)
		(stroke
			(width 0.066548)
			(type default)
		)
		(layer "In5.Cu")
	)
	(gr_arc
		(start 79.53502 -32.418274)
		(mid 79.603756 -32.33518)
		(end 79.629 -32.230314)
		(stroke
			(width 0.066548)
			(type default)
		)
		(layer "In5.Cu")
	)
	(gr_arc
		(start 79.53502 -30.866334)
		(mid 79.466171 -30.94939)
		(end 79.44104 -31.054294)
		(stroke
			(width 0.066548)
			(type default)
		)
		(layer "In5.Cu")
	)
	(gr_arc
		(start 79.53502 -30.866334)
		(mid 79.603756 -30.78324)
		(end 79.629 -30.678374)
		(stroke
			(width 0.066548)
			(type default)
		)
		(layer "In5.Cu")
	)
	(gr_arc
		(start 79.53502 -29.314394)
		(mid 79.466192 -29.397454)
		(end 79.44104 -29.502354)
		(stroke
			(width 0.066548)
			(type default)
		)
		(layer "In5.Cu")
	)
	(gr_arc
		(start 79.53502 -29.314394)
		(mid 79.603756 -29.2313)
		(end 79.629 -29.126434)
		(stroke
			(width 0.066548)
			(type default)
		)
		(layer "In5.Cu")
	)
	(gr_arc
		(start 79.53502 -27.762454)
		(mid 79.466178 -27.845511)
		(end 79.44104 -27.950414)
		(stroke
			(width 0.066548)
			(type default)
		)
		(layer "In5.Cu")
	)
	(gr_arc
		(start 79.53502 -27.762454)
		(mid 79.603756 -27.67936)
		(end 79.629 -27.574494)
		(stroke
			(width 0.066548)
			(type default)
		)
		(layer "In5.Cu")
	)
	(gr_arc
		(start 79.53502 -26.210514)
		(mid 79.466199 -26.293575)
		(end 79.44104 -26.398474)
		(stroke
			(width 0.066548)
			(type default)
		)
		(layer "In5.Cu")
	)
	(gr_arc
		(start 79.53502 -26.210514)
		(mid 79.603756 -26.12742)
		(end 79.629 -26.022554)
		(stroke
			(width 0.066548)
			(type default)
		)
		(layer "In5.Cu")
	)
	(gr_arc
		(start 79.53502 -24.658574)
		(mid 79.466185 -24.741633)
		(end 79.44104 -24.846534)
		(stroke
			(width 0.066548)
			(type default)
		)
		(layer "In5.Cu")
	)
	(gr_arc
		(start 79.53502 -24.658574)
		(mid 79.603756 -24.57548)
		(end 79.629 -24.470614)
		(stroke
			(width 0.066548)
			(type default)
		)
		(layer "In5.Cu")
	)
	(gr_arc
		(start 79.53502 -23.106634)
		(mid 79.466171 -23.18969)
		(end 79.44104 -23.294594)
		(stroke
			(width 0.066548)
			(type default)
		)
		(layer "In5.Cu")
	)
	(gr_arc
		(start 79.53502 -23.106634)
		(mid 79.603756 -23.02354)
		(end 79.629 -22.918674)
		(stroke
			(width 0.066548)
			(type default)
		)
		(layer "In5.Cu")
	)
	(gr_arc
		(start 79.58709 -43.02506)
		(mid 79.692 -42.999905)
		(end 79.77505 -42.93108)
		(stroke
			(width 0.066548)
			(type default)
		)
		(layer "In5.Cu")
	)
	(gr_arc
		(start 79.629 -33.382204)
		(mid 79.603845 -33.277294)
		(end 79.53502 -33.194244)
		(stroke
			(width 0.066548)
			(type default)
		)
		(layer "In5.Cu")
	)
	(gr_arc
		(start 79.629 -31.830264)
		(mid 79.603845 -31.725354)
		(end 79.53502 -31.642304)
		(stroke
			(width 0.066548)
			(type default)
		)
		(layer "In5.Cu")
	)
	(gr_arc
		(start 79.629 -30.278324)
		(mid 79.603845 -30.173414)
		(end 79.53502 -30.090364)
		(stroke
			(width 0.066548)
			(type default)
		)
		(layer "In5.Cu")
	)
	(gr_arc
		(start 79.629 -28.726384)
		(mid 79.603845 -28.621474)
		(end 79.53502 -28.538424)
		(stroke
			(width 0.066548)
			(type default)
		)
		(layer "In5.Cu")
	)
	(gr_arc
		(start 79.629 -27.174444)
		(mid 79.603845 -27.069534)
		(end 79.53502 -26.986484)
		(stroke
			(width 0.066548)
			(type default)
		)
		(layer "In5.Cu")
	)
	(gr_arc
		(start 79.629 -25.622504)
		(mid 79.603845 -25.517594)
		(end 79.53502 -25.434544)
		(stroke
			(width 0.066548)
			(type default)
		)
		(layer "In5.Cu")
	)
	(gr_arc
		(start 79.629 -24.070564)
		(mid 79.603845 -23.965654)
		(end 79.53502 -23.882604)
		(stroke
			(width 0.066548)
			(type default)
		)
		(layer "In5.Cu")
	)
	(gr_line
		(start 79.95285 -32.556704)
		(end 79.95285 -33.055814)
		(stroke
			(width 0.066548)
			(type default)
		)
		(layer "In5.Cu")
	)
	(gr_line
		(start 79.95285 -31.004764)
		(end 79.95285 -31.503874)
		(stroke
			(width 0.066548)
			(type default)
		)
		(layer "In5.Cu")
	)
	(gr_line
		(start 79.95285 -29.452824)
		(end 79.95285 -29.951934)
		(stroke
			(width 0.066548)
			(type default)
		)
		(layer "In5.Cu")
	)
	(gr_line
		(start 79.95285 -27.900884)
		(end 79.95285 -28.399994)
		(stroke
			(width 0.066548)
			(type default)
		)
		(layer "In5.Cu")
	)
	(gr_line
		(start 79.95285 -26.348944)
		(end 79.95285 -26.848054)
		(stroke
			(width 0.066548)
			(type default)
		)
		(layer "In5.Cu")
	)
	(gr_line
		(start 79.95285 -24.797004)
		(end 79.95285 -25.296114)
		(stroke
			(width 0.066548)
			(type default)
		)
		(layer "In5.Cu")
	)
	(gr_line
		(start 79.95285 -23.245064)
		(end 79.95285 -23.744174)
		(stroke
			(width 0.066548)
			(type default)
		)
		(layer "In5.Cu")
	)
	(gr_arc
		(start 79.96301 -42.8371)
		(mid 79.858156 -42.86234)
		(end 79.77505 -42.93108)
		(stroke
			(width 0.066548)
			(type default)
		)
		(layer "In5.Cu")
	)
	(gr_arc
		(start 80.55102 -42.93108)
		(mid 80.467958 -42.862258)
		(end 80.36306 -42.8371)
		(stroke
			(width 0.066548)
			(type default)
		)
		(layer "In5.Cu")
	)
	(gr_arc
		(start 80.55102 -42.93108)
		(mid 80.634114 -42.999816)
		(end 80.73898 -43.02506)
		(stroke
			(width 0.066548)
			(type default)
		)
		(layer "In5.Cu")
	)
	(gr_line
		(start 80.68945 -42.51325)
		(end 81.18856 -42.51325)
		(stroke
			(width 0.066548)
			(type default)
		)
		(layer "In5.Cu")
	)
	(gr_line
		(start 80.73898 -43.02506)
		(end 81.13903 -43.02506)
		(stroke
			(width 0.066548)
			(type default)
		)
		(layer "In5.Cu")
	)
	(gr_arc
		(start 81.13903 -43.02506)
		(mid 81.24394 -42.999905)
		(end 81.32699 -42.93108)
		(stroke
			(width 0.066548)
			(type default)
		)
		(layer "In5.Cu")
	)
	(gr_arc
		(start 81.51495 -42.8371)
		(mid 81.410085 -42.862326)
		(end 81.32699 -42.93108)
		(stroke
			(width 0.066548)
			(type default)
		)
		(layer "In5.Cu")
	)
	(gr_arc
		(start 81.788 -42.51325)
		(mid 82.216867 -42.452495)
		(end 82.611976 -42.274998)
		(stroke
			(width 0.066548)
			(type default)
		)
		(layer "In5.Cu")
	)
	(gr_line
		(start 82.11439 -42.8371)
		(end 82.169 -42.8371)
		(stroke
			(width 0.066548)
			(type default)
		)
		(layer "In5.Cu")
	)
	(gr_arc
		(start 82.518758 -42.982134)
		(mid 82.358299 -42.874836)
		(end 82.169 -42.8371)
		(stroke
			(width 0.066548)
			(type default)
		)
		(layer "In5.Cu")
	)
	(gr_line
		(start 82.518758 -42.982134)
		(end 82.611976 -43.075098)
		(stroke
			(width 0.066548)
			(type default)
		)
		(layer "In5.Cu")
	)
	(gr_arc
		(start 68.75526 -53.593746)
		(mid 69.367273 -54.20614)
		(end 69.97954 -53.594)
		(stroke
			(width 0.2)
			(type default)
		)
		(layer "In6.Cu")
	)
	(gr_arc
		(start 68.75526 -53.584094)
		(mid 69.3674 -54.196234)
		(end 69.97954 -53.584094)
		(stroke
			(width 0.2)
			(type default)
		)
		(layer "In6.Cu")
	)
	(gr_line
		(start 68.75526 -52.4764)
		(end 68.75526 -53.593746)
		(stroke
			(width 0.2)
			(type default)
		)
		(layer "In6.Cu")
	)
	(gr_line
		(start 68.75526 -52.466494)
		(end 68.75526 -53.584094)
		(stroke
			(width 0.2)
			(type default)
		)
		(layer "In6.Cu")
	)
	(gr_arc
		(start 68.75526 -25.994106)
		(mid 69.3674 -26.606246)
		(end 69.97954 -25.994106)
		(stroke
			(width 0.2)
			(type default)
		)
		(layer "In6.Cu")
	)
	(gr_arc
		(start 68.75526 -25.983946)
		(mid 69.3674 -26.596086)
		(end 69.97954 -25.983946)
		(stroke
			(width 0.2)
			(type default)
		)
		(layer "In6.Cu")
	)
	(gr_line
		(start 68.75526 -24.876506)
		(end 68.75526 -25.994106)
		(stroke
			(width 0.2)
			(type default)
		)
		(layer "In6.Cu")
	)
	(gr_line
		(start 68.75526 -24.866346)
		(end 68.75526 -25.983946)
		(stroke
			(width 0.2)
			(type default)
		)
		(layer "In6.Cu")
	)
	(gr_arc
		(start 69.26326 -56.59374)
		(mid 69.875273 -57.206134)
		(end 70.48754 -56.593994)
		(stroke
			(width 0.2)
			(type default)
		)
		(layer "In6.Cu")
	)
	(gr_arc
		(start 69.26326 -56.584088)
		(mid 69.8754 -57.196228)
		(end 70.48754 -56.584088)
		(stroke
			(width 0.2)
			(type default)
		)
		(layer "In6.Cu")
	)
	(gr_line
		(start 69.26326 -55.476394)
		(end 69.26326 -56.59374)
		(stroke
			(width 0.2)
			(type default)
		)
		(layer "In6.Cu")
	)
	(gr_line
		(start 69.26326 -55.466488)
		(end 69.26326 -56.584088)
		(stroke
			(width 0.2)
			(type default)
		)
		(layer "In6.Cu")
	)
	(gr_arc
		(start 69.26326 -28.9941)
		(mid 69.8754 -29.60624)
		(end 70.48754 -28.9941)
		(stroke
			(width 0.2)
			(type default)
		)
		(layer "In6.Cu")
	)
	(gr_arc
		(start 69.26326 -28.983686)
		(mid 69.875273 -29.59608)
		(end 70.48754 -28.98394)
		(stroke
			(width 0.2)
			(type default)
		)
		(layer "In6.Cu")
	)
	(gr_line
		(start 69.26326 -27.8765)
		(end 69.26326 -28.9941)
		(stroke
			(width 0.2)
			(type default)
		)
		(layer "In6.Cu")
	)
	(gr_line
		(start 69.26326 -27.86634)
		(end 69.26326 -28.983686)
		(stroke
			(width 0.2)
			(type default)
		)
		(layer "In6.Cu")
	)
	(gr_line
		(start 69.97954 -53.594)
		(end 69.97954 -52.4764)
		(stroke
			(width 0.2)
			(type default)
		)
		(layer "In6.Cu")
	)
	(gr_line
		(start 69.97954 -53.584094)
		(end 69.97954 -52.466748)
		(stroke
			(width 0.2)
			(type default)
		)
		(layer "In6.Cu")
	)
	(gr_arc
		(start 69.97954 -52.4764)
		(mid 69.3674 -51.86426)
		(end 68.75526 -52.4764)
		(stroke
			(width 0.2)
			(type default)
		)
		(layer "In6.Cu")
	)
	(gr_arc
		(start 69.97954 -52.466748)
		(mid 69.367527 -51.854354)
		(end 68.75526 -52.466494)
		(stroke
			(width 0.2)
			(type default)
		)
		(layer "In6.Cu")
	)
	(gr_line
		(start 69.97954 -25.994106)
		(end 69.97954 -24.87676)
		(stroke
			(width 0.2)
			(type default)
		)
		(layer "In6.Cu")
	)
	(gr_line
		(start 69.97954 -25.983946)
		(end 69.97954 -24.8666)
		(stroke
			(width 0.2)
			(type default)
		)
		(layer "In6.Cu")
	)
	(gr_arc
		(start 69.97954 -24.87676)
		(mid 69.367527 -24.264366)
		(end 68.75526 -24.876506)
		(stroke
			(width 0.2)
			(type default)
		)
		(layer "In6.Cu")
	)
	(gr_arc
		(start 69.97954 -24.8666)
		(mid 69.367527 -24.254206)
		(end 68.75526 -24.866346)
		(stroke
			(width 0.2)
			(type default)
		)
		(layer "In6.Cu")
	)
	(gr_line
		(start 70.48754 -56.593994)
		(end 70.48754 -55.476394)
		(stroke
			(width 0.2)
			(type default)
		)
		(layer "In6.Cu")
	)
	(gr_line
		(start 70.48754 -56.584088)
		(end 70.48754 -55.466742)
		(stroke
			(width 0.2)
			(type default)
		)
		(layer "In6.Cu")
	)
	(gr_arc
		(start 70.48754 -55.476394)
		(mid 69.8754 -54.864254)
		(end 69.26326 -55.476394)
		(stroke
			(width 0.2)
			(type default)
		)
		(layer "In6.Cu")
	)
	(gr_arc
		(start 70.48754 -55.466742)
		(mid 69.875527 -54.854348)
		(end 69.26326 -55.466488)
		(stroke
			(width 0.2)
			(type default)
		)
		(layer "In6.Cu")
	)
	(gr_line
		(start 70.48754 -28.9941)
		(end 70.48754 -27.876754)
		(stroke
			(width 0.2)
			(type default)
		)
		(layer "In6.Cu")
	)
	(gr_line
		(start 70.48754 -28.98394)
		(end 70.48754 -27.86634)
		(stroke
			(width 0.2)
			(type default)
		)
		(layer "In6.Cu")
	)
	(gr_arc
		(start 70.48754 -27.876754)
		(mid 69.875527 -27.26436)
		(end 69.26326 -27.8765)
		(stroke
			(width 0.2)
			(type default)
		)
		(layer "In6.Cu")
	)
	(gr_arc
		(start 70.48754 -27.86634)
		(mid 69.8754 -27.2542)
		(end 69.26326 -27.86634)
		(stroke
			(width 0.2)
			(type default)
		)
		(layer "In6.Cu")
	)
	(gr_arc
		(start 73.47966 -50.434494)
		(mid 73.9902 -50.945034)
		(end 74.50074 -50.434494)
		(stroke
			(width 0.2)
			(type default)
		)
		(layer "In6.Cu")
	)
	(gr_line
		(start 73.47966 -49.621694)
		(end 73.47966 -50.434494)
		(stroke
			(width 0.2)
			(type default)
		)
		(layer "In6.Cu")
	)
	(gr_arc
		(start 74.41946 -22.834346)
		(mid 74.93 -23.344886)
		(end 75.44054 -22.834346)
		(stroke
			(width 0.2)
			(type default)
		)
		(layer "In6.Cu")
	)
	(gr_line
		(start 74.41946 -22.021546)
		(end 74.41946 -22.834346)
		(stroke
			(width 0.2)
			(type default)
		)
		(layer "In6.Cu")
	)
	(gr_line
		(start 74.50074 -50.434494)
		(end 74.50074 -49.621948)
		(stroke
			(width 0.2)
			(type default)
		)
		(layer "In6.Cu")
	)
	(gr_arc
		(start 74.50074 -49.621948)
		(mid 73.990327 -49.111154)
		(end 73.47966 -49.621694)
		(stroke
			(width 0.2)
			(type default)
		)
		(layer "In6.Cu")
	)
	(gr_line
		(start 75.44054 -22.834346)
		(end 75.44054 -22.0218)
		(stroke
			(width 0.2)
			(type default)
		)
		(layer "In6.Cu")
	)
	(gr_arc
		(start 75.44054 -22.0218)
		(mid 74.930127 -21.511006)
		(end 74.41946 -22.021546)
		(stroke
			(width 0.2)
			(type default)
		)
		(layer "In6.Cu")
	)
	(gr_arc
		(start 76.29906 -34.808922)
		(mid 76.9112 -35.421062)
		(end 77.52334 -34.808922)
		(stroke
			(width 0.2)
			(type default)
		)
		(layer "In6.Cu")
	)
	(gr_line
		(start 76.29906 -33.691322)
		(end 76.29906 -34.808922)
		(stroke
			(width 0.2)
			(type default)
		)
		(layer "In6.Cu")
	)
	(gr_line
		(start 77.52334 -34.808922)
		(end 77.52334 -33.691576)
		(stroke
			(width 0.2)
			(type default)
		)
		(layer "In6.Cu")
	)
	(gr_arc
		(start 77.52334 -33.691576)
		(mid 76.911327 -33.079182)
		(end 76.29906 -33.691322)
		(stroke
			(width 0.2)
			(type default)
		)
		(layer "In6.Cu")
	)
	(gr_line
		(start 77.893672 -35.405568)
		(end 77.893672 -35.196272)
		(stroke
			(width 0.2)
			(type default)
		)
		(layer "In6.Cu")
	)
	(gr_line
		(start 77.893672 -35.196272)
		(end 77.893672 -33.304226)
		(stroke
			(width 0.2)
			(type default)
		)
		(layer "In6.Cu")
	)
	(gr_line
		(start 77.893672 -33.304226)
		(end 78.793848 -33.304226)
		(stroke
			(width 0.2)
			(type default)
		)
		(layer "In6.Cu")
	)
	(gr_line
		(start 78.793848 -33.304226)
		(end 78.83525 -33.304226)
		(stroke
			(width 0.2)
			(type default)
		)
		(layer "In6.Cu")
	)
	(gr_line
		(start 78.83525 -33.304226)
		(end 78.844648 -33.304226)
		(stroke
			(width 0.2)
			(type default)
		)
		(layer "In6.Cu")
	)
	(gr_line
		(start 78.844648 -35.405568)
		(end 77.893672 -35.405568)
		(stroke
			(width 0.2)
			(type default)
		)
		(layer "In6.Cu")
	)
	(gr_line
		(start 78.844648 -35.196272)
		(end 78.844648 -35.405568)
		(stroke
			(width 0.2)
			(type default)
		)
		(layer "In6.Cu")
	)
	(gr_line
		(start 78.844648 -35.167824)
		(end 78.844648 -35.196272)
		(stroke
			(width 0.2)
			(type default)
		)
		(layer "In6.Cu")
	)
	(gr_line
		(start 78.844648 -33.313624)
		(end 78.844648 -35.167824)
		(stroke
			(width 0.2)
			(type default)
		)
		(layer "In6.Cu")
	)
	(gr_line
		(start 78.844648 -33.304226)
		(end 78.844648 -33.313624)
		(stroke
			(width 0.2)
			(type default)
		)
		(layer "In6.Cu")
	)
	(gr_line
		(start 80.503776 -41.221152)
		(end 80.503776 -39.329106)
		(stroke
			(width 0.2)
			(type default)
		)
		(layer "In6.Cu")
	)
	(gr_line
		(start 80.503776 -39.329106)
		(end 82.256376 -39.329106)
		(stroke
			(width 0.2)
			(type default)
		)
		(layer "In6.Cu")
	)
	(gr_line
		(start 80.503776 -38.821106)
		(end 80.503776 -36.92906)
		(stroke
			(width 0.2)
			(type default)
		)
		(layer "In6.Cu")
	)
	(gr_line
		(start 80.503776 -36.92906)
		(end 82.256376 -36.92906)
		(stroke
			(width 0.2)
			(type default)
		)
		(layer "In6.Cu")
	)
	(gr_line
		(start 80.503776 -28.421076)
		(end 80.503776 -26.52903)
		(stroke
			(width 0.2)
			(type default)
		)
		(layer "In6.Cu")
	)
	(gr_line
		(start 80.503776 -26.52903)
		(end 82.256376 -26.52903)
		(stroke
			(width 0.2)
			(type default)
		)
		(layer "In6.Cu")
	)
	(gr_line
		(start 80.503776 -26.02103)
		(end 80.503776 -24.128984)
		(stroke
			(width 0.2)
			(type default)
		)
		(layer "In6.Cu")
	)
	(gr_line
		(start 80.503776 -24.128984)
		(end 82.256376 -24.128984)
		(stroke
			(width 0.2)
			(type default)
		)
		(layer "In6.Cu")
	)
	(gr_line
		(start 80.503776 -23.621238)
		(end 80.503776 -21.729192)
		(stroke
			(width 0.2)
			(type default)
		)
		(layer "In6.Cu")
	)
	(gr_line
		(start 80.503776 -21.729192)
		(end 82.256376 -21.729192)
		(stroke
			(width 0.2)
			(type default)
		)
		(layer "In6.Cu")
	)
	(gr_line
		(start 80.503776 -21.221192)
		(end 80.503776 -19.329146)
		(stroke
			(width 0.2)
			(type default)
		)
		(layer "In6.Cu")
	)
	(gr_line
		(start 80.503776 -19.329146)
		(end 82.256376 -19.329146)
		(stroke
			(width 0.2)
			(type default)
		)
		(layer "In6.Cu")
	)
	(gr_line
		(start 80.503776 -18.821146)
		(end 80.503776 -16.9291)
		(stroke
			(width 0.2)
			(type default)
		)
		(layer "In6.Cu")
	)
	(gr_line
		(start 80.503776 -16.9291)
		(end 82.256376 -16.9291)
		(stroke
			(width 0.2)
			(type default)
		)
		(layer "In6.Cu")
	)
	(gr_line
		(start 80.503776 -16.4211)
		(end 80.503776 -14.529054)
		(stroke
			(width 0.2)
			(type default)
		)
		(layer "In6.Cu")
	)
	(gr_line
		(start 80.503776 -14.529054)
		(end 82.256376 -14.529054)
		(stroke
			(width 0.2)
			(type default)
		)
		(layer "In6.Cu")
	)
	(gr_line
		(start 81.3054 -43.621198)
		(end 81.3054 -43.6118)
		(stroke
			(width 0.2)
			(type default)
		)
		(layer "In6.Cu")
	)
	(gr_line
		(start 81.3054 -43.6118)
		(end 81.3054 -41.7576)
		(stroke
			(width 0.2)
			(type default)
		)
		(layer "In6.Cu")
	)
	(gr_line
		(start 81.3054 -41.7576)
		(end 81.3054 -41.729152)
		(stroke
			(width 0.2)
			(type default)
		)
		(layer "In6.Cu")
	)
	(gr_line
		(start 81.3054 -41.729152)
		(end 81.3562 -41.729152)
		(stroke
			(width 0.2)
			(type default)
		)
		(layer "In6.Cu")
	)
	(gr_line
		(start 81.314798 -43.621198)
		(end 81.3054 -43.621198)
		(stroke
			(width 0.2)
			(type default)
		)
		(layer "In6.Cu")
	)
	(gr_line
		(start 81.3562 -43.621198)
		(end 81.314798 -43.621198)
		(stroke
			(width 0.2)
			(type default)
		)
		(layer "In6.Cu")
	)
	(gr_line
		(start 81.3562 -41.729152)
		(end 82.256376 -41.729152)
		(stroke
			(width 0.2)
			(type default)
		)
		(layer "In6.Cu")
	)
	(gr_arc
		(start 82.228436 -43.075098)
		(mid 82.611976 -43.458638)
		(end 82.995516 -43.075098)
		(stroke
			(width 0.2)
			(type default)
		)
		(layer "In6.Cu")
	)
	(gr_line
		(start 82.228436 -42.274998)
		(end 82.228436 -43.075098)
		(stroke
			(width 0.2)
			(type default)
		)
		(layer "In6.Cu")
	)
	(gr_arc
		(start 82.228436 -40.675052)
		(mid 82.611976 -41.058592)
		(end 82.995516 -40.675052)
		(stroke
			(width 0.2)
			(type default)
		)
		(layer "In6.Cu")
	)
	(gr_line
		(start 82.228436 -39.874952)
		(end 82.228436 -40.675052)
		(stroke
			(width 0.2)
			(type default)
		)
		(layer "In6.Cu")
	)
	(gr_arc
		(start 82.228436 -38.274752)
		(mid 82.611849 -38.658546)
		(end 82.995516 -38.275006)
		(stroke
			(width 0.2)
			(type default)
		)
		(layer "In6.Cu")
	)
	(gr_line
		(start 82.228436 -37.47516)
		(end 82.228436 -38.274752)
		(stroke
			(width 0.2)
			(type default)
		)
		(layer "In6.Cu")
	)
	(gr_arc
		(start 82.228436 -27.874976)
		(mid 82.611976 -28.258516)
		(end 82.995516 -27.874976)
		(stroke
			(width 0.2)
			(type default)
		)
		(layer "In6.Cu")
	)
	(gr_line
		(start 82.228436 -27.07513)
		(end 82.228436 -27.874976)
		(stroke
			(width 0.2)
			(type default)
		)
		(layer "In6.Cu")
	)
	(gr_arc
		(start 82.228436 -25.475184)
		(mid 82.611976 -25.858724)
		(end 82.995516 -25.475184)
		(stroke
			(width 0.2)
			(type default)
		)
		(layer "In6.Cu")
	)
	(gr_line
		(start 82.228436 -24.675084)
		(end 82.228436 -25.475184)
		(stroke
			(width 0.2)
			(type default)
		)
		(layer "In6.Cu")
	)
	(gr_arc
		(start 82.228436 -23.075138)
		(mid 82.611976 -23.458678)
		(end 82.995516 -23.075138)
		(stroke
			(width 0.2)
			(type default)
		)
		(layer "In6.Cu")
	)
	(gr_line
		(start 82.228436 -22.275038)
		(end 82.228436 -23.075138)
		(stroke
			(width 0.2)
			(type default)
		)
		(layer "In6.Cu")
	)
	(gr_arc
		(start 82.228436 -20.674838)
		(mid 82.611849 -21.058632)
		(end 82.995516 -20.675092)
		(stroke
			(width 0.2)
			(type default)
		)
		(layer "In6.Cu")
	)
	(gr_line
		(start 82.228436 -19.874992)
		(end 82.228436 -20.674838)
		(stroke
			(width 0.2)
			(type default)
		)
		(layer "In6.Cu")
	)
	(gr_arc
		(start 82.228436 -18.275046)
		(mid 82.611976 -18.658586)
		(end 82.995516 -18.275046)
		(stroke
			(width 0.2)
			(type default)
		)
		(layer "In6.Cu")
	)
	(gr_line
		(start 82.228436 -17.474946)
		(end 82.228436 -18.275046)
		(stroke
			(width 0.2)
			(type default)
		)
		(layer "In6.Cu")
	)
	(gr_arc
		(start 82.228436 -15.874746)
		(mid 82.611849 -16.25854)
		(end 82.995516 -15.875)
		(stroke
			(width 0.2)
			(type default)
		)
		(layer "In6.Cu")
	)
	(gr_line
		(start 82.228436 -15.075154)
		(end 82.228436 -15.874746)
		(stroke
			(width 0.2)
			(type default)
		)
		(layer "In6.Cu")
	)
	(gr_line
		(start 82.256376 -43.621198)
		(end 81.3562 -43.621198)
		(stroke
			(width 0.2)
			(type default)
		)
		(layer "In6.Cu")
	)
	(gr_line
		(start 82.256376 -41.729152)
		(end 82.256376 -43.621198)
		(stroke
			(width 0.2)
			(type default)
		)
		(layer "In6.Cu")
	)
	(gr_line
		(start 82.256376 -41.221152)
		(end 80.503776 -41.221152)
		(stroke
			(width 0.2)
			(type default)
		)
		(layer "In6.Cu")
	)
	(gr_line
		(start 82.256376 -39.329106)
		(end 82.256376 -41.221152)
		(stroke
			(width 0.2)
			(type default)
		)
		(layer "In6.Cu")
	)
	(gr_line
		(start 82.256376 -38.821106)
		(end 80.503776 -38.821106)
		(stroke
			(width 0.2)
			(type default)
		)
		(layer "In6.Cu")
	)
	(gr_line
		(start 82.256376 -36.92906)
		(end 82.256376 -38.821106)
		(stroke
			(width 0.2)
			(type default)
		)
		(layer "In6.Cu")
	)
	(gr_line
		(start 82.256376 -28.421076)
		(end 80.503776 -28.421076)
		(stroke
			(width 0.2)
			(type default)
		)
		(layer "In6.Cu")
	)
	(gr_line
		(start 82.256376 -26.52903)
		(end 82.256376 -28.421076)
		(stroke
			(width 0.2)
			(type default)
		)
		(layer "In6.Cu")
	)
	(gr_line
		(start 82.256376 -26.02103)
		(end 80.503776 -26.02103)
		(stroke
			(width 0.2)
			(type default)
		)
		(layer "In6.Cu")
	)
	(gr_line
		(start 82.256376 -24.128984)
		(end 82.256376 -26.02103)
		(stroke
			(width 0.2)
			(type default)
		)
		(layer "In6.Cu")
	)
	(gr_line
		(start 82.256376 -23.621238)
		(end 80.503776 -23.621238)
		(stroke
			(width 0.2)
			(type default)
		)
		(layer "In6.Cu")
	)
	(gr_line
		(start 82.256376 -21.729192)
		(end 82.256376 -23.621238)
		(stroke
			(width 0.2)
			(type default)
		)
		(layer "In6.Cu")
	)
	(gr_line
		(start 82.256376 -21.221192)
		(end 80.503776 -21.221192)
		(stroke
			(width 0.2)
			(type default)
		)
		(layer "In6.Cu")
	)
	(gr_line
		(start 82.256376 -19.329146)
		(end 82.256376 -21.221192)
		(stroke
			(width 0.2)
			(type default)
		)
		(layer "In6.Cu")
	)
	(gr_line
		(start 82.256376 -18.821146)
		(end 80.503776 -18.821146)
		(stroke
			(width 0.2)
			(type default)
		)
		(layer "In6.Cu")
	)
	(gr_line
		(start 82.256376 -16.9291)
		(end 82.256376 -18.821146)
		(stroke
			(width 0.2)
			(type default)
		)
		(layer "In6.Cu")
	)
	(gr_line
		(start 82.256376 -16.4211)
		(end 80.503776 -16.4211)
		(stroke
			(width 0.2)
			(type default)
		)
		(layer "In6.Cu")
	)
	(gr_line
		(start 82.256376 -14.529054)
		(end 82.256376 -16.4211)
		(stroke
			(width 0.2)
			(type default)
		)
		(layer "In6.Cu")
	)
	(gr_line
		(start 82.995516 -43.075098)
		(end 82.995516 -42.275252)
		(stroke
			(width 0.2)
			(type default)
		)
		(layer "In6.Cu")
	)
	(gr_arc
		(start 82.995516 -42.275252)
		(mid 82.612103 -41.891458)
		(end 82.228436 -42.274998)
		(stroke
			(width 0.2)
			(type default)
		)
		(layer "In6.Cu")
	)
	(gr_line
		(start 82.995516 -40.675052)
		(end 82.995516 -39.875206)
		(stroke
			(width 0.2)
			(type default)
		)
		(layer "In6.Cu")
	)
	(gr_arc
		(start 82.995516 -39.875206)
		(mid 82.612103 -39.491412)
		(end 82.228436 -39.874952)
		(stroke
			(width 0.2)
			(type default)
		)
		(layer "In6.Cu")
	)
	(gr_line
		(start 82.995516 -38.275006)
		(end 82.995516 -37.47516)
		(stroke
			(width 0.2)
			(type default)
		)
		(layer "In6.Cu")
	)
	(gr_arc
		(start 82.995516 -37.47516)
		(mid 82.611976 -37.09162)
		(end 82.228436 -37.47516)
		(stroke
			(width 0.2)
			(type default)
		)
		(layer "In6.Cu")
	)
	(gr_line
		(start 82.995516 -27.874976)
		(end 82.995516 -27.075384)
		(stroke
			(width 0.2)
			(type default)
		)
		(layer "In6.Cu")
	)
	(gr_arc
		(start 82.995516 -27.075384)
		(mid 82.612103 -26.69159)
		(end 82.228436 -27.07513)
		(stroke
			(width 0.2)
			(type default)
		)
		(layer "In6.Cu")
	)
	(gr_line
		(start 82.995516 -25.475184)
		(end 82.995516 -24.675338)
		(stroke
			(width 0.2)
			(type default)
		)
		(layer "In6.Cu")
	)
	(gr_arc
		(start 82.995516 -24.675338)
		(mid 82.612103 -24.291544)
		(end 82.228436 -24.675084)
		(stroke
			(width 0.2)
			(type default)
		)
		(layer "In6.Cu")
	)
	(gr_line
		(start 82.995516 -23.075138)
		(end 82.995516 -22.275292)
		(stroke
			(width 0.2)
			(type default)
		)
		(layer "In6.Cu")
	)
	(gr_arc
		(start 82.995516 -22.275292)
		(mid 82.612103 -21.891498)
		(end 82.228436 -22.275038)
		(stroke
			(width 0.2)
			(type default)
		)
		(layer "In6.Cu")
	)
	(gr_line
		(start 82.995516 -20.675092)
		(end 82.995516 -19.874992)
		(stroke
			(width 0.2)
			(type default)
		)
		(layer "In6.Cu")
	)
	(gr_arc
		(start 82.995516 -19.874992)
		(mid 82.611976 -19.491452)
		(end 82.228436 -19.874992)
		(stroke
			(width 0.2)
			(type default)
		)
		(layer "In6.Cu")
	)
	(gr_line
		(start 82.995516 -18.275046)
		(end 82.995516 -17.4752)
		(stroke
			(width 0.2)
			(type default)
		)
		(layer "In6.Cu")
	)
	(gr_arc
		(start 82.995516 -17.4752)
		(mid 82.612103 -17.091406)
		(end 82.228436 -17.474946)
		(stroke
			(width 0.2)
			(type default)
		)
		(layer "In6.Cu")
	)
	(gr_line
		(start 82.995516 -15.875)
		(end 82.995516 -15.075154)
		(stroke
			(width 0.2)
			(type default)
		)
		(layer "In6.Cu")
	)
	(gr_arc
		(start 82.995516 -15.075154)
		(mid 82.611976 -14.691614)
		(end 82.228436 -15.075154)
		(stroke
			(width 0.2)
			(type default)
		)
		(layer "In6.Cu")
	)
	(gr_line
		(start 0 -90.309954)
		(end 0 -69.550026)
		(stroke
			(width 0.05)
			(type default)
		)
		(layer "Edge.Cuts")
	)
	(gr_arc
		(start 0 -90.309954)
		(mid 0.585785 -91.724165)
		(end 1.999996 -92.30995)
		(stroke
			(width 0.05)
			(type default)
		)
		(layer "Edge.Cuts")
	)
	(gr_arc
		(start 1.999996 -67.55003)
		(mid 0.585785 -68.135815)
		(end 0 -69.550026)
		(stroke
			(width 0.05)
			(type default)
		)
		(layer "Edge.Cuts")
	)
	(gr_line
		(start 1.999996 -67.55003)
		(end 52.850034 -67.55003)
		(stroke
			(width 0.05)
			(type default)
		)
		(layer "Edge.Cuts")
	)
	(gr_arc
		(start 6.500114 -82.084926)
		(mid 8.275066 -80.309974)
		(end 6.500114 -78.535022)
		(stroke
			(width 0.05)
			(type default)
		)
		(layer "Edge.Cuts")
	)
	(gr_arc
		(start 6.500114 -78.535022)
		(mid 4.725162 -80.309974)
		(end 6.500114 -82.084926)
		(stroke
			(width 0.05)
			(type default)
		)
		(layer "Edge.Cuts")
	)
	(gr_arc
		(start 52.850034 -67.55003)
		(mid 54.264245 -66.964245)
		(end 54.85003 -65.550034)
		(stroke
			(width 0.05)
			(type default)
		)
		(layer "Edge.Cuts")
	)
	(gr_line
		(start 54.85003 -65.550034)
		(end 54.85003 -1.999996)
		(stroke
			(width 0.05)
			(type default)
		)
		(layer "Edge.Cuts")
	)
	(gr_arc
		(start 56.850026 0)
		(mid 55.435797 -0.585776)
		(end 54.85003 -1.999996)
		(stroke
			(width 0.05)
			(type default)
		)
		(layer "Edge.Cuts")
	)
	(gr_line
		(start 56.850026 0)
		(end 88.250014 0)
		(stroke
			(width 0.05)
			(type default)
		)
		(layer "Edge.Cuts")
	)
	(gr_arc
		(start 60.200032 -6.27507)
		(mid 61.974984 -4.500118)
		(end 60.200032 -2.724912)
		(stroke
			(width 0.05)
			(type default)
		)
		(layer "Edge.Cuts")
	)
	(gr_arc
		(start 60.200032 -2.724912)
		(mid 58.424826 -4.500118)
		(end 60.200032 -6.27507)
		(stroke
			(width 0.05)
			(type default)
		)
		(layer "Edge.Cuts")
	)
	(gr_arc
		(start 73.000108 -89.585038)
		(mid 74.77506 -87.810086)
		(end 73.000108 -86.03488)
		(stroke
			(width 0.05)
			(type default)
		)
		(layer "Edge.Cuts")
	)
	(gr_arc
		(start 73.000108 -86.03488)
		(mid 71.224902 -87.810086)
		(end 73.000108 -89.585038)
		(stroke
			(width 0.05)
			(type default)
		)
		(layer "Edge.Cuts")
	)
	(gr_arc
		(start 81.049876 -48.764952)
		(mid 81.19636 -49.118594)
		(end 81.550002 -49.265078)
		(stroke
			(width 0.05)
			(type default)
		)
		(layer "Edge.Cuts")
	)
	(gr_line
		(start 81.049876 -44.515024)
		(end 81.049876 -48.764952)
		(stroke
			(width 0.05)
			(type default)
		)
		(layer "Edge.Cuts")
	)
	(gr_arc
		(start 81.049876 -10.685018)
		(mid 81.196449 -11.038496)
		(end 81.550002 -11.18489)
		(stroke
			(width 0.05)
			(type default)
		)
		(layer "Edge.Cuts")
	)
	(gr_line
		(start 81.049876 -6.43509)
		(end 81.049876 -10.685018)
		(stroke
			(width 0.05)
			(type default)
		)
		(layer "Edge.Cuts")
	)
	(gr_line
		(start 81.550002 -49.265078)
		(end 88.250014 -49.265078)
		(stroke
			(width 0.05)
			(type default)
		)
		(layer "Edge.Cuts")
	)
	(gr_arc
		(start 81.550002 -44.014898)
		(mid 81.19636 -44.161382)
		(end 81.049876 -44.515024)
		(stroke
			(width 0.05)
			(type default)
		)
		(layer "Edge.Cuts")
	)
	(gr_line
		(start 81.550002 -11.18489)
		(end 82.849974 -11.18489)
		(stroke
			(width 0.05)
			(type default)
		)
		(layer "Edge.Cuts")
	)
	(gr_arc
		(start 81.550002 -5.934964)
		(mid 81.19636 -6.081448)
		(end 81.049876 -6.43509)
		(stroke
			(width 0.05)
			(type default)
		)
		(layer "Edge.Cuts")
	)
	(gr_line
		(start 82.849974 -44.014898)
		(end 81.550002 -44.014898)
		(stroke
			(width 0.05)
			(type default)
		)
		(layer "Edge.Cuts")
	)
	(gr_arc
		(start 82.849974 -44.014898)
		(mid 83.203534 -43.868512)
		(end 83.3501 -43.515026)
		(stroke
			(width 0.05)
			(type default)
		)
		(layer "Edge.Cuts")
	)
	(gr_arc
		(start 83.3501 -11.685016)
		(mid 83.203621 -11.331372)
		(end 82.849974 -11.18489)
		(stroke
			(width 0.05)
			(type default)
		)
		(layer "Edge.Cuts")
	)
	(gr_line
		(start 83.3501 -11.685016)
		(end 83.3501 -43.515026)
		(stroke
			(width 0.05)
			(type default)
		)
		(layer "Edge.Cuts")
	)
	(gr_arc
		(start 85.749892 -69.810122)
		(mid 85.896465 -70.1636)
		(end 86.250018 -70.309994)
		(stroke
			(width 0.05)
			(type default)
		)
		(layer "Edge.Cuts")
	)
	(gr_line
		(start 85.749892 -55.770018)
		(end 85.749892 -69.810122)
		(stroke
			(width 0.05)
			(type default)
		)
		(layer "Edge.Cuts")
	)
	(gr_line
		(start 86.250018 -70.309994)
		(end 88.250014 -70.309994)
		(stroke
			(width 0.05)
			(type default)
		)
		(layer "Edge.Cuts")
	)
	(gr_arc
		(start 86.250018 -55.269892)
		(mid 85.896376 -55.416376)
		(end 85.749892 -55.770018)
		(stroke
			(width 0.05)
			(type default)
		)
		(layer "Edge.Cuts")
	)
	(gr_line
		(start 86.74989 -92.30995)
		(end 1.999996 -92.30995)
		(stroke
			(width 0.05)
			(type default)
		)
		(layer "Edge.Cuts")
	)
	(gr_arc
		(start 86.74989 -92.30995)
		(mid 88.164091 -91.724165)
		(end 88.749886 -90.309954)
		(stroke
			(width 0.05)
			(type default)
		)
		(layer "Edge.Cuts")
	)
	(gr_line
		(start 88.250014 -55.269892)
		(end 86.250018 -55.269892)
		(stroke
			(width 0.05)
			(type default)
		)
		(layer "Edge.Cuts")
	)
	(gr_arc
		(start 88.250014 -55.269892)
		(mid 88.603475 -55.123479)
		(end 88.749886 -54.77002)
		(stroke
			(width 0.05)
			(type default)
		)
		(layer "Edge.Cuts")
	)
	(gr_line
		(start 88.250014 -5.934964)
		(end 81.550002 -5.934964)
		(stroke
			(width 0.05)
			(type default)
		)
		(layer "Edge.Cuts")
	)
	(gr_arc
		(start 88.250014 -5.934964)
		(mid 88.603465 -5.788549)
		(end 88.749886 -5.435092)
		(stroke
			(width 0.05)
			(type default)
		)
		(layer "Edge.Cuts")
	)
	(gr_arc
		(start 88.749886 -70.81012)
		(mid 88.603556 -70.45651)
		(end 88.250014 -70.309994)
		(stroke
			(width 0.05)
			(type default)
		)
		(layer "Edge.Cuts")
	)
	(gr_line
		(start 88.749886 -70.81012)
		(end 88.749886 -90.309954)
		(stroke
			(width 0.05)
			(type default)
		)
		(layer "Edge.Cuts")
	)
	(gr_arc
		(start 88.749886 -49.76495)
		(mid 88.603495 -49.41145)
		(end 88.250014 -49.265078)
		(stroke
			(width 0.05)
			(type default)
		)
		(layer "Edge.Cuts")
	)
	(gr_line
		(start 88.749886 -49.76495)
		(end 88.749886 -54.77002)
		(stroke
			(width 0.05)
			(type default)
		)
		(layer "Edge.Cuts")
	)
	(gr_arc
		(start 88.749886 -0.500126)
		(mid 88.603558 -0.146512)
		(end 88.250014 0)
		(stroke
			(width 0.05)
			(type default)
		)
		(layer "Edge.Cuts")
	)
	(gr_line
		(start 88.749886 -0.500126)
		(end 88.749886 -5.435092)
		(stroke
			(width 0.05)
			(type default)
		)
		(layer "Edge.Cuts")
	)
	(segment
		(start 31.115 -72.517)
		(end 30.6705 -72.0725)
		(width 0.12065)
		(layer "F.Cu")
		(net "Z50_SSD_B1_SMB_DATA_LR")
	)
	(segment
		(start 31.115 -72.517)
		(end 31.384748 -72.786748)
		(width 0.12065)
		(layer "F.Cu")
		(net "Z50_SSD_B1_SMB_DATA_LR")
	)
	(segment
		(start 31.384748 -72.786748)
		(end 31.384748 -74.062082)
		(width 0.12065)
		(layer "F.Cu")
		(net "Z50_SSD_B1_SMB_DATA_LR")
	)
	(segment
		(start 31.384748 -74.062082)
		(end 31.2674 -74.17943)
		(width 0.12065)
		(layer "F.Cu")
		(net "Z50_SSD_B1_SMB_DATA_LR")
	)
	(segment
		(start 30.6705 -72.0725)
		(end 30.226 -72.0725)
		(width 0.12065)
		(layer "F.Cu")
		(net "Z50_SSD_B1_SMB_DATA_LR")
	)
	(via
		(at 31.115 -72.517)
		(size 0.7112)
		(drill 0.3556)
		(layers "F.Cu" "B.Cu")
		(net "Z50_SSD_B1_SMB_DATA_LR")
	)
	(segment
		(start 31.2674 -75.68057)
		(end 31.2674 -75.9714)
		(width 0.12065)
		(layer "F.Cu")
		(net "Z50_SSD_B1_SMB_DATA_LL")
	)
	(segment
		(start 32.639 -78.0415)
		(end 32.385 -78.2955)
		(width 0.12065)
		(layer "F.Cu")
		(net "Z50_SSD_B1_SMB_DATA_LL")
	)
	(segment
		(start 32.639 -77.343)
		(end 32.639 -78.0415)
		(width 0.12065)
		(layer "F.Cu")
		(net "Z50_SSD_B1_SMB_DATA_LL")
	)
	(segment
		(start 31.2674 -75.9714)
		(end 32.639 -77.343)
		(width 0.12065)
		(layer "F.Cu")
		(net "Z50_SSD_B1_SMB_DATA_LL")
	)
	(via
		(at 32.639 -77.343)
		(size 0.7112)
		(drill 0.3556)
		(layers "F.Cu" "B.Cu")
		(net "Z50_SSD_B1_SMB_DATA_LL")
	)
	(segment
		(start 29.083 -72.4535)
		(end 29.429202 -72.4535)
		(width 0.12065)
		(layer "F.Cu")
		(net "Z50_SSD_B1_SMB_CLK_LR")
	)
	(segment
		(start 29.429202 -72.4535)
		(end 29.949902 -72.9742)
		(width 0.12065)
		(layer "F.Cu")
		(net "Z50_SSD_B1_SMB_CLK_LR")
	)
	(segment
		(start 29.949902 -72.9742)
		(end 29.949902 -73.160128)
		(width 0.12065)
		(layer "F.Cu")
		(net "Z50_SSD_B1_SMB_CLK_LR")
	)
	(segment
		(start 29.949902 -73.160128)
		(end 28.9306 -74.17943)
		(width 0.12065)
		(layer "F.Cu")
		(net "Z50_SSD_B1_SMB_CLK_LR")
	)
	(via
		(at 29.949902 -72.9742)
		(size 0.7112)
		(drill 0.3556)
		(layers "F.Cu" "B.Cu")
		(net "Z50_SSD_B1_SMB_CLK_LR")
	)
	(segment
		(start 30.81528 -77.018896)
		(end 29.476954 -75.68057)
		(width 0.12065)
		(layer "F.Cu")
		(net "Z50_SSD_B1_SMB_CLK_LL")
	)
	(segment
		(start 29.476954 -75.68057)
		(end 28.9306 -75.68057)
		(width 0.12065)
		(layer "F.Cu")
		(net "Z50_SSD_B1_SMB_CLK_LL")
	)
	(segment
		(start 31.369 -77.3938)
		(end 30.994096 -77.018896)
		(width 0.12065)
		(layer "F.Cu")
		(net "Z50_SSD_B1_SMB_CLK_LL")
	)
	(segment
		(start 31.369 -77.3938)
		(end 31.369 -78.2955)
		(width 0.12065)
		(layer "F.Cu")
		(net "Z50_SSD_B1_SMB_CLK_LL")
	)
	(segment
		(start 30.994096 -77.018896)
		(end 30.81528 -77.018896)
		(width 0.12065)
		(layer "F.Cu")
		(net "Z50_SSD_B1_SMB_CLK_LL")
	)
	(via
		(at 31.369 -77.3938)
		(size 0.7112)
		(drill 0.3556)
		(layers "F.Cu" "B.Cu")
		(net "Z50_SSD_B1_SMB_CLK_LL")
	)
	(segment
		(start 24.13 -73.2155)
		(end 24.13 -73.406)
		(width 0.12065)
		(layer "F.Cu")
		(net "Z50_SSD_A1_SMB_DATA_LR")
	)
	(segment
		(start 24.13 -73.406)
		(end 24.13 -73.62317)
		(width 0.12065)
		(layer "F.Cu")
		(net "Z50_SSD_A1_SMB_DATA_LR")
	)
	(segment
		(start 25.146 -72.1995)
		(end 24.13 -73.2155)
		(width 0.12065)
		(layer "F.Cu")
		(net "Z50_SSD_A1_SMB_DATA_LR")
	)
	(segment
		(start 24.13 -73.62317)
		(end 25.15743 -74.6506)
		(width 0.12065)
		(layer "F.Cu")
		(net "Z50_SSD_A1_SMB_DATA_LR")
	)
	(via
		(at 24.13 -73.406)
		(size 0.7112)
		(drill 0.3556)
		(layers "F.Cu" "B.Cu")
		(net "Z50_SSD_A1_SMB_DATA_LR")
	)
	(segment
		(start 27.219148 -76.368148)
		(end 26.65857 -75.80757)
		(width 0.12065)
		(layer "F.Cu")
		(net "Z50_SSD_A1_SMB_DATA_LL")
	)
	(segment
		(start 28.6385 -78.2955)
		(end 28.067 -77.724)
		(width 0.12065)
		(layer "F.Cu")
		(net "Z50_SSD_A1_SMB_DATA_LL")
	)
	(segment
		(start 27.68854 -76.368148)
		(end 27.219148 -76.368148)
		(width 0.12065)
		(layer "F.Cu")
		(net "Z50_SSD_A1_SMB_DATA_LL")
	)
	(segment
		(start 26.65857 -75.80757)
		(end 26.65857 -74.6506)
		(width 0.12065)
		(layer "F.Cu")
		(net "Z50_SSD_A1_SMB_DATA_LL")
	)
	(segment
		(start 29.21 -78.2955)
		(end 28.6385 -78.2955)
		(width 0.12065)
		(layer "F.Cu")
		(net "Z50_SSD_A1_SMB_DATA_LL")
	)
	(segment
		(start 28.067 -77.724)
		(end 28.067 -76.746608)
		(width 0.12065)
		(layer "F.Cu")
		(net "Z50_SSD_A1_SMB_DATA_LL")
	)
	(segment
		(start 28.067 -76.746608)
		(end 27.68854 -76.368148)
		(width 0.12065)
		(layer "F.Cu")
		(net "Z50_SSD_A1_SMB_DATA_LL")
	)
	(via
		(at 28.067 -77.724)
		(size 0.7112)
		(drill 0.3556)
		(layers "F.Cu" "B.Cu")
		(net "Z50_SSD_A1_SMB_DATA_LL")
	)
	(segment
		(start 24.13 -76.059792)
		(end 24.003 -76.186792)
		(width 0.12065)
		(layer "F.Cu")
		(net "Z50_SSD_A1_SMB_CLK_LR")
	)
	(segment
		(start 23.409148 -72.920352)
		(end 23.409148 -73.70445)
		(width 0.12065)
		(layer "F.Cu")
		(net "Z50_SSD_A1_SMB_CLK_LR")
	)
	(segment
		(start 23.409148 -73.70445)
		(end 24.13 -74.425302)
		(width 0.12065)
		(layer "F.Cu")
		(net "Z50_SSD_A1_SMB_CLK_LR")
	)
	(segment
		(start 24.13 -74.425302)
		(end 24.13 -76.059792)
		(width 0.12065)
		(layer "F.Cu")
		(net "Z50_SSD_A1_SMB_CLK_LR")
	)
	(segment
		(start 24.003 -76.186792)
		(end 24.003 -76.9874)
		(width 0.12065)
		(layer "F.Cu")
		(net "Z50_SSD_A1_SMB_CLK_LR")
	)
	(segment
		(start 24.13 -72.1995)
		(end 23.409148 -72.920352)
		(width 0.12065)
		(layer "F.Cu")
		(net "Z50_SSD_A1_SMB_CLK_LR")
	)
	(segment
		(start 25.15743 -76.9874)
		(end 24.003 -76.9874)
		(width 0.12065)
		(layer "F.Cu")
		(net "Z50_SSD_A1_SMB_CLK_LR")
	)
	(via
		(at 24.003 -76.9874)
		(size 0.7112)
		(drill 0.3556)
		(layers "F.Cu" "B.Cu")
		(net "Z50_SSD_A1_SMB_CLK_LR")
	)
	(segment
		(start 27.432 -76.9874)
		(end 26.65857 -76.9874)
		(width 0.12065)
		(layer "F.Cu")
		(net "Z50_SSD_A1_SMB_CLK_LL")
	)
	(segment
		(start 30.226 -78.2955)
		(end 30.226 -77.47)
		(width 0.12065)
		(layer "F.Cu")
		(net "Z50_SSD_A1_SMB_CLK_LL")
	)
	(via
		(at 28.575 -76.708)
		(size 0.7112)
		(drill 0.3556)
		(layers "F.Cu" "B.Cu")
		(net "Z50_SSD_A1_SMB_CLK_LL")
	)
	(via
		(at 27.432 -76.9874)
		(size 0.508)
		(drill 0.254)
		(layers "F.Cu" "B.Cu")
		(net "Z50_SSD_A1_SMB_CLK_LL")
	)
	(via
		(at 30.226 -77.47)
		(size 0.508)
		(drill 0.254)
		(layers "F.Cu" "B.Cu")
		(net "Z50_SSD_A1_SMB_CLK_LL")
	)
	(segment
		(start 28.575 -76.708)
		(end 29.464 -76.708)
		(width 0.12065)
		(layer "B.Cu")
		(net "Z50_SSD_A1_SMB_CLK_LL")
	)
	(segment
		(start 29.464 -76.708)
		(end 30.226 -77.47)
		(width 0.12065)
		(layer "B.Cu")
		(net "Z50_SSD_A1_SMB_CLK_LL")
	)
	(segment
		(start 27.432 -76.9874)
		(end 27.7114 -76.708)
		(width 0.12065)
		(layer "B.Cu")
		(net "Z50_SSD_A1_SMB_CLK_LL")
	)
	(segment
		(start 27.7114 -76.708)
		(end 28.575 -76.708)
		(width 0.12065)
		(layer "B.Cu")
		(net "Z50_SSD_A1_SMB_CLK_LL")
	)
	(segment
		(start 32.004 -72.898)
		(end 32.216852 -73.110852)
		(width 0.12065)
		(layer "F.Cu")
		(net "SSD_B1_SMB_OE")
	)
	(segment
		(start 31.946342 -74.67981)
		(end 31.2674 -74.67981)
		(width 0.12065)
		(layer "F.Cu")
		(net "SSD_B1_SMB_OE")
	)
	(segment
		(start 32.216852 -74.4093)
		(end 31.946342 -74.67981)
		(width 0.12065)
		(layer "F.Cu")
		(net "SSD_B1_SMB_OE")
	)
	(segment
		(start 32.216852 -73.110852)
		(end 32.216852 -74.4093)
		(width 0.12065)
		(layer "F.Cu")
		(net "SSD_B1_SMB_OE")
	)
	(via
		(at 31.115 -75.3364)
		(size 0.7112)
		(drill 0.3556)
		(layers "F.Cu" "B.Cu")
		(net "SSD_B1_SMB_OE")
	)
	(via
		(at 32.004 -72.898)
		(size 0.508)
		(drill 0.254)
		(layers "F.Cu" "B.Cu")
		(net "SSD_B1_SMB_OE")
	)
	(segment
		(start 32.004 -73.064116)
		(end 32.004 -72.898)
		(width 0.12065)
		(layer "B.Cu")
		(net "SSD_B1_SMB_OE")
	)
	(segment
		(start 31.3055 -74.422)
		(end 31.3055 -74.39152)
		(width 0.12065)
		(layer "B.Cu")
		(net "SSD_B1_SMB_OE")
	)
	(segment
		(start 31.3055 -74.422)
		(end 31.3055 -75.1459)
		(width 0.12065)
		(layer "B.Cu")
		(net "SSD_B1_SMB_OE")
	)
	(segment
		(start 31.556452 -74.140568)
		(end 31.556452 -73.511664)
		(width 0.12065)
		(layer "B.Cu")
		(net "SSD_B1_SMB_OE")
	)
	(segment
		(start 31.556452 -73.511664)
		(end 32.004 -73.064116)
		(width 0.12065)
		(layer "B.Cu")
		(net "SSD_B1_SMB_OE")
	)
	(segment
		(start 31.3055 -75.1459)
		(end 31.115 -75.3364)
		(width 0.12065)
		(layer "B.Cu")
		(net "SSD_B1_SMB_OE")
	)
	(segment
		(start 31.3055 -74.39152)
		(end 31.556452 -74.140568)
		(width 0.12065)
		(layer "B.Cu")
		(net "SSD_B1_SMB_OE")
	)
	(segment
		(start 25.65781 -73.53681)
		(end 25.4 -73.279)
		(width 0.12065)
		(layer "F.Cu")
		(net "SSD_A1_SMB_OE")
	)
	(segment
		(start 25.65781 -74.6506)
		(end 25.65781 -73.53681)
		(width 0.12065)
		(layer "F.Cu")
		(net "SSD_A1_SMB_OE")
	)
	(via
		(at 24.4856 -74.2315)
		(size 0.7112)
		(drill 0.3556)
		(layers "F.Cu" "B.Cu")
		(net "SSD_A1_SMB_OE")
	)
	(via
		(at 25.4 -73.279)
		(size 0.508)
		(drill 0.254)
		(layers "F.Cu" "B.Cu")
		(net "SSD_A1_SMB_OE")
	)
	(segment
		(start 25.4 -74.2315)
		(end 25.4 -73.279)
		(width 0.12065)
		(layer "B.Cu")
		(net "SSD_A1_SMB_OE")
	)
	(segment
		(start 25.4 -74.2315)
		(end 24.4856 -74.2315)
		(width 0.12065)
		(layer "B.Cu")
		(net "SSD_A1_SMB_OE")
	)
	(segment
		(start 66.411094 -21.939758)
		(end 66.802 -21.548852)
		(width 0.12065)
		(layer "F.Cu")
		(net "SSD_B1_MFG_DATA_TP")
	)
	(segment
		(start 65.174876 -21.939758)
		(end 66.411094 -21.939758)
		(width 0.12065)
		(layer "F.Cu")
		(net "SSD_B1_MFG_DATA_TP")
	)
	(via
		(at 66.802 -21.548852)
		(size 0.508)
		(drill 0.254)
		(layers "F.Cu" "B.Cu")
		(net "SSD_B1_MFG_DATA_TP")
	)
	(segment
		(start 66.167 -20.913852)
		(end 66.802 -21.548852)
		(width 0.12065)
		(layer "B.Cu")
		(net "SSD_B1_MFG_DATA_TP")
	)
	(segment
		(start 65.913 -20.913852)
		(end 66.167 -20.913852)
		(width 0.12065)
		(layer "B.Cu")
		(net "SSD_B1_MFG_DATA_TP")
	)
	(segment
		(start 65.174876 -21.439886)
		(end 65.95491 -20.659852)
		(width 0.12065)
		(layer "F.Cu")
		(net "SSD_B1_MFG_CLK_TP")
	)
	(segment
		(start 65.95491 -20.659852)
		(end 66.802 -20.659852)
		(width 0.12065)
		(layer "F.Cu")
		(net "SSD_B1_MFG_CLK_TP")
	)
	(via
		(at 66.802 -20.659852)
		(size 0.508)
		(drill 0.254)
		(layers "F.Cu" "B.Cu")
		(net "SSD_B1_MFG_CLK_TP")
	)
	(segment
		(start 66.802 -20.659852)
		(end 66.512948 -20.3708)
		(width 0.12065)
		(layer "B.Cu")
		(net "SSD_B1_MFG_CLK_TP")
	)
	(segment
		(start 64.551052 -20.3708)
		(end 64.008 -20.913852)
		(width 0.12065)
		(layer "B.Cu")
		(net "SSD_B1_MFG_CLK_TP")
	)
	(segment
		(start 66.512948 -20.3708)
		(end 64.551052 -20.3708)
		(width 0.12065)
		(layer "B.Cu")
		(net "SSD_B1_MFG_CLK_TP")
	)
	(segment
		(start 66.411094 -49.539906)
		(end 66.802 -49.149)
		(width 0.12065)
		(layer "F.Cu")
		(net "SSD_A1_MFG_DATA_TP")
	)
	(segment
		(start 65.174876 -49.539906)
		(end 66.411094 -49.539906)
		(width 0.12065)
		(layer "F.Cu")
		(net "SSD_A1_MFG_DATA_TP")
	)
	(via
		(at 66.802 -49.149)
		(size 0.508)
		(drill 0.254)
		(layers "F.Cu" "B.Cu")
		(net "SSD_A1_MFG_DATA_TP")
	)
	(segment
		(start 66.167 -48.514)
		(end 66.802 -49.149)
		(width 0.12065)
		(layer "B.Cu")
		(net "SSD_A1_MFG_DATA_TP")
	)
	(segment
		(start 65.913 -48.514)
		(end 66.167 -48.514)
		(width 0.12065)
		(layer "B.Cu")
		(net "SSD_A1_MFG_DATA_TP")
	)
	(segment
		(start 65.174876 -49.040034)
		(end 65.95491 -48.26)
		(width 0.12065)
		(layer "F.Cu")
		(net "SSD_A1_MFG_CLK_TP")
	)
	(segment
		(start 65.95491 -48.26)
		(end 66.802 -48.26)
		(width 0.12065)
		(layer "F.Cu")
		(net "SSD_A1_MFG_CLK_TP")
	)
	(via
		(at 66.802 -48.26)
		(size 0.508)
		(drill 0.254)
		(layers "F.Cu" "B.Cu")
		(net "SSD_A1_MFG_CLK_TP")
	)
	(segment
		(start 66.512948 -47.970948)
		(end 66.802 -48.26)
		(width 0.12065)
		(layer "B.Cu")
		(net "SSD_A1_MFG_CLK_TP")
	)
	(segment
		(start 64.551052 -47.970948)
		(end 66.512948 -47.970948)
		(width 0.12065)
		(layer "B.Cu")
		(net "SSD_A1_MFG_CLK_TP")
	)
	(segment
		(start 64.008 -48.514)
		(end 64.551052 -47.970948)
		(width 0.12065)
		(layer "B.Cu")
		(net "SSD_A1_MFG_CLK_TP")
	)
	(segment
		(start 74.676 -31.496)
		(end 75.438 -31.496)
		(width 0.508)
		(layer "F.Cu")
		(net "P3V3_DPB")
	)
	(segment
		(start 60.458604 -38.735)
		(end 60.198 -38.735)
		(width 0.508)
		(layer "F.Cu")
		(net "P3V3_DPB")
	)
	(segment
		(start 60.5155 -41.7195)
		(end 61.0108 -41.2242)
		(width 0.508)
		(layer "F.Cu")
		(net "P3V3_DPB")
	)
	(segment
		(start 58.039254 -52.438046)
		(end 57.277 -53.2003)
		(width 0.508)
		(layer "F.Cu")
		(net "P3V3_DPB")
	)
	(segment
		(start 61.0108 -41.2242)
		(end 61.0108 -39.287196)
		(width 0.508)
		(layer "F.Cu")
		(net "P3V3_DPB")
	)
	(segment
		(start 33.02 -74.9935)
		(end 33.02 -75.819)
		(width 0.508)
		(layer "F.Cu")
		(net "P3V3_DPB")
	)
	(segment
		(start 26.958798 -72.644)
		(end 26.514298 -72.1995)
		(width 0.508)
		(layer "F.Cu")
		(net "P3V3_DPB")
	)
	(segment
		(start 33.0073 -70.358)
		(end 32.639 -70.7263)
		(width 0.508)
		(layer "F.Cu")
		(net "P3V3_DPB")
	)
	(segment
		(start 32.639 -70.7263)
		(end 32.639 -71.755)
		(width 0.508)
		(layer "F.Cu")
		(net "P3V3_DPB")
	)
	(segment
		(start 60.198 -41.7195)
		(end 60.5155 -41.7195)
		(width 0.508)
		(layer "F.Cu")
		(net "P3V3_DPB")
	)
	(segment
		(start 27.26055 -86.941406)
		(end 25.5651 -86.941406)
		(width 0.3048)
		(layer "F.Cu")
		(net "P3V3_DPB")
	)
	(segment
		(start 61.0108 -39.287196)
		(end 60.458604 -38.735)
		(width 0.508)
		(layer "F.Cu")
		(net "P3V3_DPB")
	)
	(segment
		(start 54.2163 -70.358)
		(end 33.0073 -70.358)
		(width 0.508)
		(layer "F.Cu")
		(net "P3V3_DPB")
	)
	(segment
		(start 58.52414 -39.28364)
		(end 59.14136 -39.28364)
		(width 0.3048)
		(layer "F.Cu")
		(net "P3V3_DPB")
	)
	(segment
		(start 75.04176 -42.8625)
		(end 75.04176 -42.84726)
		(width 0.4064)
		(layer "F.Cu")
		(net "P3V3_DPB")
	)
	(segment
		(start 32.076644 -75.18019)
		(end 32.263334 -74.9935)
		(width 0.3048)
		(layer "F.Cu")
		(net "P3V3_DPB")
	)
	(segment
		(start 71.1708 -42.164)
		(end 71.8693 -41.4655)
		(width 0.508)
		(layer "F.Cu")
		(net "P3V3_DPB")
	)
	(segment
		(start 57.277 -53.2003)
		(end 57.277 -67.2973)
		(width 0.508)
		(layer "F.Cu")
		(net "P3V3_DPB")
	)
	(segment
		(start 75.692 -38.2905)
		(end 74.676 -38.2905)
		(width 0.508)
		(layer "F.Cu")
		(net "P3V3_DPB")
	)
	(segment
		(start 57.15 -43.053)
		(end 57.15 -50.8127)
		(width 0.508)
		(layer "F.Cu")
		(net "P3V3_DPB")
	)
	(segment
		(start 73.787 -38.2905)
		(end 70.767194 -38.2905)
		(width 0.508)
		(layer "F.Cu")
		(net "P3V3_DPB")
	)
	(segment
		(start 24.5745 -81.534)
		(end 24.5745 -82.55)
		(width 0.508)
		(layer "F.Cu")
		(net "P3V3_DPB")
	)
	(segment
		(start 76.2 -31.496)
		(end 76.454 -31.75)
		(width 0.508)
		(layer "F.Cu")
		(net "P3V3_DPB")
	)
	(segment
		(start 26.162 -72.1995)
		(end 26.15819 -72.20331)
		(width 0.3048)
		(layer "F.Cu")
		(net "P3V3_DPB")
	)
	(segment
		(start 57.277 -67.2973)
		(end 54.2163 -70.358)
		(width 0.508)
		(layer "F.Cu")
		(net "P3V3_DPB")
	)
	(segment
		(start 69.321426 -42.164)
		(end 70.866 -42.164)
		(width 0.508)
		(layer "F.Cu")
		(net "P3V3_DPB")
	)
	(segment
		(start 57.15 -50.8127)
		(end 58.039254 -51.701954)
		(width 0.508)
		(layer "F.Cu")
		(net "P3V3_DPB")
	)
	(segment
		(start 25.527 -86.979506)
		(end 25.527 -88.211406)
		(width 0.508)
		(layer "F.Cu")
		(net "P3V3_DPB")
	)
	(segment
		(start 26.514298 -72.1995)
		(end 26.162 -72.1995)
		(width 0.508)
		(layer "F.Cu")
		(net "P3V3_DPB")
	)
	(segment
		(start 59.14136 -39.28364)
		(end 59.69 -38.735)
		(width 0.3048)
		(layer "F.Cu")
		(net "P3V3_DPB")
	)
	(segment
		(start 74.676 -38.2905)
		(end 73.787 -38.2905)
		(width 0.508)
		(layer "F.Cu")
		(net "P3V3_DPB")
	)
	(segment
		(start 74.168 -32.004)
		(end 74.676 -31.496)
		(width 0.508)
		(layer "F.Cu")
		(net "P3V3_DPB")
	)
	(segment
		(start 70.866 -42.164)
		(end 71.1708 -42.164)
		(width 0.508)
		(layer "F.Cu")
		(net "P3V3_DPB")
	)
	(segment
		(start 75.438 -31.496)
		(end 76.2 -31.496)
		(width 0.508)
		(layer "F.Cu")
		(net "P3V3_DPB")
	)
	(segment
		(start 24.5745 -82.55)
		(end 24.5745 -83.439)
		(width 0.508)
		(layer "F.Cu")
		(net "P3V3_DPB")
	)
	(segment
		(start 70.767194 -38.2905)
		(end 68.10756 -40.950134)
		(width 0.508)
		(layer "F.Cu")
		(net "P3V3_DPB")
	)
	(segment
		(start 58.039254 -51.701954)
		(end 58.039254 -52.438046)
		(width 0.508)
		(layer "F.Cu")
		(net "P3V3_DPB")
	)
	(segment
		(start 75.04176 -42.84726)
		(end 73.66 -41.4655)
		(width 0.4064)
		(layer "F.Cu")
		(net "P3V3_DPB")
	)
	(segment
		(start 68.10756 -40.950134)
		(end 69.321426 -42.164)
		(width 0.508)
		(layer "F.Cu")
		(net "P3V3_DPB")
	)
	(segment
		(start 24.5745 -80.518)
		(end 24.5745 -81.534)
		(width 0.508)
		(layer "F.Cu")
		(net "P3V3_DPB")
	)
	(segment
		(start 32.263334 -74.9935)
		(end 33.02 -74.9935)
		(width 0.3048)
		(layer "F.Cu")
		(net "P3V3_DPB")
	)
	(segment
		(start 71.8693 -41.4655)
		(end 73.66 -41.4655)
		(width 0.508)
		(layer "F.Cu")
		(net "P3V3_DPB")
	)
	(segment
		(start 26.15819 -72.20331)
		(end 26.15819 -74.6506)
		(width 0.3048)
		(layer "F.Cu")
		(net "P3V3_DPB")
	)
	(segment
		(start 31.2674 -75.18019)
		(end 32.076644 -75.18019)
		(width 0.3048)
		(layer "F.Cu")
		(net "P3V3_DPB")
	)
	(segment
		(start 25.5651 -86.941406)
		(end 25.527 -86.979506)
		(width 0.3048)
		(layer "F.Cu")
		(net "P3V3_DPB")
	)
	(segment
		(start 65.7225 -42.672)
		(end 62.4586 -42.672)
		(width 0.508)
		(layer "F.Cu")
		(net "P3V3_DPB")
	)
	(segment
		(start 62.4586 -42.672)
		(end 61.0108 -41.2242)
		(width 0.508)
		(layer "F.Cu")
		(net "P3V3_DPB")
	)
	(segment
		(start 59.69 -38.735)
		(end 60.198 -38.735)
		(width 0.3048)
		(layer "F.Cu")
		(net "P3V3_DPB")
	)
	(via
		(at 60.198 -38.735)
		(size 0.508)
		(drill 0.254)
		(layers "F.Cu" "B.Cu")
		(net "P3V3_DPB")
	)
	(via
		(at 57.15 -43.053)
		(size 0.508)
		(drill 0.254)
		(layers "F.Cu" "B.Cu")
		(net "P3V3_DPB")
	)
	(via
		(at 32.639 -71.755)
		(size 0.508)
		(drill 0.254)
		(layers "F.Cu" "B.Cu")
		(net "P3V3_DPB")
	)
	(via
		(at 33.02 -75.819)
		(size 0.508)
		(drill 0.254)
		(layers "F.Cu" "B.Cu")
		(net "P3V3_DPB")
	)
	(via
		(at 60.198 -41.7195)
		(size 0.508)
		(drill 0.254)
		(layers "F.Cu" "B.Cu")
		(net "P3V3_DPB")
	)
	(via
		(at 73.787 -38.2905)
		(size 0.508)
		(drill 0.254)
		(layers "F.Cu" "B.Cu")
		(net "P3V3_DPB")
	)
	(via
		(at 76.454 -31.75)
		(size 0.508)
		(drill 0.254)
		(layers "F.Cu" "B.Cu")
		(net "P3V3_DPB")
	)
	(via
		(at 24.5745 -83.439)
		(size 0.508)
		(drill 0.254)
		(layers "F.Cu" "B.Cu")
		(net "P3V3_DPB")
	)
	(via
		(at 68.10756 -40.950134)
		(size 0.508)
		(drill 0.254)
		(layers "F.Cu" "B.Cu")
		(net "P3V3_DPB")
	)
	(via
		(at 25.527 -88.211406)
		(size 0.508)
		(drill 0.254)
		(layers "F.Cu" "B.Cu")
		(net "P3V3_DPB")
	)
	(via
		(at 26.958798 -72.644)
		(size 0.508)
		(drill 0.254)
		(layers "F.Cu" "B.Cu")
		(net "P3V3_DPB")
	)
	(via
		(at 73.787 -35.52825)
		(size 0.7112)
		(drill 0.3556)
		(layers "F.Cu" "B.Cu")
		(net "P3V3_DPB")
	)
	(via
		(at 65.7225 -42.672)
		(size 0.508)
		(drill 0.254)
		(layers "F.Cu" "B.Cu")
		(net "P3V3_DPB")
	)
	(via
		(at 70.866 -42.164)
		(size 0.508)
		(drill 0.254)
		(layers "F.Cu" "B.Cu")
		(net "P3V3_DPB")
	)
	(via
		(at 74.168 -32.004)
		(size 0.508)
		(drill 0.254)
		(layers "F.Cu" "B.Cu")
		(net "P3V3_DPB")
	)
	(via
		(at 29.21 -77.47)
		(size 0.508)
		(drill 0.254)
		(layers "F.Cu" "B.Cu")
		(net "P3V3_DPB")
	)
	(segment
		(start 68.81876 -39.5605)
		(end 68.56476 -39.8145)
		(width 0.4064)
		(layer "B.Cu")
		(net "P3V3_DPB")
	)
	(segment
		(start 73.787 -38.2905)
		(end 73.787 -35.52825)
		(width 0.508)
		(layer "B.Cu")
		(net "P3V3_DPB")
	)
	(segment
		(start 60.198 -41.7195)
		(end 59.260994 -41.7195)
		(width 0.508)
		(layer "B.Cu")
		(net "P3V3_DPB")
	)
	(segment
		(start 73.787 -32.385)
		(end 74.168 -32.004)
		(width 0.508)
		(layer "B.Cu")
		(net "P3V3_DPB")
	)
	(segment
		(start 24.5745 -87.258906)
		(end 25.527 -88.211406)
		(width 0.508)
		(layer "B.Cu")
		(net "P3V3_DPB")
	)
	(segment
		(start 71.755 -41.8465)
		(end 71.4375 -42.164)
		(width 0.508)
		(layer "B.Cu")
		(net "P3V3_DPB")
	)
	(segment
		(start 59.260994 -40.7035)
		(end 59.260994 -41.7195)
		(width 0.508)
		(layer "B.Cu")
		(net "P3V3_DPB")
	)
	(segment
		(start 71.4375 -42.164)
		(end 70.866 -42.164)
		(width 0.508)
		(layer "B.Cu")
		(net "P3V3_DPB")
	)
	(segment
		(start 67.183 -39.8145)
		(end 67.183 -40.9575)
		(width 0.508)
		(layer "B.Cu")
		(net "P3V3_DPB")
	)
	(segment
		(start 73.787 -35.52825)
		(end 73.787 -32.385)
		(width 0.508)
		(layer "B.Cu")
		(net "P3V3_DPB")
	)
	(segment
		(start 29.21 -78.2955)
		(end 29.21 -77.47)
		(width 0.508)
		(layer "B.Cu")
		(net "P3V3_DPB")
	)
	(segment
		(start 78.769972 -33.050226)
		(end 77.754226 -33.050226)
		(width 0.508)
		(layer "B.Cu")
		(net "P3V3_DPB")
	)
	(segment
		(start 68.100194 -40.9575)
		(end 67.183 -40.9575)
		(width 0.508)
		(layer "B.Cu")
		(net "P3V3_DPB")
	)
	(segment
		(start 68.10756 -40.950134)
		(end 68.100194 -40.9575)
		(width 0.508)
		(layer "B.Cu")
		(net "P3V3_DPB")
	)
	(segment
		(start 24.5745 -83.439)
		(end 24.5745 -87.258906)
		(width 0.508)
		(layer "B.Cu")
		(net "P3V3_DPB")
	)
	(segment
		(start 30.226 -78.2955)
		(end 29.21 -78.2955)
		(width 0.508)
		(layer "B.Cu")
		(net "P3V3_DPB")
	)
	(segment
		(start 60.198 -38.354)
		(end 60.198 -38.735)
		(width 0.508)
		(layer "B.Cu")
		(net "P3V3_DPB")
	)
	(segment
		(start 59.7535 -37.9095)
		(end 60.198 -38.354)
		(width 0.508)
		(layer "B.Cu")
		(net "P3V3_DPB")
	)
	(segment
		(start 27.686 -86.6775)
		(end 28.829 -86.6775)
		(width 0.508)
		(layer "B.Cu")
		(net "P3V3_DPB")
	)
	(segment
		(start 28.829 -86.6775)
		(end 29.845 -86.6775)
		(width 0.508)
		(layer "B.Cu")
		(net "P3V3_DPB")
	)
	(segment
		(start 65.7225 -40.767)
		(end 65.7225 -41.783)
		(width 0.508)
		(layer "B.Cu")
		(net "P3V3_DPB")
	)
	(segment
		(start 65.7225 -41.783)
		(end 65.7225 -42.672)
		(width 0.508)
		(layer "B.Cu")
		(net "P3V3_DPB")
	)
	(segment
		(start 77.754226 -33.050226)
		(end 76.454 -31.75)
		(width 0.508)
		(layer "B.Cu")
		(net "P3V3_DPB")
	)
	(segment
		(start 59.260994 -37.9095)
		(end 59.7535 -37.9095)
		(width 0.508)
		(layer "B.Cu")
		(net "P3V3_DPB")
	)
	(segment
		(start 27.060906 -86.6775)
		(end 25.527 -88.211406)
		(width 0.508)
		(layer "B.Cu")
		(net "P3V3_DPB")
	)
	(segment
		(start 30.861 -86.6775)
		(end 29.845 -86.6775)
		(width 0.508)
		(layer "B.Cu")
		(net "P3V3_DPB")
	)
	(segment
		(start 68.56476 -39.8145)
		(end 67.183 -39.8145)
		(width 0.4064)
		(layer "B.Cu")
		(net "P3V3_DPB")
	)
	(segment
		(start 27.686 -86.6775)
		(end 27.060906 -86.6775)
		(width 0.508)
		(layer "B.Cu")
		(net "P3V3_DPB")
	)
	(segment
		(start 29.21 -77.851)
		(end 30.099 -78.74)
		(width 0.508)
		(layer "In5.Cu")
		(net "P3V3_DPB")
	)
	(segment
		(start 31.495492 -78.74)
		(end 32.3088 -79.553308)
		(width 0.508)
		(layer "In5.Cu")
		(net "P3V3_DPB")
	)
	(segment
		(start 31.718504 -71.755)
		(end 31.350204 -72.1233)
		(width 0.508)
		(layer "In5.Cu")
		(net "P3V3_DPB")
	)
	(segment
		(start 30.5308 -75.6412)
		(end 31.324804 -75.6412)
		(width 0.508)
		(layer "In5.Cu")
		(net "P3V3_DPB")
	)
	(segment
		(start 27.479498 -72.1233)
		(end 26.958798 -72.644)
		(width 0.508)
		(layer "In5.Cu")
		(net "P3V3_DPB")
	)
	(segment
		(start 30.099 -78.74)
		(end 31.495492 -78.74)
		(width 0.508)
		(layer "In5.Cu")
		(net "P3V3_DPB")
	)
	(segment
		(start 67.444366 -40.950134)
		(end 65.7225 -42.672)
		(width 0.508)
		(layer "In5.Cu")
		(net "P3V3_DPB")
	)
	(segment
		(start 29.21 -76.962)
		(end 30.5308 -75.6412)
		(width 0.508)
		(layer "In5.Cu")
		(net "P3V3_DPB")
	)
	(segment
		(start 29.083 -83.693)
		(end 24.8285 -83.693)
		(width 0.508)
		(layer "In5.Cu")
		(net "P3V3_DPB")
	)
	(segment
		(start 32.3088 -79.553308)
		(end 32.3088 -80.4672)
		(width 0.508)
		(layer "In5.Cu")
		(net "P3V3_DPB")
	)
	(segment
		(start 29.21 -77.47)
		(end 29.21 -76.962)
		(width 0.508)
		(layer "In5.Cu")
		(net "P3V3_DPB")
	)
	(segment
		(start 58.4835 -41.7195)
		(end 57.15 -43.053)
		(width 0.508)
		(layer "In5.Cu")
		(net "P3V3_DPB")
	)
	(segment
		(start 32.639 -71.755)
		(end 31.718504 -71.755)
		(width 0.508)
		(layer "In5.Cu")
		(net "P3V3_DPB")
	)
	(segment
		(start 31.350204 -72.1233)
		(end 27.479498 -72.1233)
		(width 0.508)
		(layer "In5.Cu")
		(net "P3V3_DPB")
	)
	(segment
		(start 33.02 -72.136)
		(end 33.02 -75.819)
		(width 0.508)
		(layer "In5.Cu")
		(net "P3V3_DPB")
	)
	(segment
		(start 32.3088 -80.4672)
		(end 29.083 -83.693)
		(width 0.508)
		(layer "In5.Cu")
		(net "P3V3_DPB")
	)
	(segment
		(start 29.21 -77.47)
		(end 29.21 -77.851)
		(width 0.508)
		(layer "In5.Cu")
		(net "P3V3_DPB")
	)
	(segment
		(start 24.8285 -83.693)
		(end 24.5745 -83.439)
		(width 0.508)
		(layer "In5.Cu")
		(net "P3V3_DPB")
	)
	(segment
		(start 68.10756 -40.950134)
		(end 67.444366 -40.950134)
		(width 0.508)
		(layer "In5.Cu")
		(net "P3V3_DPB")
	)
	(segment
		(start 60.198 -41.7195)
		(end 58.4835 -41.7195)
		(width 0.508)
		(layer "In5.Cu")
		(net "P3V3_DPB")
	)
	(segment
		(start 31.324804 -75.6412)
		(end 31.502604 -75.819)
		(width 0.508)
		(layer "In5.Cu")
		(net "P3V3_DPB")
	)
	(segment
		(start 32.639 -71.755)
		(end 33.02 -72.136)
		(width 0.508)
		(layer "In5.Cu")
		(net "P3V3_DPB")
	)
	(segment
		(start 31.502604 -75.819)
		(end 33.02 -75.819)
		(width 0.508)
		(layer "In5.Cu")
		(net "P3V3_DPB")
	)
	(segment
		(start 65.174876 -33.439862)
		(end 66.78168 -33.439862)
		(width 0.12065)
		(layer "F.Cu")
		(net "Z50_SSD_B_R_ACT#")
	)
	(via
		(at 67.818 -33.450022)
		(size 0.7112)
		(drill 0.3556)
		(layers "F.Cu" "B.Cu")
		(net "Z50_SSD_B_R_ACT#")
	)
	(via
		(at 66.78168 -33.439862)
		(size 0.5588)
		(drill 0.3048)
		(layers "F.Cu" "B.Cu")
		(net "Z50_SSD_B_R_ACT#")
	)
	(segment
		(start 68.848478 -33.450022)
		(end 67.818 -33.450022)
		(width 0.12065)
		(layer "B.Cu")
		(net "Z50_SSD_B_R_ACT#")
	)
	(segment
		(start 66.79184 -33.450022)
		(end 66.78168 -33.439862)
		(width 0.12065)
		(layer "B.Cu")
		(net "Z50_SSD_B_R_ACT#")
	)
	(segment
		(start 67.818 -33.450022)
		(end 66.79184 -33.450022)
		(width 0.12065)
		(layer "B.Cu")
		(net "Z50_SSD_B_R_ACT#")
	)
	(segment
		(start 68.8975 -33.401)
		(end 68.848478 -33.450022)
		(width 0.12065)
		(layer "B.Cu")
		(net "Z50_SSD_B_R_ACT#")
	)
	(segment
		(start 65.174876 -61.04001)
		(end 66.802 -61.04001)
		(width 0.12065)
		(layer "F.Cu")
		(net "Z50_SSD_A_R_ACT#")
	)
	(via
		(at 66.802 -61.04001)
		(size 0.508)
		(drill 0.254)
		(layers "F.Cu" "B.Cu")
		(net "Z50_SSD_A_R_ACT#")
	)
	(via
		(at 67.691 -61.976)
		(size 0.7112)
		(drill 0.3556)
		(layers "F.Cu" "B.Cu")
		(net "Z50_SSD_A_R_ACT#")
	)
	(segment
		(start 67.691 -61.0235)
		(end 67.691 -61.976)
		(width 0.12065)
		(layer "B.Cu")
		(net "Z50_SSD_A_R_ACT#")
	)
	(segment
		(start 66.81851 -61.0235)
		(end 66.802 -61.04001)
		(width 0.12065)
		(layer "B.Cu")
		(net "Z50_SSD_A_R_ACT#")
	)
	(segment
		(start 67.691 -61.0235)
		(end 66.81851 -61.0235)
		(width 0.12065)
		(layer "B.Cu")
		(net "Z50_SSD_A_R_ACT#")
	)
	(segment
		(start 75.545188 -43.659552)
		(end 74.520552 -43.659552)
		(width 0.12065)
		(layer "F.Cu")
		(net "Z50_SSD_M2_PRSNT#")
	)
	(segment
		(start 76.34224 -42.8625)
		(end 75.545188 -43.659552)
		(width 0.12065)
		(layer "F.Cu")
		(net "Z50_SSD_M2_PRSNT#")
	)
	(segment
		(start 74.520552 -43.659552)
		(end 73.914 -43.053)
		(width 0.12065)
		(layer "F.Cu")
		(net "Z50_SSD_M2_PRSNT#")
	)
	(via
		(at 74.676 -42.291)
		(size 0.7112)
		(drill 0.3556)
		(layers "F.Cu" "B.Cu")
		(net "Z50_SSD_M2_PRSNT#")
	)
	(via
		(at 73.914 -43.053)
		(size 0.508)
		(drill 0.254)
		(layers "F.Cu" "B.Cu")
		(net "Z50_SSD_M2_PRSNT#")
	)
	(segment
		(start 74.676 -42.291)
		(end 73.914 -43.053)
		(width 0.12065)
		(layer "B.Cu")
		(net "Z50_SSD_M2_PRSNT#")
	)
	(segment
		(start 77.597 -25.690068)
		(end 76.62545 -26.661618)
		(width 0.12065)
		(layer "B.Cu")
		(net "Z50_SSD_M2_PRSNT#")
	)
	(segment
		(start 75.729846 -32.601154)
		(end 75.311 -33.02)
		(width 0.12065)
		(layer "B.Cu")
		(net "Z50_SSD_M2_PRSNT#")
	)
	(segment
		(start 77.654658 -18.070068)
		(end 76.62545 -19.09953)
		(width 0.12065)
		(layer "B.Cu")
		(net "Z50_SSD_M2_PRSNT#")
	)
	(segment
		(start 75.311 -39.129208)
		(end 75.930252 -39.74846)
		(width 0.12065)
		(layer "B.Cu")
		(net "Z50_SSD_M2_PRSNT#")
	)
	(segment
		(start 78.82001 -25.690068)
		(end 77.597 -25.690068)
		(width 0.12065)
		(layer "B.Cu")
		(net "Z50_SSD_M2_PRSNT#")
	)
	(segment
		(start 76.62545 -29.861002)
		(end 75.729846 -30.756606)
		(width 0.12065)
		(layer "B.Cu")
		(net "Z50_SSD_M2_PRSNT#")
	)
	(segment
		(start 76.62545 -19.09953)
		(end 76.62545 -26.661618)
		(width 0.12065)
		(layer "B.Cu")
		(net "Z50_SSD_M2_PRSNT#")
	)
	(segment
		(start 75.311 -33.02)
		(end 75.311 -39.129208)
		(width 0.12065)
		(layer "B.Cu")
		(net "Z50_SSD_M2_PRSNT#")
	)
	(segment
		(start 78.82001 -18.070068)
		(end 77.654658 -18.070068)
		(width 0.12065)
		(layer "B.Cu")
		(net "Z50_SSD_M2_PRSNT#")
	)
	(segment
		(start 75.930252 -39.74846)
		(end 75.930252 -41.036748)
		(width 0.12065)
		(layer "B.Cu")
		(net "Z50_SSD_M2_PRSNT#")
	)
	(segment
		(start 75.729846 -30.756606)
		(end 75.729846 -32.601154)
		(width 0.12065)
		(layer "B.Cu")
		(net "Z50_SSD_M2_PRSNT#")
	)
	(segment
		(start 75.930252 -41.036748)
		(end 74.676 -42.291)
		(width 0.12065)
		(layer "B.Cu")
		(net "Z50_SSD_M2_PRSNT#")
	)
	(segment
		(start 76.62545 -26.661618)
		(end 76.62545 -29.861002)
		(width 0.12065)
		(layer "B.Cu")
		(net "Z50_SSD_M2_PRSNT#")
	)
	(segment
		(start 32.616902 -79.416402)
		(end 32.385 -79.1845)
		(width 0.12065)
		(layer "F.Cu")
		(net "Z50_SSD_B1_SMB_DATA_R")
	)
	(segment
		(start 30.734 -84.963)
		(end 30.51048 -85.18652)
		(width 0.12065)
		(layer "F.Cu")
		(net "Z50_SSD_B1_SMB_DATA_R")
	)
	(segment
		(start 30.734 -84.963)
		(end 32.616902 -83.080098)
		(width 0.12065)
		(layer "F.Cu")
		(net "Z50_SSD_B1_SMB_DATA_R")
	)
	(segment
		(start 30.51048 -85.18652)
		(end 30.51048 -86.941406)
		(width 0.12065)
		(layer "F.Cu")
		(net "Z50_SSD_B1_SMB_DATA_R")
	)
	(segment
		(start 32.616902 -83.080098)
		(end 32.616902 -79.416402)
		(width 0.12065)
		(layer "F.Cu")
		(net "Z50_SSD_B1_SMB_DATA_R")
	)
	(via
		(at 31.7754 -86.4235)
		(size 0.7112)
		(drill 0.3556)
		(layers "F.Cu" "B.Cu")
		(net "Z50_SSD_B1_SMB_DATA_R")
	)
	(via
		(at 27.178 -78.232)
		(size 0.508)
		(drill 0.254)
		(layers "F.Cu" "B.Cu")
		(net "Z50_SSD_B1_SMB_DATA_R")
	)
	(via
		(at 30.734 -84.963)
		(size 0.508)
		(drill 0.254)
		(layers "F.Cu" "B.Cu")
		(net "Z50_SSD_B1_SMB_DATA_R")
	)
	(segment
		(start 30.861 -85.7885)
		(end 30.861 -85.09)
		(width 0.12065)
		(layer "B.Cu")
		(net "Z50_SSD_B1_SMB_DATA_R")
	)
	(segment
		(start 30.861 -85.09)
		(end 30.734 -84.963)
		(width 0.12065)
		(layer "B.Cu")
		(net "Z50_SSD_B1_SMB_DATA_R")
	)
	(segment
		(start 26.543 -77.6605)
		(end 26.6065 -77.6605)
		(width 0.12065)
		(layer "B.Cu")
		(net "Z50_SSD_B1_SMB_DATA_R")
	)
	(segment
		(start 31.1404 -85.7885)
		(end 31.7754 -86.4235)
		(width 0.12065)
		(layer "B.Cu")
		(net "Z50_SSD_B1_SMB_DATA_R")
	)
	(segment
		(start 26.6065 -77.6605)
		(end 27.178 -78.232)
		(width 0.12065)
		(layer "B.Cu")
		(net "Z50_SSD_B1_SMB_DATA_R")
	)
	(segment
		(start 30.861 -85.7885)
		(end 31.1404 -85.7885)
		(width 0.12065)
		(layer "B.Cu")
		(net "Z50_SSD_B1_SMB_DATA_R")
	)
	(segment
		(start 31.690818 -78.61935)
		(end 27.56535 -78.61935)
		(width 0.12065)
		(layer "In2.Cu")
		(net "Z50_SSD_B1_SMB_DATA_R")
	)
	(segment
		(start 30.734 -84.963)
		(end 32.616902 -83.080098)
		(width 0.12065)
		(layer "In2.Cu")
		(net "Z50_SSD_B1_SMB_DATA_R")
	)
	(segment
		(start 32.616902 -79.545434)
		(end 31.690818 -78.61935)
		(width 0.12065)
		(layer "In2.Cu")
		(net "Z50_SSD_B1_SMB_DATA_R")
	)
	(segment
		(start 27.56535 -78.61935)
		(end 27.178 -78.232)
		(width 0.12065)
		(layer "In2.Cu")
		(net "Z50_SSD_B1_SMB_DATA_R")
	)
	(segment
		(start 32.616902 -83.080098)
		(end 32.616902 -79.545434)
		(width 0.12065)
		(layer "In2.Cu")
		(net "Z50_SSD_B1_SMB_DATA_R")
	)
	(segment
		(start 65.174876 -25.439878)
		(end 66.756026 -25.439878)
		(width 0.12065)
		(layer "F.Cu")
		(net "Z50_SSD_B1_SMB_DATA")
	)
	(segment
		(start 30.019752 -70.977252)
		(end 30.226 -71.1835)
		(width 0.12065)
		(layer "F.Cu")
		(net "Z50_SSD_B1_SMB_DATA")
	)
	(segment
		(start 28.559252 -70.977252)
		(end 30.019752 -70.977252)
		(width 0.12065)
		(layer "F.Cu")
		(net "Z50_SSD_B1_SMB_DATA")
	)
	(segment
		(start 28.067 -70.485)
		(end 28.559252 -70.977252)
		(width 0.12065)
		(layer "F.Cu")
		(net "Z50_SSD_B1_SMB_DATA")
	)
	(via
		(at 28.067 -70.485)
		(size 0.508)
		(drill 0.254)
		(layers "F.Cu" "B.Cu")
		(net "Z50_SSD_B1_SMB_DATA")
	)
	(via
		(at 27.432 -75.819)
		(size 0.508)
		(drill 0.254)
		(layers "F.Cu" "B.Cu")
		(net "Z50_SSD_B1_SMB_DATA")
	)
	(via
		(at 64.135 -26.162)
		(size 0.7112)
		(drill 0.3556)
		(layers "F.Cu" "B.Cu")
		(net "Z50_SSD_B1_SMB_DATA")
	)
	(via
		(at 66.756026 -25.439878)
		(size 0.508)
		(drill 0.254)
		(layers "F.Cu" "B.Cu")
		(net "Z50_SSD_B1_SMB_DATA")
	)
	(segment
		(start 30.064456 -68.106544)
		(end 54.52491 -68.106544)
		(width 0.12065)
		(layer "B.Cu")
		(net "Z50_SSD_B1_SMB_DATA")
	)
	(segment
		(start 28.8925 -71.3105)
		(end 28.067 -70.485)
		(width 0.12065)
		(layer "B.Cu")
		(net "Z50_SSD_B1_SMB_DATA")
	)
	(segment
		(start 61.624718 -26.162)
		(end 64.135 -26.162)
		(width 0.12065)
		(layer "B.Cu")
		(net "Z50_SSD_B1_SMB_DATA")
	)
	(segment
		(start 28.956 -71.3105)
		(end 28.8925 -71.3105)
		(width 0.12065)
		(layer "B.Cu")
		(net "Z50_SSD_B1_SMB_DATA")
	)
	(segment
		(start 55.952898 -31.83382)
		(end 61.624718 -26.162)
		(width 0.12065)
		(layer "B.Cu")
		(net "Z50_SSD_B1_SMB_DATA")
	)
	(segment
		(start 28.067 -70.104)
		(end 30.064456 -68.106544)
		(width 0.12065)
		(layer "B.Cu")
		(net "Z50_SSD_B1_SMB_DATA")
	)
	(segment
		(start 54.52491 -68.106544)
		(end 55.952898 -66.678556)
		(width 0.12065)
		(layer "B.Cu")
		(net "Z50_SSD_B1_SMB_DATA")
	)
	(segment
		(start 64.135 -26.162)
		(end 66.033904 -26.162)
		(width 0.12065)
		(layer "B.Cu")
		(net "Z50_SSD_B1_SMB_DATA")
	)
	(segment
		(start 66.033904 -26.162)
		(end 66.756026 -25.439878)
		(width 0.12065)
		(layer "B.Cu")
		(net "Z50_SSD_B1_SMB_DATA")
	)
	(segment
		(start 26.543 -76.7715)
		(end 26.543 -76.708)
		(width 0.12065)
		(layer "B.Cu")
		(net "Z50_SSD_B1_SMB_DATA")
	)
	(segment
		(start 26.543 -76.708)
		(end 27.432 -75.819)
		(width 0.12065)
		(layer "B.Cu")
		(net "Z50_SSD_B1_SMB_DATA")
	)
	(segment
		(start 28.067 -70.485)
		(end 28.067 -70.104)
		(width 0.12065)
		(layer "B.Cu")
		(net "Z50_SSD_B1_SMB_DATA")
	)
	(segment
		(start 55.952898 -66.678556)
		(end 55.952898 -31.83382)
		(width 0.12065)
		(layer "B.Cu")
		(net "Z50_SSD_B1_SMB_DATA")
	)
	(segment
		(start 28.067 -70.485)
		(end 27.57805 -70.97395)
		(width 0.12065)
		(layer "In2.Cu")
		(net "Z50_SSD_B1_SMB_DATA")
	)
	(segment
		(start 28.051252 -75.199748)
		(end 27.432 -75.819)
		(width 0.12065)
		(layer "In2.Cu")
		(net "Z50_SSD_B1_SMB_DATA")
	)
	(segment
		(start 27.57805 -74.200258)
		(end 28.051252 -74.67346)
		(width 0.12065)
		(layer "In2.Cu")
		(net "Z50_SSD_B1_SMB_DATA")
	)
	(segment
		(start 27.57805 -70.97395)
		(end 27.57805 -74.200258)
		(width 0.12065)
		(layer "In2.Cu")
		(net "Z50_SSD_B1_SMB_DATA")
	)
	(segment
		(start 28.051252 -74.67346)
		(end 28.051252 -75.199748)
		(width 0.12065)
		(layer "In2.Cu")
		(net "Z50_SSD_B1_SMB_DATA")
	)
	(segment
		(start 32.115252 -82.565748)
		(end 32.115252 -79.75346)
		(width 0.12065)
		(layer "F.Cu")
		(net "Z50_SSD_B1_SMB_CLK_R")
	)
	(segment
		(start 31.75254 -79.390748)
		(end 31.575248 -79.390748)
		(width 0.12065)
		(layer "F.Cu")
		(net "Z50_SSD_B1_SMB_CLK_R")
	)
	(segment
		(start 29.86024 -85.10524)
		(end 29.718 -84.963)
		(width 0.12065)
		(layer "F.Cu")
		(net "Z50_SSD_B1_SMB_CLK_R")
	)
	(segment
		(start 29.86024 -86.941406)
		(end 29.86024 -85.10524)
		(width 0.12065)
		(layer "F.Cu")
		(net "Z50_SSD_B1_SMB_CLK_R")
	)
	(segment
		(start 31.575248 -79.390748)
		(end 31.369 -79.1845)
		(width 0.12065)
		(layer "F.Cu")
		(net "Z50_SSD_B1_SMB_CLK_R")
	)
	(segment
		(start 32.115252 -79.75346)
		(end 31.75254 -79.390748)
		(width 0.12065)
		(layer "F.Cu")
		(net "Z50_SSD_B1_SMB_CLK_R")
	)
	(segment
		(start 29.718 -84.963)
		(end 32.115252 -82.565748)
		(width 0.12065)
		(layer "F.Cu")
		(net "Z50_SSD_B1_SMB_CLK_R")
	)
	(via
		(at 29.718 -84.963)
		(size 0.508)
		(drill 0.254)
		(layers "F.Cu" "B.Cu")
		(net "Z50_SSD_B1_SMB_CLK_R")
	)
	(via
		(at 30.353 -83.82)
		(size 0.7112)
		(drill 0.3556)
		(layers "F.Cu" "B.Cu")
		(net "Z50_SSD_B1_SMB_CLK_R")
	)
	(via
		(at 27.178 -79.121)
		(size 0.508)
		(drill 0.254)
		(layers "F.Cu" "B.Cu")
		(net "Z50_SSD_B1_SMB_CLK_R")
	)
	(segment
		(start 25.527 -77.6605)
		(end 25.7175 -77.6605)
		(width 0.12065)
		(layer "B.Cu")
		(net "Z50_SSD_B1_SMB_CLK_R")
	)
	(segment
		(start 29.718 -84.963)
		(end 29.718 -84.455)
		(width 0.12065)
		(layer "B.Cu")
		(net "Z50_SSD_B1_SMB_CLK_R")
	)
	(segment
		(start 25.7175 -77.6605)
		(end 27.178 -79.121)
		(width 0.12065)
		(layer "B.Cu")
		(net "Z50_SSD_B1_SMB_CLK_R")
	)
	(segment
		(start 29.718 -84.455)
		(end 30.353 -83.82)
		(width 0.12065)
		(layer "B.Cu")
		(net "Z50_SSD_B1_SMB_CLK_R")
	)
	(segment
		(start 29.845 -85.7885)
		(end 29.718 -85.6615)
		(width 0.12065)
		(layer "B.Cu")
		(net "Z50_SSD_B1_SMB_CLK_R")
	)
	(segment
		(start 29.718 -85.6615)
		(end 29.718 -84.963)
		(width 0.12065)
		(layer "B.Cu")
		(net "Z50_SSD_B1_SMB_CLK_R")
	)
	(segment
		(start 32.115252 -82.565748)
		(end 32.115252 -79.75346)
		(width 0.12065)
		(layer "In2.Cu")
		(net "Z50_SSD_B1_SMB_CLK_R")
	)
	(segment
		(start 31.482792 -79.121)
		(end 27.178 -79.121)
		(width 0.12065)
		(layer "In2.Cu")
		(net "Z50_SSD_B1_SMB_CLK_R")
	)
	(segment
		(start 29.718 -84.963)
		(end 32.115252 -82.565748)
		(width 0.12065)
		(layer "In2.Cu")
		(net "Z50_SSD_B1_SMB_CLK_R")
	)
	(segment
		(start 32.115252 -79.75346)
		(end 31.482792 -79.121)
		(width 0.12065)
		(layer "In2.Cu")
		(net "Z50_SSD_B1_SMB_CLK_R")
	)
	(segment
		(start 66.32575 -25.93975)
		(end 66.802 -26.416)
		(width 0.12065)
		(layer "F.Cu")
		(net "Z50_SSD_B1_SMB_CLK")
	)
	(segment
		(start 28.10129 -71.250048)
		(end 28.415742 -71.5645)
		(width 0.12065)
		(layer "F.Cu")
		(net "Z50_SSD_B1_SMB_CLK")
	)
	(segment
		(start 27.051 -70.485)
		(end 27.670252 -69.865748)
		(width 0.12065)
		(layer "F.Cu")
		(net "Z50_SSD_B1_SMB_CLK")
	)
	(segment
		(start 28.717748 -69.865748)
		(end 29.083 -70.231)
		(width 0.12065)
		(layer "F.Cu")
		(net "Z50_SSD_B1_SMB_CLK")
	)
	(segment
		(start 65.174876 -25.93975)
		(end 66.32575 -25.93975)
		(width 0.12065)
		(layer "F.Cu")
		(net "Z50_SSD_B1_SMB_CLK")
	)
	(segment
		(start 27.670252 -69.865748)
		(end 28.717748 -69.865748)
		(width 0.12065)
		(layer "F.Cu")
		(net "Z50_SSD_B1_SMB_CLK")
	)
	(segment
		(start 28.415742 -71.5645)
		(end 29.083 -71.5645)
		(width 0.12065)
		(layer "F.Cu")
		(net "Z50_SSD_B1_SMB_CLK")
	)
	(segment
		(start 27.816048 -71.250048)
		(end 28.10129 -71.250048)
		(width 0.12065)
		(layer "F.Cu")
		(net "Z50_SSD_B1_SMB_CLK")
	)
	(segment
		(start 27.051 -70.485)
		(end 27.816048 -71.250048)
		(width 0.12065)
		(layer "F.Cu")
		(net "Z50_SSD_B1_SMB_CLK")
	)
	(via
		(at 65.151 -26.924)
		(size 0.7112)
		(drill 0.3556)
		(layers "F.Cu" "B.Cu")
		(net "Z50_SSD_B1_SMB_CLK")
	)
	(via
		(at 27.432 -74.93)
		(size 0.508)
		(drill 0.254)
		(layers "F.Cu" "B.Cu")
		(net "Z50_SSD_B1_SMB_CLK")
	)
	(via
		(at 29.083 -70.231)
		(size 0.508)
		(drill 0.254)
		(layers "F.Cu" "B.Cu")
		(net "Z50_SSD_B1_SMB_CLK")
	)
	(via
		(at 66.802 -26.416)
		(size 0.508)
		(drill 0.254)
		(layers "F.Cu" "B.Cu")
		(net "Z50_SSD_B1_SMB_CLK")
	)
	(via
		(at 27.051 -70.485)
		(size 0.508)
		(drill 0.254)
		(layers "F.Cu" "B.Cu")
		(net "Z50_SSD_B1_SMB_CLK")
	)
	(segment
		(start 30.653482 -68.608194)
		(end 54.732936 -68.608194)
		(width 0.12065)
		(layer "B.Cu")
		(net "Z50_SSD_B1_SMB_CLK")
	)
	(segment
		(start 54.732936 -68.608194)
		(end 56.454548 -66.886582)
		(width 0.12065)
		(layer "B.Cu")
		(net "Z50_SSD_B1_SMB_CLK")
	)
	(segment
		(start 29.083 -70.231)
		(end 29.083 -70.178676)
		(width 0.12065)
		(layer "B.Cu")
		(net "Z50_SSD_B1_SMB_CLK")
	)
	(segment
		(start 25.527 -76.7715)
		(end 25.5905 -76.7715)
		(width 0.12065)
		(layer "B.Cu")
		(net "Z50_SSD_B1_SMB_CLK")
	)
	(segment
		(start 29.083 -70.178676)
		(end 30.653482 -68.608194)
		(width 0.12065)
		(layer "B.Cu")
		(net "Z50_SSD_B1_SMB_CLK")
	)
	(segment
		(start 56.454548 -66.886582)
		(end 56.454548 -32.041846)
		(width 0.12065)
		(layer "B.Cu")
		(net "Z50_SSD_B1_SMB_CLK")
	)
	(segment
		(start 27.051 -70.485)
		(end 27.8765 -71.3105)
		(width 0.12065)
		(layer "B.Cu")
		(net "Z50_SSD_B1_SMB_CLK")
	)
	(segment
		(start 65.151 -26.924)
		(end 66.294 -26.924)
		(width 0.12065)
		(layer "B.Cu")
		(net "Z50_SSD_B1_SMB_CLK")
	)
	(segment
		(start 27.8765 -71.3105)
		(end 27.94 -71.3105)
		(width 0.12065)
		(layer "B.Cu")
		(net "Z50_SSD_B1_SMB_CLK")
	)
	(segment
		(start 66.294 -26.924)
		(end 66.802 -26.416)
		(width 0.12065)
		(layer "B.Cu")
		(net "Z50_SSD_B1_SMB_CLK")
	)
	(segment
		(start 25.5905 -76.7715)
		(end 27.432 -74.93)
		(width 0.12065)
		(layer "B.Cu")
		(net "Z50_SSD_B1_SMB_CLK")
	)
	(segment
		(start 61.572394 -26.924)
		(end 65.151 -26.924)
		(width 0.12065)
		(layer "B.Cu")
		(net "Z50_SSD_B1_SMB_CLK")
	)
	(segment
		(start 56.454548 -32.041846)
		(end 61.572394 -26.924)
		(width 0.12065)
		(layer "B.Cu")
		(net "Z50_SSD_B1_SMB_CLK")
	)
	(segment
		(start 26.339546 -72.38746)
		(end 26.339546 -72.90054)
		(width 0.12065)
		(layer "In2.Cu")
		(net "Z50_SSD_B1_SMB_CLK")
	)
	(segment
		(start 27.051 -70.485)
		(end 27.051 -71.676006)
		(width 0.12065)
		(layer "In2.Cu")
		(net "Z50_SSD_B1_SMB_CLK")
	)
	(segment
		(start 27.051 -71.676006)
		(end 26.339546 -72.38746)
		(width 0.12065)
		(layer "In2.Cu")
		(net "Z50_SSD_B1_SMB_CLK")
	)
	(segment
		(start 26.339546 -72.90054)
		(end 27.0764 -73.637394)
		(width 0.12065)
		(layer "In2.Cu")
		(net "Z50_SSD_B1_SMB_CLK")
	)
	(segment
		(start 27.0764 -74.5744)
		(end 27.432 -74.93)
		(width 0.12065)
		(layer "In2.Cu")
		(net "Z50_SSD_B1_SMB_CLK")
	)
	(segment
		(start 27.0764 -73.637394)
		(end 27.0764 -74.5744)
		(width 0.12065)
		(layer "In2.Cu")
		(net "Z50_SSD_B1_SMB_CLK")
	)
	(segment
		(start 65.174876 -22.939756)
		(end 66.341244 -22.939756)
		(width 0.12065)
		(layer "F.Cu")
		(net "Z50_SSD_B1_CLKREQ#")
	)
	(segment
		(start 66.341244 -22.939756)
		(end 66.802 -22.479)
		(width 0.12065)
		(layer "F.Cu")
		(net "Z50_SSD_B1_CLKREQ#")
	)
	(via
		(at 66.802 -22.479)
		(size 0.508)
		(drill 0.254)
		(layers "F.Cu" "B.Cu")
		(net "Z50_SSD_B1_CLKREQ#")
	)
	(via
		(at 65.278 -23.495)
		(size 0.7112)
		(drill 0.3556)
		(layers "F.Cu" "B.Cu")
		(net "Z50_SSD_B1_CLKREQ#")
	)
	(segment
		(start 65.5955 -22.479)
		(end 65.5955 -23.1775)
		(width 0.12065)
		(layer "B.Cu")
		(net "Z50_SSD_B1_CLKREQ#")
	)
	(segment
		(start 65.5955 -22.479)
		(end 66.802 -22.479)
		(width 0.12065)
		(layer "B.Cu")
		(net "Z50_SSD_B1_CLKREQ#")
	)
	(segment
		(start 65.5955 -23.1775)
		(end 65.278 -23.495)
		(width 0.12065)
		(layer "B.Cu")
		(net "Z50_SSD_B1_CLKREQ#")
	)
	(segment
		(start 66.373248 -24.939752)
		(end 65.174876 -24.939752)
		(width 0.12065)
		(layer "F.Cu")
		(net "Z50_SSD_B1_ALERT#")
	)
	(segment
		(start 66.802 -24.511)
		(end 66.373248 -24.939752)
		(width 0.12065)
		(layer "F.Cu")
		(net "Z50_SSD_B1_ALERT#")
	)
	(via
		(at 65.151 -25.4)
		(size 0.7112)
		(drill 0.3556)
		(layers "F.Cu" "B.Cu")
		(net "Z50_SSD_B1_ALERT#")
	)
	(via
		(at 66.802 -24.511)
		(size 0.508)
		(drill 0.254)
		(layers "F.Cu" "B.Cu")
		(net "Z50_SSD_B1_ALERT#")
	)
	(segment
		(start 65.5955 -24.511)
		(end 66.802 -24.511)
		(width 0.12065)
		(layer "B.Cu")
		(net "Z50_SSD_B1_ALERT#")
	)
	(segment
		(start 65.5955 -24.9555)
		(end 65.151 -25.4)
		(width 0.12065)
		(layer "B.Cu")
		(net "Z50_SSD_B1_ALERT#")
	)
	(segment
		(start 65.5955 -24.511)
		(end 65.5955 -24.9555)
		(width 0.12065)
		(layer "B.Cu")
		(net "Z50_SSD_B1_ALERT#")
	)
	(segment
		(start 29.21 -79.1845)
		(end 29.21 -79.629)
		(width 0.12065)
		(layer "F.Cu")
		(net "Z50_SSD_A1_SMB_DATA_R")
	)
	(segment
		(start 29.86024 -80.27924)
		(end 29.591 -80.01)
		(width 0.12065)
		(layer "F.Cu")
		(net "Z50_SSD_A1_SMB_DATA_R")
	)
	(segment
		(start 29.86024 -81.302606)
		(end 29.86024 -80.27924)
		(width 0.12065)
		(layer "F.Cu")
		(net "Z50_SSD_A1_SMB_DATA_R")
	)
	(segment
		(start 29.21 -79.629)
		(end 29.591 -80.01)
		(width 0.12065)
		(layer "F.Cu")
		(net "Z50_SSD_A1_SMB_DATA_R")
	)
	(via
		(at 29.591 -80.01)
		(size 0.508)
		(drill 0.254)
		(layers "F.Cu" "B.Cu")
		(net "Z50_SSD_A1_SMB_DATA_R")
	)
	(via
		(at 23.495 -78.486)
		(size 0.508)
		(drill 0.254)
		(layers "F.Cu" "B.Cu")
		(net "Z50_SSD_A1_SMB_DATA_R")
	)
	(via
		(at 28.2956 -79.1845)
		(size 0.7112)
		(drill 0.3556)
		(layers "F.Cu" "B.Cu")
		(net "Z50_SSD_A1_SMB_DATA_R")
	)
	(segment
		(start 23.495 -77.6605)
		(end 23.495 -78.486)
		(width 0.12065)
		(layer "B.Cu")
		(net "Z50_SSD_A1_SMB_DATA_R")
	)
	(segment
		(start 29.21 -79.629)
		(end 29.591 -80.01)
		(width 0.12065)
		(layer "B.Cu")
		(net "Z50_SSD_A1_SMB_DATA_R")
	)
	(segment
		(start 29.21 -79.1845)
		(end 29.21 -79.629)
		(width 0.12065)
		(layer "B.Cu")
		(net "Z50_SSD_A1_SMB_DATA_R")
	)
	(segment
		(start 29.21 -79.1845)
		(end 28.2956 -79.1845)
		(width 0.12065)
		(layer "B.Cu")
		(net "Z50_SSD_A1_SMB_DATA_R")
	)
	(segment
		(start 26.03246 -82.153252)
		(end 23.876 -79.996792)
		(width 0.12065)
		(layer "In2.Cu")
		(net "Z50_SSD_A1_SMB_DATA_R")
	)
	(segment
		(start 29.591 -80.01)
		(end 29.591 -80.219804)
		(width 0.12065)
		(layer "In2.Cu")
		(net "Z50_SSD_A1_SMB_DATA_R")
	)
	(segment
		(start 27.657552 -82.153252)
		(end 26.03246 -82.153252)
		(width 0.12065)
		(layer "In2.Cu")
		(net "Z50_SSD_A1_SMB_DATA_R")
	)
	(segment
		(start 29.591 -80.219804)
		(end 27.657552 -82.153252)
		(width 0.12065)
		(layer "In2.Cu")
		(net "Z50_SSD_A1_SMB_DATA_R")
	)
	(segment
		(start 23.876 -79.996792)
		(end 23.876 -78.867)
		(width 0.12065)
		(layer "In2.Cu")
		(net "Z50_SSD_A1_SMB_DATA_R")
	)
	(segment
		(start 23.876 -78.867)
		(end 23.495 -78.486)
		(width 0.12065)
		(layer "In2.Cu")
		(net "Z50_SSD_A1_SMB_DATA_R")
	)
	(segment
		(start 27.462226 -69.364098)
		(end 27.100022 -69.726302)
		(width 0.12065)
		(layer "F.Cu")
		(net "Z50_SSD_A1_SMB_DATA")
	)
	(segment
		(start 67.43065 -59.685174)
		(end 67.43065 -53.727858)
		(width 0.12065)
		(layer "F.Cu")
		(net "Z50_SSD_A1_SMB_DATA")
	)
	(segment
		(start 76.708 -73.787)
		(end 76.26985 -73.34885)
		(width 0.12065)
		(layer "F.Cu")
		(net "Z50_SSD_A1_SMB_DATA")
	)
	(segment
		(start 69.33565 -68.168774)
		(end 69.33565 -63.266574)
		(width 0.12065)
		(layer "F.Cu")
		(net "Z50_SSD_A1_SMB_DATA")
	)
	(segment
		(start 29.105098 -69.364098)
		(end 27.462226 -69.364098)
		(width 0.12065)
		(layer "F.Cu")
		(net "Z50_SSD_A1_SMB_DATA")
	)
	(segment
		(start 72.401938 -71.235062)
		(end 69.33565 -68.168774)
		(width 0.12065)
		(layer "F.Cu")
		(net "Z50_SSD_A1_SMB_DATA")
	)
	(segment
		(start 67.43065 -53.727858)
		(end 66.756026 -53.053234)
		(width 0.12065)
		(layer "F.Cu")
		(net "Z50_SSD_A1_SMB_DATA")
	)
	(segment
		(start 68.75145 -61.005974)
		(end 67.43065 -59.685174)
		(width 0.12065)
		(layer "F.Cu")
		(net "Z50_SSD_A1_SMB_DATA")
	)
	(segment
		(start 76.26985 -73.34885)
		(end 76.26985 -72.105774)
		(width 0.12065)
		(layer "F.Cu")
		(net "Z50_SSD_A1_SMB_DATA")
	)
	(segment
		(start 68.75145 -62.682374)
		(end 68.75145 -61.005974)
		(width 0.12065)
		(layer "F.Cu")
		(net "Z50_SSD_A1_SMB_DATA")
	)
	(segment
		(start 75.399138 -71.235062)
		(end 72.401938 -71.235062)
		(width 0.12065)
		(layer "F.Cu")
		(net "Z50_SSD_A1_SMB_DATA")
	)
	(segment
		(start 25.146 -71.3105)
		(end 25.146 -70.485)
		(width 0.12065)
		(layer "F.Cu")
		(net "Z50_SSD_A1_SMB_DATA")
	)
	(segment
		(start 27.100022 -69.726302)
		(end 25.904698 -69.726302)
		(width 0.12065)
		(layer "F.Cu")
		(net "Z50_SSD_A1_SMB_DATA")
	)
	(segment
		(start 25.904698 -69.726302)
		(end 25.146 -70.485)
		(width 0.12065)
		(layer "F.Cu")
		(net "Z50_SSD_A1_SMB_DATA")
	)
	(segment
		(start 69.33565 -63.266574)
		(end 68.75145 -62.682374)
		(width 0.12065)
		(layer "F.Cu")
		(net "Z50_SSD_A1_SMB_DATA")
	)
	(segment
		(start 66.756026 -53.053234)
		(end 66.756026 -53.040026)
		(width 0.12065)
		(layer "F.Cu")
		(net "Z50_SSD_A1_SMB_DATA")
	)
	(segment
		(start 65.174876 -53.040026)
		(end 66.756026 -53.040026)
		(width 0.12065)
		(layer "F.Cu")
		(net "Z50_SSD_A1_SMB_DATA")
	)
	(segment
		(start 29.972 -70.231)
		(end 29.105098 -69.364098)
		(width 0.12065)
		(layer "F.Cu")
		(net "Z50_SSD_A1_SMB_DATA")
	)
	(segment
		(start 76.26985 -72.105774)
		(end 75.399138 -71.235062)
		(width 0.12065)
		(layer "F.Cu")
		(net "Z50_SSD_A1_SMB_DATA")
	)
	(via
		(at 29.972 -70.231)
		(size 0.508)
		(drill 0.254)
		(layers "F.Cu" "B.Cu")
		(net "Z50_SSD_A1_SMB_DATA")
	)
	(via
		(at 66.756026 -53.040026)
		(size 0.508)
		(drill 0.254)
		(layers "F.Cu" "B.Cu")
		(net "Z50_SSD_A1_SMB_DATA")
	)
	(via
		(at 23.495 -75.819)
		(size 0.508)
		(drill 0.254)
		(layers "F.Cu" "B.Cu")
		(net "Z50_SSD_A1_SMB_DATA")
	)
	(via
		(at 25.146 -70.485)
		(size 0.508)
		(drill 0.254)
		(layers "F.Cu" "B.Cu")
		(net "Z50_SSD_A1_SMB_DATA")
	)
	(via
		(at 64.135 -53.721)
		(size 0.7112)
		(drill 0.3556)
		(layers "F.Cu" "B.Cu")
		(net "Z50_SSD_A1_SMB_DATA")
	)
	(segment
		(start 64.135 -53.721)
		(end 66.075052 -53.721)
		(width 0.12065)
		(layer "B.Cu")
		(net "Z50_SSD_A1_SMB_DATA")
	)
	(segment
		(start 56.956198 -67.094608)
		(end 56.956198 -58.38952)
		(width 0.12065)
		(layer "B.Cu")
		(net "Z50_SSD_A1_SMB_DATA")
	)
	(segment
		(start 56.956198 -58.38952)
		(end 61.624718 -53.721)
		(width 0.12065)
		(layer "B.Cu")
		(net "Z50_SSD_A1_SMB_DATA")
	)
	(segment
		(start 66.075052 -53.721)
		(end 66.756026 -53.040026)
		(width 0.12065)
		(layer "B.Cu")
		(net "Z50_SSD_A1_SMB_DATA")
	)
	(segment
		(start 61.624718 -53.721)
		(end 64.135 -53.721)
		(width 0.12065)
		(layer "B.Cu")
		(net "Z50_SSD_A1_SMB_DATA")
	)
	(segment
		(start 23.495 -76.7715)
		(end 23.495 -75.819)
		(width 0.12065)
		(layer "B.Cu")
		(net "Z50_SSD_A1_SMB_DATA")
	)
	(segment
		(start 54.940962 -69.109844)
		(end 56.956198 -67.094608)
		(width 0.12065)
		(layer "B.Cu")
		(net "Z50_SSD_A1_SMB_DATA")
	)
	(segment
		(start 25.146 -71.3105)
		(end 25.146 -70.485)
		(width 0.12065)
		(layer "B.Cu")
		(net "Z50_SSD_A1_SMB_DATA")
	)
	(segment
		(start 29.972 -70.231)
		(end 31.093156 -69.109844)
		(width 0.12065)
		(layer "B.Cu")
		(net "Z50_SSD_A1_SMB_DATA")
	)
	(segment
		(start 31.093156 -69.109844)
		(end 54.940962 -69.109844)
		(width 0.12065)
		(layer "B.Cu")
		(net "Z50_SSD_A1_SMB_DATA")
	)
	(segment
		(start 24.114252 -75.18654)
		(end 23.495 -75.805792)
		(width 0.12065)
		(layer "In2.Cu")
		(net "Z50_SSD_A1_SMB_DATA")
	)
	(segment
		(start 24.114252 -71.516748)
		(end 24.114252 -75.18654)
		(width 0.12065)
		(layer "In2.Cu")
		(net "Z50_SSD_A1_SMB_DATA")
	)
	(segment
		(start 23.495 -75.805792)
		(end 23.495 -75.819)
		(width 0.12065)
		(layer "In2.Cu")
		(net "Z50_SSD_A1_SMB_DATA")
	)
	(segment
		(start 25.146 -70.485)
		(end 24.114252 -71.516748)
		(width 0.12065)
		(layer "In2.Cu")
		(net "Z50_SSD_A1_SMB_DATA")
	)
	(segment
		(start 30.226 -79.1845)
		(end 30.226 -79.72552)
		(width 0.12065)
		(layer "F.Cu")
		(net "Z50_SSD_A1_SMB_CLK_R")
	)
	(segment
		(start 30.51048 -81.302606)
		(end 30.51048 -80.01)
		(width 0.12065)
		(layer "F.Cu")
		(net "Z50_SSD_A1_SMB_CLK_R")
	)
	(segment
		(start 30.226 -79.72552)
		(end 30.51048 -80.01)
		(width 0.12065)
		(layer "F.Cu")
		(net "Z50_SSD_A1_SMB_CLK_R")
	)
	(via
		(at 30.099 -80.899)
		(size 0.7112)
		(drill 0.3556)
		(layers "F.Cu" "B.Cu")
		(net "Z50_SSD_A1_SMB_CLK_R")
	)
	(via
		(at 23.241 -79.375)
		(size 0.508)
		(drill 0.254)
		(layers "F.Cu" "B.Cu")
		(net "Z50_SSD_A1_SMB_CLK_R")
	)
	(via
		(at 30.51048 -80.01)
		(size 0.508)
		(drill 0.254)
		(layers "F.Cu" "B.Cu")
		(net "Z50_SSD_A1_SMB_CLK_R")
	)
	(segment
		(start 30.226 -79.72552)
		(end 30.51048 -80.01)
		(width 0.12065)
		(layer "B.Cu")
		(net "Z50_SSD_A1_SMB_CLK_R")
	)
	(segment
		(start 24.511 -78.359)
		(end 24.511 -77.6605)
		(width 0.12065)
		(layer "B.Cu")
		(net "Z50_SSD_A1_SMB_CLK_R")
	)
	(segment
		(start 30.51048 -80.48752)
		(end 30.099 -80.899)
		(width 0.12065)
		(layer "B.Cu")
		(net "Z50_SSD_A1_SMB_CLK_R")
	)
	(segment
		(start 30.226 -79.1845)
		(end 30.226 -79.72552)
		(width 0.12065)
		(layer "B.Cu")
		(net "Z50_SSD_A1_SMB_CLK_R")
	)
	(segment
		(start 23.495 -79.375)
		(end 24.511 -78.359)
		(width 0.12065)
		(layer "B.Cu")
		(net "Z50_SSD_A1_SMB_CLK_R")
	)
	(segment
		(start 23.241 -79.375)
		(end 23.495 -79.375)
		(width 0.12065)
		(layer "B.Cu")
		(net "Z50_SSD_A1_SMB_CLK_R")
	)
	(segment
		(start 30.51048 -80.01)
		(end 30.51048 -80.48752)
		(width 0.12065)
		(layer "B.Cu")
		(net "Z50_SSD_A1_SMB_CLK_R")
	)
	(segment
		(start 23.241 -79.375)
		(end 23.241 -80.071468)
		(width 0.12065)
		(layer "In2.Cu")
		(net "Z50_SSD_A1_SMB_CLK_R")
	)
	(segment
		(start 25.824434 -82.654902)
		(end 27.865578 -82.654902)
		(width 0.12065)
		(layer "In2.Cu")
		(net "Z50_SSD_A1_SMB_CLK_R")
	)
	(segment
		(start 23.241 -80.071468)
		(end 25.824434 -82.654902)
		(width 0.12065)
		(layer "In2.Cu")
		(net "Z50_SSD_A1_SMB_CLK_R")
	)
	(segment
		(start 27.865578 -82.654902)
		(end 30.51048 -80.01)
		(width 0.12065)
		(layer "In2.Cu")
		(net "Z50_SSD_A1_SMB_CLK_R")
	)
	(segment
		(start 25.390348 -69.224652)
		(end 26.891996 -69.224652)
		(width 0.12065)
		(layer "F.Cu")
		(net "Z50_SSD_A1_SMB_CLK")
	)
	(segment
		(start 72.193912 -71.736712)
		(end 68.833746 -68.376546)
		(width 0.12065)
		(layer "F.Cu")
		(net "Z50_SSD_A1_SMB_CLK")
	)
	(segment
		(start 68.2498 -61.214)
		(end 66.929 -59.8932)
		(width 0.12065)
		(layer "F.Cu")
		(net "Z50_SSD_A1_SMB_CLK")
	)
	(segment
		(start 75.7682 -75.3872)
		(end 75.7682 -72.3138)
		(width 0.12065)
		(layer "F.Cu")
		(net "Z50_SSD_A1_SMB_CLK")
	)
	(segment
		(start 29.492448 -68.862448)
		(end 30.861 -70.231)
		(width 0.12065)
		(layer "F.Cu")
		(net "Z50_SSD_A1_SMB_CLK")
	)
	(segment
		(start 68.833746 -68.376546)
		(end 68.833746 -67.961002)
		(width 0.12065)
		(layer "F.Cu")
		(net "Z50_SSD_A1_SMB_CLK")
	)
	(segment
		(start 24.13 -70.485)
		(end 25.390348 -69.224652)
		(width 0.12065)
		(layer "F.Cu")
		(net "Z50_SSD_A1_SMB_CLK")
	)
	(segment
		(start 76.708 -76.327)
		(end 75.7682 -75.3872)
		(width 0.12065)
		(layer "F.Cu")
		(net "Z50_SSD_A1_SMB_CLK")
	)
	(segment
		(start 75.191112 -71.736712)
		(end 72.193912 -71.736712)
		(width 0.12065)
		(layer "F.Cu")
		(net "Z50_SSD_A1_SMB_CLK")
	)
	(segment
		(start 66.802 -53.975)
		(end 66.366898 -53.539898)
		(width 0.12065)
		(layer "F.Cu")
		(net "Z50_SSD_A1_SMB_CLK")
	)
	(segment
		(start 66.366898 -53.539898)
		(end 65.174876 -53.539898)
		(width 0.12065)
		(layer "F.Cu")
		(net "Z50_SSD_A1_SMB_CLK")
	)
	(segment
		(start 68.2498 -62.8904)
		(end 68.2498 -61.214)
		(width 0.12065)
		(layer "F.Cu")
		(net "Z50_SSD_A1_SMB_CLK")
	)
	(segment
		(start 66.929 -59.8932)
		(end 66.929 -54.102)
		(width 0.12065)
		(layer "F.Cu")
		(net "Z50_SSD_A1_SMB_CLK")
	)
	(segment
		(start 75.7682 -72.3138)
		(end 75.191112 -71.736712)
		(width 0.12065)
		(layer "F.Cu")
		(net "Z50_SSD_A1_SMB_CLK")
	)
	(segment
		(start 26.891996 -69.224652)
		(end 27.2542 -68.862448)
		(width 0.12065)
		(layer "F.Cu")
		(net "Z50_SSD_A1_SMB_CLK")
	)
	(segment
		(start 68.833746 -67.961002)
		(end 68.834 -67.960748)
		(width 0.12065)
		(layer "F.Cu")
		(net "Z50_SSD_A1_SMB_CLK")
	)
	(segment
		(start 68.834 -67.960748)
		(end 68.834 -63.4746)
		(width 0.12065)
		(layer "F.Cu")
		(net "Z50_SSD_A1_SMB_CLK")
	)
	(segment
		(start 27.2542 -68.862448)
		(end 29.492448 -68.862448)
		(width 0.12065)
		(layer "F.Cu")
		(net "Z50_SSD_A1_SMB_CLK")
	)
	(segment
		(start 66.929 -54.102)
		(end 66.802 -53.975)
		(width 0.12065)
		(layer "F.Cu")
		(net "Z50_SSD_A1_SMB_CLK")
	)
	(segment
		(start 24.13 -71.3105)
		(end 24.13 -70.485)
		(width 0.12065)
		(layer "F.Cu")
		(net "Z50_SSD_A1_SMB_CLK")
	)
	(segment
		(start 68.834 -63.4746)
		(end 68.2498 -62.8904)
		(width 0.12065)
		(layer "F.Cu")
		(net "Z50_SSD_A1_SMB_CLK")
	)
	(via
		(at 66.802 -53.975)
		(size 0.508)
		(drill 0.254)
		(layers "F.Cu" "B.Cu")
		(net "Z50_SSD_A1_SMB_CLK")
	)
	(via
		(at 23.495 -74.93)
		(size 0.508)
		(drill 0.254)
		(layers "F.Cu" "B.Cu")
		(net "Z50_SSD_A1_SMB_CLK")
	)
	(via
		(at 30.861 -70.231)
		(size 0.508)
		(drill 0.254)
		(layers "F.Cu" "B.Cu")
		(net "Z50_SSD_A1_SMB_CLK")
	)
	(via
		(at 65.151 -54.483)
		(size 0.7112)
		(drill 0.3556)
		(layers "F.Cu" "B.Cu")
		(net "Z50_SSD_A1_SMB_CLK")
	)
	(via
		(at 24.13 -70.485)
		(size 0.508)
		(drill 0.254)
		(layers "F.Cu" "B.Cu")
		(net "Z50_SSD_A1_SMB_CLK")
	)
	(segment
		(start 24.13 -71.3105)
		(end 24.13 -70.485)
		(width 0.12065)
		(layer "B.Cu")
		(net "Z50_SSD_A1_SMB_CLK")
	)
	(segment
		(start 57.457848 -58.597546)
		(end 61.572394 -54.483)
		(width 0.12065)
		(layer "B.Cu")
		(net "Z50_SSD_A1_SMB_CLK")
	)
	(segment
		(start 61.572394 -54.483)
		(end 65.151 -54.483)
		(width 0.12065)
		(layer "B.Cu")
		(net "Z50_SSD_A1_SMB_CLK")
	)
	(segment
		(start 30.861 -70.231)
		(end 31.480506 -69.611494)
		(width 0.12065)
		(layer "B.Cu")
		(net "Z50_SSD_A1_SMB_CLK")
	)
	(segment
		(start 24.511 -75.946)
		(end 23.495 -74.93)
		(width 0.12065)
		(layer "B.Cu")
		(net "Z50_SSD_A1_SMB_CLK")
	)
	(segment
		(start 57.457848 -67.302634)
		(end 57.457848 -58.597546)
		(width 0.12065)
		(layer "B.Cu")
		(net "Z50_SSD_A1_SMB_CLK")
	)
	(segment
		(start 66.294 -54.483)
		(end 65.151 -54.483)
		(width 0.12065)
		(layer "B.Cu")
		(net "Z50_SSD_A1_SMB_CLK")
	)
	(segment
		(start 31.480506 -69.611494)
		(end 55.148988 -69.611494)
		(width 0.12065)
		(layer "B.Cu")
		(net "Z50_SSD_A1_SMB_CLK")
	)
	(segment
		(start 24.511 -76.7715)
		(end 24.511 -75.946)
		(width 0.12065)
		(layer "B.Cu")
		(net "Z50_SSD_A1_SMB_CLK")
	)
	(segment
		(start 55.148988 -69.611494)
		(end 57.457848 -67.302634)
		(width 0.12065)
		(layer "B.Cu")
		(net "Z50_SSD_A1_SMB_CLK")
	)
	(segment
		(start 66.802 -53.975)
		(end 66.294 -54.483)
		(width 0.12065)
		(layer "B.Cu")
		(net "Z50_SSD_A1_SMB_CLK")
	)
	(segment
		(start 23.612602 -74.812398)
		(end 23.612602 -71.308722)
		(width 0.12065)
		(layer "In2.Cu")
		(net "Z50_SSD_A1_SMB_CLK")
	)
	(segment
		(start 24.13 -70.791324)
		(end 24.13 -70.485)
		(width 0.12065)
		(layer "In2.Cu")
		(net "Z50_SSD_A1_SMB_CLK")
	)
	(segment
		(start 23.495 -74.93)
		(end 23.612602 -74.812398)
		(width 0.12065)
		(layer "In2.Cu")
		(net "Z50_SSD_A1_SMB_CLK")
	)
	(segment
		(start 23.612602 -71.308722)
		(end 24.13 -70.791324)
		(width 0.12065)
		(layer "In2.Cu")
		(net "Z50_SSD_A1_SMB_CLK")
	)
	(segment
		(start 66.300096 -50.539904)
		(end 66.802 -50.038)
		(width 0.12065)
		(layer "F.Cu")
		(net "Z50_SSD_A1_CLKREQ#")
	)
	(segment
		(start 65.174876 -50.539904)
		(end 66.300096 -50.539904)
		(width 0.12065)
		(layer "F.Cu")
		(net "Z50_SSD_A1_CLKREQ#")
	)
	(via
		(at 65.151 -51.054)
		(size 0.7112)
		(drill 0.3556)
		(layers "F.Cu" "B.Cu")
		(net "Z50_SSD_A1_CLKREQ#")
	)
	(via
		(at 66.802 -50.038)
		(size 0.508)
		(drill 0.254)
		(layers "F.Cu" "B.Cu")
		(net "Z50_SSD_A1_CLKREQ#")
	)
	(segment
		(start 65.5955 -50.6095)
		(end 65.5955 -50.038)
		(width 0.12065)
		(layer "B.Cu")
		(net "Z50_SSD_A1_CLKREQ#")
	)
	(segment
		(start 65.5955 -50.038)
		(end 66.802 -50.038)
		(width 0.12065)
		(layer "B.Cu")
		(net "Z50_SSD_A1_CLKREQ#")
	)
	(segment
		(start 65.151 -51.054)
		(end 65.5955 -50.6095)
		(width 0.12065)
		(layer "B.Cu")
		(net "Z50_SSD_A1_CLKREQ#")
	)
	(segment
		(start 65.174876 -52.5399)
		(end 66.3321 -52.5399)
		(width 0.12065)
		(layer "F.Cu")
		(net "Z50_SSD_A1_ALERT#")
	)
	(segment
		(start 66.3321 -52.5399)
		(end 66.802 -52.07)
		(width 0.12065)
		(layer "F.Cu")
		(net "Z50_SSD_A1_ALERT#")
	)
	(via
		(at 66.802 -52.07)
		(size 0.508)
		(drill 0.254)
		(layers "F.Cu" "B.Cu")
		(net "Z50_SSD_A1_ALERT#")
	)
	(via
		(at 65.151 -52.959)
		(size 0.7112)
		(drill 0.3556)
		(layers "F.Cu" "B.Cu")
		(net "Z50_SSD_A1_ALERT#")
	)
	(segment
		(start 65.5955 -52.5145)
		(end 65.151 -52.959)
		(width 0.12065)
		(layer "B.Cu")
		(net "Z50_SSD_A1_ALERT#")
	)
	(segment
		(start 65.5955 -52.07)
		(end 66.802 -52.07)
		(width 0.12065)
		(layer "B.Cu")
		(net "Z50_SSD_A1_ALERT#")
	)
	(segment
		(start 65.5955 -52.07)
		(end 65.5955 -52.5145)
		(width 0.12065)
		(layer "B.Cu")
		(net "Z50_SSD_A1_ALERT#")
	)
	(segment
		(start 25.4635 -82.55)
		(end 25.667208 -82.753708)
		(width 0.12065)
		(layer "F.Cu")
		(net "Z50_SMB_SWITCH_RESET#")
	)
	(segment
		(start 25.4635 -83.5025)
		(end 24.511 -84.455)
		(width 0.12065)
		(layer "F.Cu")
		(net "Z50_SMB_SWITCH_RESET#")
	)
	(segment
		(start 27.723846 -82.753708)
		(end 28.55976 -81.917794)
		(width 0.12065)
		(layer "F.Cu")
		(net "Z50_SMB_SWITCH_RESET#")
	)
	(segment
		(start 25.667208 -82.753708)
		(end 27.723846 -82.753708)
		(width 0.12065)
		(layer "F.Cu")
		(net "Z50_SMB_SWITCH_RESET#")
	)
	(segment
		(start 28.55976 -81.917794)
		(end 28.55976 -81.302606)
		(width 0.12065)
		(layer "F.Cu")
		(net "Z50_SMB_SWITCH_RESET#")
	)
	(segment
		(start 25.4635 -82.55)
		(end 25.4635 -83.5025)
		(width 0.12065)
		(layer "F.Cu")
		(net "Z50_SMB_SWITCH_RESET#")
	)
	(via
		(at 24.511 -84.455)
		(size 0.7112)
		(drill 0.3556)
		(layers "F.Cu" "B.Cu")
		(net "Z50_SMB_SWITCH_RESET#")
	)
	(segment
		(start 27.90952 -81.302606)
		(end 27.90952 -81.858358)
		(width 0.12065)
		(layer "F.Cu")
		(net "Z50_SMB_SWITCH_ADDRESS_A1")
	)
	(segment
		(start 27.51582 -82.252058)
		(end 27.00528 -82.252058)
		(width 0.12065)
		(layer "F.Cu")
		(net "Z50_SMB_SWITCH_ADDRESS_A1")
	)
	(segment
		(start 25.4635 -81.534)
		(end 26.289 -81.534)
		(width 0.12065)
		(layer "F.Cu")
		(net "Z50_SMB_SWITCH_ADDRESS_A1")
	)
	(segment
		(start 26.895298 -82.140298)
		(end 26.289 -81.534)
		(width 0.12065)
		(layer "F.Cu")
		(net "Z50_SMB_SWITCH_ADDRESS_A1")
	)
	(segment
		(start 26.895298 -82.142076)
		(end 26.895298 -82.140298)
		(width 0.12065)
		(layer "F.Cu")
		(net "Z50_SMB_SWITCH_ADDRESS_A1")
	)
	(segment
		(start 27.90952 -81.858358)
		(end 27.51582 -82.252058)
		(width 0.12065)
		(layer "F.Cu")
		(net "Z50_SMB_SWITCH_ADDRESS_A1")
	)
	(segment
		(start 27.00528 -82.252058)
		(end 26.895298 -82.142076)
		(width 0.12065)
		(layer "F.Cu")
		(net "Z50_SMB_SWITCH_ADDRESS_A1")
	)
	(via
		(at 26.289 -81.534)
		(size 0.508)
		(drill 0.254)
		(layers "F.Cu" "B.Cu")
		(net "Z50_SMB_SWITCH_ADDRESS_A1")
	)
	(via
		(at 25.4635 -82.4865)
		(size 0.7112)
		(drill 0.3556)
		(layers "F.Cu" "B.Cu")
		(net "Z50_SMB_SWITCH_ADDRESS_A1")
	)
	(segment
		(start 25.4635 -81.534)
		(end 26.289 -81.534)
		(width 0.12065)
		(layer "B.Cu")
		(net "Z50_SMB_SWITCH_ADDRESS_A1")
	)
	(segment
		(start 25.4635 -81.534)
		(end 25.4635 -82.4865)
		(width 0.12065)
		(layer "B.Cu")
		(net "Z50_SMB_SWITCH_ADDRESS_A1")
	)
	(segment
		(start 25.4635 -80.518)
		(end 26.289 -80.518)
		(width 0.12065)
		(layer "F.Cu")
		(net "Z50_SMB_SWITCH_ADDRESS_A0")
	)
	(segment
		(start 27.073606 -81.302606)
		(end 26.289 -80.518)
		(width 0.12065)
		(layer "F.Cu")
		(net "Z50_SMB_SWITCH_ADDRESS_A0")
	)
	(segment
		(start 27.26055 -81.302606)
		(end 27.073606 -81.302606)
		(width 0.12065)
		(layer "F.Cu")
		(net "Z50_SMB_SWITCH_ADDRESS_A0")
	)
	(via
		(at 27.2542 -80.518)
		(size 0.7112)
		(drill 0.3556)
		(layers "F.Cu" "B.Cu")
		(net "Z50_SMB_SWITCH_ADDRESS_A0")
	)
	(via
		(at 26.289 -80.518)
		(size 0.508)
		(drill 0.254)
		(layers "F.Cu" "B.Cu")
		(net "Z50_SMB_SWITCH_ADDRESS_A0")
	)
	(segment
		(start 26.289 -80.518)
		(end 27.2542 -80.518)
		(width 0.12065)
		(layer "B.Cu")
		(net "Z50_SMB_SWITCH_ADDRESS_A0")
	)
	(segment
		(start 25.4635 -80.518)
		(end 26.289 -80.518)
		(width 0.12065)
		(layer "B.Cu")
		(net "Z50_SMB_SWITCH_ADDRESS_A0")
	)
	(segment
		(start 17.66062 -78.165706)
		(end 17.66062 -78.635606)
		(width 0.254)
		(layer "F.Cu")
		(net "P1V8_PWR_SS_C")
	)
	(segment
		(start 16.8529 -77.924406)
		(end 17.41932 -77.924406)
		(width 0.254)
		(layer "F.Cu")
		(net "P1V8_PWR_SS_C")
	)
	(segment
		(start 15.1765 -77.073506)
		(end 16.002 -77.073506)
		(width 0.254)
		(layer "F.Cu")
		(net "P1V8_PWR_SS_C")
	)
	(segment
		(start 16.002 -77.073506)
		(end 16.8529 -77.924406)
		(width 0.254)
		(layer "F.Cu")
		(net "P1V8_PWR_SS_C")
	)
	(segment
		(start 14.986 -77.264006)
		(end 15.1765 -77.073506)
		(width 0.254)
		(layer "F.Cu")
		(net "P1V8_PWR_SS_C")
	)
	(segment
		(start 17.41932 -77.924406)
		(end 17.66062 -78.165706)
		(width 0.254)
		(layer "F.Cu")
		(net "P1V8_PWR_SS_C")
	)
	(via
		(at 14.986 -77.264006)
		(size 0.7112)
		(drill 0.3556)
		(layers "F.Cu" "B.Cu")
		(net "P1V8_PWR_SS_C")
	)
	(segment
		(start 18.161 -81.734406)
		(end 18.161 -83.677506)
		(width 0.254)
		(layer "F.Cu")
		(net "P1V8_PWR_GD")
	)
	(segment
		(start 17.5387 -83.982306)
		(end 17.5387 -85.887306)
		(width 0.254)
		(layer "F.Cu")
		(net "P1V8_PWR_GD")
	)
	(segment
		(start 18.161 -83.677506)
		(end 17.8435 -83.677506)
		(width 0.254)
		(layer "F.Cu")
		(net "P1V8_PWR_GD")
	)
	(segment
		(start 17.8435 -83.677506)
		(end 17.5387 -83.982306)
		(width 0.254)
		(layer "F.Cu")
		(net "P1V8_PWR_GD")
	)
	(segment
		(start 17.272 -86.9315)
		(end 17.9705 -87.63)
		(width 0.254)
		(layer "F.Cu")
		(net "P1V8_PWR_GD")
	)
	(segment
		(start 17.5387 -85.887306)
		(end 17.272 -86.154006)
		(width 0.254)
		(layer "F.Cu")
		(net "P1V8_PWR_GD")
	)
	(segment
		(start 17.272 -86.154006)
		(end 17.272 -86.9315)
		(width 0.254)
		(layer "F.Cu")
		(net "P1V8_PWR_GD")
	)
	(segment
		(start 17.0815 -74.851006)
		(end 17.0815 -75.867006)
		(width 0.254)
		(layer "F.Cu")
		(net "P1V8_PWR_FB")
	)
	(segment
		(start 16.9545 -73.581006)
		(end 16.9545 -74.724006)
		(width 0.254)
		(layer "F.Cu")
		(net "P1V8_PWR_FB")
	)
	(segment
		(start 16.9545 -74.724006)
		(end 17.0815 -74.851006)
		(width 0.254)
		(layer "F.Cu")
		(net "P1V8_PWR_FB")
	)
	(segment
		(start 17.0815 -75.867006)
		(end 17.0815 -76.883006)
		(width 0.254)
		(layer "F.Cu")
		(net "P1V8_PWR_FB")
	)
	(segment
		(start 18.161 -78.026006)
		(end 18.161 -78.635606)
		(width 0.254)
		(layer "F.Cu")
		(net "P1V8_PWR_FB")
	)
	(segment
		(start 17.0815 -76.946506)
		(end 18.161 -78.026006)
		(width 0.254)
		(layer "F.Cu")
		(net "P1V8_PWR_FB")
	)
	(segment
		(start 17.0815 -76.883006)
		(end 17.0815 -76.946506)
		(width 0.254)
		(layer "F.Cu")
		(net "P1V8_PWR_FB")
	)
	(via
		(at 16.9545 -73.581006)
		(size 0.7112)
		(drill 0.3556)
		(layers "F.Cu" "B.Cu")
		(net "P1V8_PWR_FB")
	)
	(segment
		(start 16.29791 -82.598006)
		(end 17.16151 -81.734406)
		(width 0.254)
		(layer "F.Cu")
		(net "P1V8_PWR_EN_R")
	)
	(segment
		(start 14.732 -81.455006)
		(end 13.589 -81.455006)
		(width 0.254)
		(layer "F.Cu")
		(net "P1V8_PWR_EN_R")
	)
	(segment
		(start 15.1765 -81.899506)
		(end 15.1765 -82.598006)
		(width 0.254)
		(layer "F.Cu")
		(net "P1V8_PWR_EN_R")
	)
	(segment
		(start 15.1765 -82.598006)
		(end 16.29791 -82.598006)
		(width 0.254)
		(layer "F.Cu")
		(net "P1V8_PWR_EN_R")
	)
	(segment
		(start 14.732 -81.455006)
		(end 15.1765 -81.899506)
		(width 0.254)
		(layer "F.Cu")
		(net "P1V8_PWR_EN_R")
	)
	(via
		(at 13.589 -81.455006)
		(size 0.7112)
		(drill 0.3556)
		(layers "F.Cu" "B.Cu")
		(net "P1V8_PWR_EN_R")
	)
	(segment
		(start 16.7132 -83.18754)
		(end 17.66062 -82.24012)
		(width 0.3048)
		(layer "F.Cu")
		(net "P1V8_PWR_BIAS")
	)
	(segment
		(start 17.66062 -82.24012)
		(end 17.66062 -81.734406)
		(width 0.3048)
		(layer "F.Cu")
		(net "P1V8_PWR_BIAS")
	)
	(segment
		(start 16.7132 -84.122006)
		(end 16.7132 -83.18754)
		(width 0.3048)
		(layer "F.Cu")
		(net "P1V8_PWR_BIAS")
	)
	(segment
		(start 15.748 -85.709506)
		(end 16.7132 -84.744306)
		(width 0.508)
		(layer "F.Cu")
		(net "P1V8_PWR_BIAS")
	)
	(segment
		(start 16.7132 -84.744306)
		(end 16.7132 -84.122006)
		(width 0.508)
		(layer "F.Cu")
		(net "P1V8_PWR_BIAS")
	)
	(segment
		(start 14.732 -85.709506)
		(end 15.748 -85.709506)
		(width 0.508)
		(layer "F.Cu")
		(net "P1V8_PWR_BIAS")
	)
	(via
		(at 14.732 -85.709506)
		(size 0.7112)
		(drill 0.3556)
		(layers "F.Cu" "B.Cu")
		(net "P1V8_PWR_BIAS")
	)
	(segment
		(start 56.388 -52.832)
		(end 56.388 -66.929)
		(width 0.508)
		(layer "F.Cu")
		(net "P1V8_PWR")
	)
	(segment
		(start 28.07081 -74.67981)
		(end 28.9306 -74.67981)
		(width 0.3048)
		(layer "F.Cu")
		(net "P1V8_PWR")
	)
	(segment
		(start 56.388 -66.929)
		(end 53.848 -69.469)
		(width 0.508)
		(layer "F.Cu")
		(net "P1V8_PWR")
	)
	(segment
		(start 27.813 -74.422)
		(end 28.07081 -74.67981)
		(width 0.3048)
		(layer "F.Cu")
		(net "P1V8_PWR")
	)
	(segment
		(start 53.848 -69.469)
		(end 32.639 -69.469)
		(width 0.508)
		(layer "F.Cu")
		(net "P1V8_PWR")
	)
	(segment
		(start 58.42 -29.718)
		(end 56.261 -31.877)
		(width 0.508)
		(layer "F.Cu")
		(net "P1V8_PWR")
	)
	(segment
		(start 25.65781 -77.91069)
		(end 25.4635 -78.105)
		(width 0.3048)
		(layer "F.Cu")
		(net "P1V8_PWR")
	)
	(segment
		(start 57.15 -52.07)
		(end 56.388 -52.832)
		(width 0.508)
		(layer "F.Cu")
		(net "P1V8_PWR")
	)
	(segment
		(start 56.261 -31.877)
		(end 56.261 -51.181)
		(width 0.508)
		(layer "F.Cu")
		(net "P1V8_PWR")
	)
	(segment
		(start 58.42 -24.511)
		(end 58.42 -29.718)
		(width 0.508)
		(layer "F.Cu")
		(net "P1V8_PWR")
	)
	(segment
		(start 28.0035 -72.8345)
		(end 28.575 -73.406)
		(width 0.508)
		(layer "F.Cu")
		(net "P1V8_PWR")
	)
	(segment
		(start 27.813 -72.8345)
		(end 27.813 -74.422)
		(width 0.3048)
		(layer "F.Cu")
		(net "P1V8_PWR")
	)
	(segment
		(start 56.261 -51.181)
		(end 57.15 -52.07)
		(width 0.508)
		(layer "F.Cu")
		(net "P1V8_PWR")
	)
	(segment
		(start 32.639 -69.469)
		(end 31.75 -70.358)
		(width 0.508)
		(layer "F.Cu")
		(net "P1V8_PWR")
	)
	(segment
		(start 25.65781 -76.9874)
		(end 25.65781 -77.91069)
		(width 0.3048)
		(layer "F.Cu")
		(net "P1V8_PWR")
	)
	(segment
		(start 25.4635 -78.105)
		(end 25.4635 -78.74)
		(width 0.3048)
		(layer "F.Cu")
		(net "P1V8_PWR")
	)
	(segment
		(start 25.4635 -78.74)
		(end 25.4635 -79.5528)
		(width 0.508)
		(layer "F.Cu")
		(net "P1V8_PWR")
	)
	(segment
		(start 27.813 -72.8345)
		(end 28.0035 -72.8345)
		(width 0.508)
		(layer "F.Cu")
		(net "P1V8_PWR")
	)
	(via
		(at 18.288 -73.66)
		(size 0.5588)
		(drill 0.3048)
		(layers "F.Cu" "B.Cu")
		(net "P1V8_PWR")
	)
	(via
		(at 57.15 -52.07)
		(size 0.5588)
		(drill 0.3048)
		(layers "F.Cu" "B.Cu")
		(net "P1V8_PWR")
	)
	(via
		(at 25.4635 -79.5528)
		(size 0.508)
		(drill 0.254)
		(layers "F.Cu" "B.Cu")
		(net "P1V8_PWR")
	)
	(via
		(at 58.42 -24.511)
		(size 0.5588)
		(drill 0.3048)
		(layers "F.Cu" "B.Cu")
		(net "P1V8_PWR")
	)
	(via
		(at 18.034 -74.724006)
		(size 0.7112)
		(drill 0.3556)
		(layers "F.Cu" "B.Cu")
		(net "P1V8_PWR")
	)
	(via
		(at 18.288 -72.644)
		(size 0.5588)
		(drill 0.3048)
		(layers "F.Cu" "B.Cu")
		(net "P1V8_PWR")
	)
	(via
		(at 31.75 -70.358)
		(size 0.508)
		(drill 0.254)
		(layers "F.Cu" "B.Cu")
		(net "P1V8_PWR")
	)
	(via
		(at 28.575 -73.406)
		(size 0.508)
		(drill 0.254)
		(layers "F.Cu" "B.Cu")
		(net "P1V8_PWR")
	)
	(segment
		(start 28.956 -73.025)
		(end 28.575 -73.406)
		(width 0.508)
		(layer "B.Cu")
		(net "P1V8_PWR")
	)
	(segment
		(start 31.8262 -70.4342)
		(end 31.8262 -71.6788)
		(width 0.508)
		(layer "B.Cu")
		(net "P1V8_PWR")
	)
	(segment
		(start 27.94 -72.1995)
		(end 28.956 -72.1995)
		(width 0.508)
		(layer "B.Cu")
		(net "P1V8_PWR")
	)
	(segment
		(start 25.146 -72.1995)
		(end 25.367488 -72.1995)
		(width 0.508)
		(layer "B.Cu")
		(net "P1V8_PWR")
	)
	(segment
		(start 64.7065 -52.07)
		(end 57.15 -52.07)
		(width 0.508)
		(layer "B.Cu")
		(net "P1V8_PWR")
	)
	(segment
		(start 28.956 -72.1995)
		(end 28.956 -73.025)
		(width 0.508)
		(layer "B.Cu")
		(net "P1V8_PWR")
	)
	(segment
		(start 25.146 -72.1995)
		(end 24.13 -72.1995)
		(width 0.508)
		(layer "B.Cu")
		(net "P1V8_PWR")
	)
	(segment
		(start 27.274012 -71.755)
		(end 27.718512 -72.1995)
		(width 0.508)
		(layer "B.Cu")
		(net "P1V8_PWR")
	)
	(segment
		(start 64.7065 -24.511)
		(end 58.42 -24.511)
		(width 0.508)
		(layer "B.Cu")
		(net "P1V8_PWR")
	)
	(segment
		(start 31.8262 -71.6788)
		(end 31.3055 -72.1995)
		(width 0.508)
		(layer "B.Cu")
		(net "P1V8_PWR")
	)
	(segment
		(start 25.367488 -72.1995)
		(end 25.811988 -71.755)
		(width 0.508)
		(layer "B.Cu")
		(net "P1V8_PWR")
	)
	(segment
		(start 25.811988 -71.755)
		(end 27.274012 -71.755)
		(width 0.508)
		(layer "B.Cu")
		(net "P1V8_PWR")
	)
	(segment
		(start 31.75 -70.358)
		(end 31.8262 -70.4342)
		(width 0.508)
		(layer "B.Cu")
		(net "P1V8_PWR")
	)
	(segment
		(start 27.718512 -72.1995)
		(end 27.94 -72.1995)
		(width 0.508)
		(layer "B.Cu")
		(net "P1V8_PWR")
	)
	(segment
		(start 31.3055 -72.1995)
		(end 28.956 -72.1995)
		(width 0.508)
		(layer "B.Cu")
		(net "P1V8_PWR")
	)
	(segment
		(start 25.4635 -79.5528)
		(end 25.4635 -74.549)
		(width 0.508)
		(layer "In5.Cu")
		(net "P1V8_PWR")
	)
	(segment
		(start 18.288 -73.66)
		(end 18.288 -72.644)
		(width 0.508)
		(layer "In5.Cu")
		(net "P1V8_PWR")
	)
	(segment
		(start 28.448 -73.533)
		(end 26.4795 -73.533)
		(width 0.508)
		(layer "In5.Cu")
		(net "P1V8_PWR")
	)
	(segment
		(start 22.953218 -71.091806)
		(end 23.495 -71.633588)
		(width 0.508)
		(layer "In5.Cu")
		(net "P1V8_PWR")
	)
	(segment
		(start 23.495 -72.5805)
		(end 25.4635 -74.549)
		(width 0.508)
		(layer "In5.Cu")
		(net "P1V8_PWR")
	)
	(segment
		(start 18.288 -72.644)
		(end 19.840194 -71.091806)
		(width 0.508)
		(layer "In5.Cu")
		(net "P1V8_PWR")
	)
	(segment
		(start 26.4795 -73.533)
		(end 25.4635 -74.549)
		(width 0.508)
		(layer "In5.Cu")
		(net "P1V8_PWR")
	)
	(segment
		(start 23.495 -71.633588)
		(end 23.495 -72.5805)
		(width 0.508)
		(layer "In5.Cu")
		(net "P1V8_PWR")
	)
	(segment
		(start 19.840194 -71.091806)
		(end 22.953218 -71.091806)
		(width 0.508)
		(layer "In5.Cu")
		(net "P1V8_PWR")
	)
	(segment
		(start 28.575 -73.406)
		(end 28.448 -73.533)
		(width 0.508)
		(layer "In5.Cu")
		(net "P1V8_PWR")
	)
	(via
		(at 71.882 -36.322)
		(size 0.7112)
		(drill 0.3556)
		(layers "F.Cu" "B.Cu")
		(net "Z50_SSD_ACT#")
	)
	(segment
		(start 76.581 -18.542)
		(end 78.322932 -16.800068)
		(width 0.12065)
		(layer "B.Cu")
		(net "Z50_SSD_ACT#")
	)
	(segment
		(start 71.882 -33.306258)
		(end 76.2 -28.988258)
		(width 0.12065)
		(layer "B.Cu")
		(net "Z50_SSD_ACT#")
	)
	(segment
		(start 78.322932 -16.800068)
		(end 78.82001 -16.800068)
		(width 0.12065)
		(layer "B.Cu")
		(net "Z50_SSD_ACT#")
	)
	(segment
		(start 70.11924 -39.5605)
		(end 70.11924 -39.22776)
		(width 0.12065)
		(layer "B.Cu")
		(net "Z50_SSD_ACT#")
	)
	(segment
		(start 71.882 -37.465)
		(end 71.882 -36.322)
		(width 0.12065)
		(layer "B.Cu")
		(net "Z50_SSD_ACT#")
	)
	(segment
		(start 70.11924 -39.22776)
		(end 71.882 -37.465)
		(width 0.12065)
		(layer "B.Cu")
		(net "Z50_SSD_ACT#")
	)
	(segment
		(start 71.882 -36.322)
		(end 71.882 -33.306258)
		(width 0.12065)
		(layer "B.Cu")
		(net "Z50_SSD_ACT#")
	)
	(segment
		(start 76.2 -18.923254)
		(end 76.581 -18.542)
		(width 0.12065)
		(layer "B.Cu")
		(net "Z50_SSD_ACT#")
	)
	(segment
		(start 76.2 -28.988258)
		(end 76.2 -18.923254)
		(width 0.12065)
		(layer "B.Cu")
		(net "Z50_SSD_ACT#")
	)
	(segment
		(start 64.008 -40.767)
		(end 65.532 -40.767)
		(width 0.12065)
		(layer "F.Cu")
		(net "Z50_TEMP_1_ALERT#")
	)
	(segment
		(start 63.82512 -40.58412)
		(end 64.008 -40.767)
		(width 0.12065)
		(layer "F.Cu")
		(net "Z50_TEMP_1_ALERT#")
	)
	(segment
		(start 62.63386 -40.58412)
		(end 63.82512 -40.58412)
		(width 0.12065)
		(layer "F.Cu")
		(net "Z50_TEMP_1_ALERT#")
	)
	(via
		(at 64.008 -40.767)
		(size 0.508)
		(drill 0.254)
		(layers "F.Cu" "B.Cu")
		(net "Z50_TEMP_1_ALERT#")
	)
	(segment
		(start 64.8335 -40.767)
		(end 64.008 -40.767)
		(width 0.12065)
		(layer "B.Cu")
		(net "Z50_TEMP_1_ALERT#")
	)
	(segment
		(start 60.071 -42.799)
		(end 58.77814 -42.799)
		(width 0.12065)
		(layer "F.Cu")
		(net "Z50_TEMP_1_A2")
	)
	(segment
		(start 58.77814 -42.799)
		(end 58.52414 -42.545)
		(width 0.12065)
		(layer "F.Cu")
		(net "Z50_TEMP_1_A2")
	)
	(segment
		(start 58.52414 -42.545)
		(end 58.52414 -41.23436)
		(width 0.12065)
		(layer "F.Cu")
		(net "Z50_TEMP_1_A2")
	)
	(via
		(at 61.0362 -42.799)
		(size 0.7112)
		(drill 0.3556)
		(layers "F.Cu" "B.Cu")
		(net "Z50_TEMP_1_A2")
	)
	(via
		(at 60.071 -42.799)
		(size 0.508)
		(drill 0.254)
		(layers "F.Cu" "B.Cu")
		(net "Z50_TEMP_1_A2")
	)
	(segment
		(start 61.0362 -42.799)
		(end 60.071 -42.799)
		(width 0.12065)
		(layer "B.Cu")
		(net "Z50_TEMP_1_A2")
	)
	(segment
		(start 58.244994 -42.6085)
		(end 59.260994 -42.6085)
		(width 0.12065)
		(layer "B.Cu")
		(net "Z50_TEMP_1_A2")
	)
	(segment
		(start 60.071 -42.799)
		(end 59.8805 -42.6085)
		(width 0.12065)
		(layer "B.Cu")
		(net "Z50_TEMP_1_A2")
	)
	(segment
		(start 59.8805 -42.6085)
		(end 59.260994 -42.6085)
		(width 0.12065)
		(layer "B.Cu")
		(net "Z50_TEMP_1_A2")
	)
	(segment
		(start 58.52414 -40.58412)
		(end 60.198 -40.58412)
		(width 0.12065)
		(layer "F.Cu")
		(net "Z50_TEMP_1_A1")
	)
	(via
		(at 60.198 -40.58412)
		(size 0.508)
		(drill 0.254)
		(layers "F.Cu" "B.Cu")
		(net "Z50_TEMP_1_A1")
	)
	(via
		(at 61.070998 -41.147746)
		(size 0.7112)
		(drill 0.3556)
		(layers "F.Cu" "B.Cu")
		(net "Z50_TEMP_1_A1")
	)
	(segment
		(start 61.070998 -41.147746)
		(end 60.761626 -41.147746)
		(width 0.12065)
		(layer "B.Cu")
		(net "Z50_TEMP_1_A1")
	)
	(segment
		(start 59.260994 -39.8145)
		(end 59.42838 -39.8145)
		(width 0.12065)
		(layer "B.Cu")
		(net "Z50_TEMP_1_A1")
	)
	(segment
		(start 58.244994 -39.8145)
		(end 59.260994 -39.8145)
		(width 0.12065)
		(layer "B.Cu")
		(net "Z50_TEMP_1_A1")
	)
	(segment
		(start 59.42838 -39.8145)
		(end 60.198 -40.58412)
		(width 0.12065)
		(layer "B.Cu")
		(net "Z50_TEMP_1_A1")
	)
	(segment
		(start 60.761626 -41.147746)
		(end 60.198 -40.58412)
		(width 0.12065)
		(layer "B.Cu")
		(net "Z50_TEMP_1_A1")
	)
	(segment
		(start 59.88812 -39.93388)
		(end 60.198 -39.624)
		(width 0.12065)
		(layer "F.Cu")
		(net "Z50_TEMP_1_A0")
	)
	(segment
		(start 58.52414 -39.93388)
		(end 59.88812 -39.93388)
		(width 0.12065)
		(layer "F.Cu")
		(net "Z50_TEMP_1_A0")
	)
	(via
		(at 60.198 -39.624)
		(size 0.508)
		(drill 0.254)
		(layers "F.Cu" "B.Cu")
		(net "Z50_TEMP_1_A0")
	)
	(via
		(at 61.087 -38.1)
		(size 0.7112)
		(drill 0.3556)
		(layers "F.Cu" "B.Cu")
		(net "Z50_TEMP_1_A0")
	)
	(segment
		(start 59.3725 -38.7985)
		(end 60.198 -39.624)
		(width 0.12065)
		(layer "B.Cu")
		(net "Z50_TEMP_1_A0")
	)
	(segment
		(start 61.087 -38.1)
		(end 61.087 -38.735)
		(width 0.12065)
		(layer "B.Cu")
		(net "Z50_TEMP_1_A0")
	)
	(segment
		(start 58.244994 -38.7985)
		(end 59.260994 -38.7985)
		(width 0.12065)
		(layer "B.Cu")
		(net "Z50_TEMP_1_A0")
	)
	(segment
		(start 61.087 -38.735)
		(end 60.198 -39.624)
		(width 0.12065)
		(layer "B.Cu")
		(net "Z50_TEMP_1_A0")
	)
	(segment
		(start 59.260994 -38.7985)
		(end 59.3725 -38.7985)
		(width 0.12065)
		(layer "B.Cu")
		(net "Z50_TEMP_1_A0")
	)
	(segment
		(start 70.172326 -55.763414)
		(end 69.8754 -55.466488)
		(width 0.136652)
		(layer "F.Cu")
		(net "D85_PCIE_A_RX0_P")
	)
	(segment
		(start 72.725026 -55.790084)
		(end 71.705978 -55.790084)
		(width 0.136652)
		(layer "F.Cu")
		(net "D85_PCIE_A_RX0_P")
	)
	(segment
		(start 71.497952 -55.892954)
		(end 70.485 -55.892954)
		(width 0.136652)
		(layer "F.Cu")
		(net "D85_PCIE_A_RX0_P")
	)
	(segment
		(start 71.616316 -55.827168)
		(end 71.587614 -55.85587)
		(width 0.136652)
		(layer "F.Cu")
		(net "D85_PCIE_A_RX0_P")
	)
	(via
		(at 69.8754 -55.466488)
		(size 0.508)
		(drill 0.254)
		(layers "F.Cu" "B.Cu")
		(net "D85_PCIE_A_RX0_P")
	)
	(via
		(at 82.611976 -37.47516)
		(size 0.508)
		(drill 0.254)
		(layers "F.Cu" "B.Cu")
		(net "D85_PCIE_A_RX0_P")
	)
	(arc
		(start 70.485 -55.892954)
		(mid 70.315772 -55.859292)
		(end 70.172326 -55.763414)
		(width 0.136652)
		(layer "F.Cu")
		(net "D85_PCIE_A_RX0_P")
	)
	(arc
		(start 71.587614 -55.85587)
		(mid 71.546463 -55.883303)
		(end 71.497952 -55.892954)
		(width 0.136652)
		(layer "F.Cu")
		(net "D85_PCIE_A_RX0_P")
	)
	(arc
		(start 71.705978 -55.790084)
		(mid 71.65746 -55.799717)
		(end 71.616316 -55.827168)
		(width 0.136652)
		(layer "F.Cu")
		(net "D85_PCIE_A_RX0_P")
	)
	(segment
		(start 81.380076 -37.47516)
		(end 82.611976 -37.47516)
		(width 0.136652)
		(layer "B.Cu")
		(net "D85_PCIE_A_RX0_P")
	)
	(segment
		(start 76.421996 -46.81601)
		(end 72.795638 -46.81601)
		(width 0.13335)
		(layer "In2.Cu")
		(net "D85_PCIE_A_RX0_P")
	)
	(segment
		(start 80.216756 -38.791388)
		(end 80.216756 -43.02125)
		(width 0.13335)
		(layer "In2.Cu")
		(net "D85_PCIE_A_RX0_P")
	)
	(segment
		(start 80.125316 -43.241214)
		(end 76.64196 -46.724824)
		(width 0.13335)
		(layer "In2.Cu")
		(net "D85_PCIE_A_RX0_P")
	)
	(segment
		(start 72.346566 -47.001938)
		(end 72.142858 -47.205646)
		(width 0.13335)
		(layer "In2.Cu")
		(net "D85_PCIE_A_RX0_P")
	)
	(segment
		(start 71.30415 -49.230788)
		(end 71.30415 -55.42915)
		(width 0.13335)
		(layer "In2.Cu")
		(net "D85_PCIE_A_RX0_P")
	)
	(segment
		(start 82.169 -37.713158)
		(end 81.294986 -37.713158)
		(width 0.13335)
		(layer "In2.Cu")
		(net "D85_PCIE_A_RX0_P")
	)
	(segment
		(start 70.869556 -55.86349)
		(end 70.485 -55.86349)
		(width 0.13335)
		(layer "In2.Cu")
		(net "D85_PCIE_A_RX0_P")
	)
	(segment
		(start 80.845914 -37.899086)
		(end 80.402684 -38.342316)
		(width 0.13335)
		(layer "In2.Cu")
		(net "D85_PCIE_A_RX0_P")
	)
	(segment
		(start 70.122034 -55.713122)
		(end 69.8754 -55.466488)
		(width 0.13335)
		(layer "In2.Cu")
		(net "D85_PCIE_A_RX0_P")
	)
	(segment
		(start 82.611976 -37.47516)
		(end 82.518758 -37.568124)
		(width 0.13335)
		(layer "In2.Cu")
		(net "D85_PCIE_A_RX0_P")
	)
	(arc
		(start 80.402684 -38.342316)
		(mid 80.265069 -38.548366)
		(end 80.216756 -38.791388)
		(width 0.13335)
		(layer "In2.Cu")
		(net "D85_PCIE_A_RX0_P")
	)
	(arc
		(start 82.518758 -37.568124)
		(mid 82.358303 -37.67543)
		(end 82.169 -37.713158)
		(width 0.13335)
		(layer "In2.Cu")
		(net "D85_PCIE_A_RX0_P")
	)
	(arc
		(start 70.485 -55.86349)
		(mid 70.288556 -55.824415)
		(end 70.122034 -55.713122)
		(width 0.13335)
		(layer "In2.Cu")
		(net "D85_PCIE_A_RX0_P")
	)
	(arc
		(start 72.795638 -46.81601)
		(mid 72.55262 -46.864331)
		(end 72.346566 -47.001938)
		(width 0.13335)
		(layer "In2.Cu")
		(net "D85_PCIE_A_RX0_P")
	)
	(arc
		(start 71.30415 -55.42915)
		(mid 71.271024 -55.595214)
		(end 71.176896 -55.735982)
		(width 0.13335)
		(layer "In2.Cu")
		(net "D85_PCIE_A_RX0_P")
	)
	(arc
		(start 76.64196 -46.724824)
		(mid 76.54104 -46.792286)
		(end 76.421996 -46.81601)
		(width 0.13335)
		(layer "In2.Cu")
		(net "D85_PCIE_A_RX0_P")
	)
	(arc
		(start 72.142858 -47.205646)
		(mid 71.522107 -48.134804)
		(end 71.30415 -49.230788)
		(width 0.13335)
		(layer "In2.Cu")
		(net "D85_PCIE_A_RX0_P")
	)
	(arc
		(start 80.216756 -43.02125)
		(mid 80.192871 -43.140297)
		(end 80.125316 -43.241214)
		(width 0.13335)
		(layer "In2.Cu")
		(net "D85_PCIE_A_RX0_P")
	)
	(arc
		(start 81.294986 -37.713158)
		(mid 81.051968 -37.761479)
		(end 80.845914 -37.899086)
		(width 0.13335)
		(layer "In2.Cu")
		(net "D85_PCIE_A_RX0_P")
	)
	(arc
		(start 71.176896 -55.735982)
		(mid 71.035917 -55.830338)
		(end 70.869556 -55.86349)
		(width 0.13335)
		(layer "In2.Cu")
		(net "D85_PCIE_A_RX0_P")
	)
	(segment
		(start 74.8665 -63.246)
		(end 74.8665 -63.5635)
		(width 0.12065)
		(layer "F.Cu")
		(net "Z50_SSD_A_PRESENT_R#")
	)
	(segment
		(start 73.860152 -63.289942)
		(end 72.725026 -63.289942)
		(width 0.12065)
		(layer "F.Cu")
		(net "Z50_SSD_A_PRESENT_R#")
	)
	(segment
		(start 74.8665 -63.5635)
		(end 75.819 -64.516)
		(width 0.12065)
		(layer "F.Cu")
		(net "Z50_SSD_A_PRESENT_R#")
	)
	(segment
		(start 74.8665 -63.246)
		(end 73.904094 -63.246)
		(width 0.12065)
		(layer "F.Cu")
		(net "Z50_SSD_A_PRESENT_R#")
	)
	(segment
		(start 73.904094 -63.246)
		(end 73.860152 -63.289942)
		(width 0.12065)
		(layer "F.Cu")
		(net "Z50_SSD_A_PRESENT_R#")
	)
	(via
		(at 75.819 -64.516)
		(size 0.7112)
		(drill 0.3556)
		(layers "F.Cu" "B.Cu")
		(net "Z50_SSD_A_PRESENT_R#")
	)
	(segment
		(start 74.488294 -35.689794)
		(end 75.184 -36.3855)
		(width 0.12065)
		(layer "F.Cu")
		(net "Z50_SSD_B_PRESENT_R#")
	)
	(segment
		(start 76.073 -36.8046)
		(end 75.6031 -36.8046)
		(width 0.12065)
		(layer "F.Cu")
		(net "Z50_SSD_B_PRESENT_R#")
	)
	(segment
		(start 72.725026 -35.689794)
		(end 74.488294 -35.689794)
		(width 0.12065)
		(layer "F.Cu")
		(net "Z50_SSD_B_PRESENT_R#")
	)
	(segment
		(start 75.6031 -36.8046)
		(end 75.184 -36.3855)
		(width 0.12065)
		(layer "F.Cu")
		(net "Z50_SSD_B_PRESENT_R#")
	)
	(via
		(at 76.073 -36.8046)
		(size 0.7112)
		(drill 0.3556)
		(layers "F.Cu" "B.Cu")
		(net "Z50_SSD_B_PRESENT_R#")
	)
	(segment
		(start 50.601118 -79.398876)
		(end 51.005994 -78.994)
		(width 0.254)
		(layer "F.Cu")
		(net "P3V3_DEV_PWRGD")
	)
	(segment
		(start 41.226994 -74.422)
		(end 41.226994 -75.819)
		(width 0.254)
		(layer "F.Cu")
		(net "P3V3_DEV_PWRGD")
	)
	(segment
		(start 42.687494 -75.819)
		(end 42.750994 -75.7555)
		(width 0.254)
		(layer "F.Cu")
		(net "P3V3_DEV_PWRGD")
	)
	(segment
		(start 49.645316 -79.398876)
		(end 50.601118 -79.398876)
		(width 0.254)
		(layer "F.Cu")
		(net "P3V3_DEV_PWRGD")
	)
	(segment
		(start 41.226994 -75.819)
		(end 42.687494 -75.819)
		(width 0.254)
		(layer "F.Cu")
		(net "P3V3_DEV_PWRGD")
	)
	(via
		(at 51.539394 -75.311)
		(size 0.7112)
		(drill 0.3556)
		(layers "F.Cu" "B.Cu")
		(net "P3V3_DEV_PWRGD")
	)
	(via
		(at 51.005994 -78.994)
		(size 0.5588)
		(drill 0.3048)
		(layers "F.Cu" "B.Cu")
		(net "P3V3_DEV_PWRGD")
	)
	(via
		(at 41.226994 -74.422)
		(size 0.5588)
		(drill 0.3048)
		(layers "F.Cu" "B.Cu")
		(net "P3V3_DEV_PWRGD")
	)
	(segment
		(start 41.811194 -73.8378)
		(end 41.226994 -74.422)
		(width 0.254)
		(layer "B.Cu")
		(net "P3V3_DEV_PWRGD")
	)
	(segment
		(start 52.2605 -76.032106)
		(end 51.539394 -75.311)
		(width 0.254)
		(layer "B.Cu")
		(net "P3V3_DEV_PWRGD")
	)
	(segment
		(start 51.539394 -75.311)
		(end 50.066194 -73.8378)
		(width 0.254)
		(layer "B.Cu")
		(net "P3V3_DEV_PWRGD")
	)
	(segment
		(start 50.066194 -73.8378)
		(end 41.811194 -73.8378)
		(width 0.254)
		(layer "B.Cu")
		(net "P3V3_DEV_PWRGD")
	)
	(segment
		(start 51.005994 -78.994)
		(end 51.8795 -78.994)
		(width 0.254)
		(layer "B.Cu")
		(net "P3V3_DEV_PWRGD")
	)
	(segment
		(start 52.2605 -78.613)
		(end 52.2605 -76.032106)
		(width 0.254)
		(layer "B.Cu")
		(net "P3V3_DEV_PWRGD")
	)
	(segment
		(start 51.8795 -78.994)
		(end 52.2605 -78.613)
		(width 0.254)
		(layer "B.Cu")
		(net "P3V3_DEV_PWRGD")
	)
	(segment
		(start 49.645316 -79.899002)
		(end 50.862992 -79.899002)
		(width 0.3048)
		(layer "F.Cu")
		(net "P3V3_DEV_VBST")
	)
	(segment
		(start 50.862992 -79.899002)
		(end 51.005994 -79.756)
		(width 0.3048)
		(layer "F.Cu")
		(net "P3V3_DEV_VBST")
	)
	(via
		(at 51.005994 -79.756)
		(size 0.5588)
		(drill 0.3048)
		(layers "F.Cu" "B.Cu")
		(net "P3V3_DEV_VBST")
	)
	(segment
		(start 52.021994 -79.756)
		(end 51.005994 -79.756)
		(width 0.508)
		(layer "B.Cu")
		(net "P3V3_DEV_VBST")
	)
	(segment
		(start 49.481994 -77.089)
		(end 49.645316 -76.925678)
		(width 0.254)
		(layer "F.Cu")
		(net "P3V3_DEV_VFB")
	)
	(segment
		(start 49.645316 -78.398878)
		(end 49.645316 -77.252322)
		(width 0.254)
		(layer "F.Cu")
		(net "P3V3_DEV_VFB")
	)
	(segment
		(start 50.751994 -76.1365)
		(end 50.688494 -76.073)
		(width 0.254)
		(layer "F.Cu")
		(net "P3V3_DEV_VFB")
	)
	(segment
		(start 49.645316 -77.252322)
		(end 49.481994 -77.089)
		(width 0.254)
		(layer "F.Cu")
		(net "P3V3_DEV_VFB")
	)
	(segment
		(start 52.5526 -76.1365)
		(end 52.6669 -76.2508)
		(width 0.254)
		(layer "F.Cu")
		(net "P3V3_DEV_VFB")
	)
	(segment
		(start 49.645316 -76.100178)
		(end 49.672494 -76.073)
		(width 0.254)
		(layer "F.Cu")
		(net "P3V3_DEV_VFB")
	)
	(segment
		(start 50.688494 -76.073)
		(end 49.672494 -76.073)
		(width 0.254)
		(layer "F.Cu")
		(net "P3V3_DEV_VFB")
	)
	(segment
		(start 50.751994 -76.1365)
		(end 51.7144 -76.1365)
		(width 0.254)
		(layer "F.Cu")
		(net "P3V3_DEV_VFB")
	)
	(segment
		(start 49.645316 -76.925678)
		(end 49.645316 -76.100178)
		(width 0.254)
		(layer "F.Cu")
		(net "P3V3_DEV_VFB")
	)
	(segment
		(start 51.7144 -76.1365)
		(end 52.5526 -76.1365)
		(width 0.254)
		(layer "F.Cu")
		(net "P3V3_DEV_VFB")
	)
	(via
		(at 49.481994 -77.089)
		(size 0.7112)
		(drill 0.3556)
		(layers "F.Cu" "B.Cu")
		(net "P3V3_DEV_VFB")
	)
	(segment
		(start 48.133 -87.3252)
		(end 49.1998 -87.3252)
		(width 0.508)
		(layer "F.Cu")
		(net "P3V3_DEV_SNB")
	)
	(segment
		(start 49.1998 -87.3252)
		(end 49.784 -86.741)
		(width 0.508)
		(layer "F.Cu")
		(net "P3V3_DEV_SNB")
	)
	(segment
		(start 49.645316 -80.398874)
		(end 50.886868 -80.398874)
		(width 0.254)
		(layer "F.Cu")
		(net "P3V3_DEV_ROVP")
	)
	(segment
		(start 50.886868 -80.398874)
		(end 51.005994 -80.518)
		(width 0.254)
		(layer "F.Cu")
		(net "P3V3_DEV_ROVP")
	)
	(via
		(at 51.005994 -80.518)
		(size 0.5588)
		(drill 0.3048)
		(layers "F.Cu" "B.Cu")
		(net "P3V3_DEV_ROVP")
	)
	(segment
		(start 51.005994 -80.518)
		(end 50.053494 -80.518)
		(width 0.254)
		(layer "B.Cu")
		(net "P3V3_DEV_ROVP")
	)
	(segment
		(start 50.751994 -75.2475)
		(end 51.7144 -75.2475)
		(width 0.254)
		(layer "F.Cu")
		(net "P3V3_DEV_VFB_R")
	)
	(segment
		(start 52.832 -74.168)
		(end 52.832 -75.1205)
		(width 0.254)
		(layer "F.Cu")
		(net "P3V3_DEV_VFB_R")
	)
	(segment
		(start 52.832 -75.1205)
		(end 52.705 -75.2475)
		(width 0.254)
		(layer "F.Cu")
		(net "P3V3_DEV_VFB_R")
	)
	(segment
		(start 51.7144 -75.2475)
		(end 52.705 -75.2475)
		(width 0.254)
		(layer "F.Cu")
		(net "P3V3_DEV_VFB_R")
	)
	(via
		(at 52.705 -75.2475)
		(size 0.7112)
		(drill 0.3556)
		(layers "F.Cu" "B.Cu")
		(net "P3V3_DEV_VFB_R")
	)
	(segment
		(start 54.765194 -76.2508)
		(end 54.815994 -76.2)
		(width 0.254)
		(layer "F.Cu")
		(net "P3V3_DEV_LL_R")
	)
	(segment
		(start 53.5559 -76.2508)
		(end 54.765194 -76.2508)
		(width 0.254)
		(layer "F.Cu")
		(net "P3V3_DEV_LL_R")
	)
	(via
		(at 54.815994 -76.2)
		(size 0.5588)
		(drill 0.3048)
		(layers "F.Cu" "B.Cu")
		(net "P3V3_DEV_LL_R")
	)
	(segment
		(start 55.450994 -77.2795)
		(end 56.466994 -77.2795)
		(width 0.254)
		(layer "B.Cu")
		(net "P3V3_DEV_LL_R")
	)
	(segment
		(start 54.815994 -76.2)
		(end 54.815994 -76.6445)
		(width 0.254)
		(layer "B.Cu")
		(net "P3V3_DEV_LL_R")
	)
	(segment
		(start 54.815994 -76.6445)
		(end 55.450994 -77.2795)
		(width 0.254)
		(layer "B.Cu")
		(net "P3V3_DEV_LL_R")
	)
	(segment
		(start 55.196994 -82.296)
		(end 55.450994 -82.55)
		(width 0.254)
		(layer "F.Cu")
		(net "P3V3_DEV_LL")
	)
	(segment
		(start 52.563522 -82.296)
		(end 55.196994 -82.296)
		(width 0.254)
		(layer "F.Cu")
		(net "P3V3_DEV_LL")
	)
	(segment
		(start 49.784 -85.217)
		(end 49.784 -84.201)
		(width 0.508)
		(layer "F.Cu")
		(net "P3V3_DEV_LL")
	)
	(via
		(at 54.626256 -80.2894)
		(size 0.508)
		(drill 0.254)
		(layers "F.Cu" "B.Cu")
		(net "P3V3_DEV_LL")
	)
	(via
		(at 55.450994 -82.55)
		(size 0.5588)
		(drill 0.3048)
		(layers "F.Cu" "B.Cu")
		(net "P3V3_DEV_LL")
	)
	(segment
		(start 55.450994 -82.55)
		(end 55.450994 -78.1685)
		(width 0.254)
		(layer "B.Cu")
		(net "P3V3_DEV_LL")
	)
	(segment
		(start 54.356 -81.28)
		(end 54.356 -80.559656)
		(width 0.508)
		(layer "B.Cu")
		(net "P3V3_DEV_LL")
	)
	(segment
		(start 54.356 -80.559656)
		(end 54.626256 -80.2894)
		(width 0.508)
		(layer "B.Cu")
		(net "P3V3_DEV_LL")
	)
	(segment
		(start 50.33899 -78.899004)
		(end 51.005994 -78.232)
		(width 0.254)
		(layer "F.Cu")
		(net "P3V3_DEV_EN")
	)
	(segment
		(start 49.645316 -78.899004)
		(end 50.33899 -78.899004)
		(width 0.254)
		(layer "F.Cu")
		(net "P3V3_DEV_EN")
	)
	(segment
		(start 51.831494 -77.216)
		(end 51.005994 -78.0415)
		(width 0.254)
		(layer "F.Cu")
		(net "P3V3_DEV_EN")
	)
	(segment
		(start 51.005994 -78.0415)
		(end 51.005994 -78.232)
		(width 0.254)
		(layer "F.Cu")
		(net "P3V3_DEV_EN")
	)
	(via
		(at 49.672494 -77.2795)
		(size 0.7112)
		(drill 0.3556)
		(layers "F.Cu" "B.Cu")
		(net "P3V3_DEV_EN")
	)
	(via
		(at 51.005994 -78.232)
		(size 0.5588)
		(drill 0.3048)
		(layers "F.Cu" "B.Cu")
		(net "P3V3_DEV_EN")
	)
	(segment
		(start 50.751994 -77.2795)
		(end 50.751994 -77.978)
		(width 0.254)
		(layer "B.Cu")
		(net "P3V3_DEV_EN")
	)
	(segment
		(start 49.672494 -77.2795)
		(end 50.751994 -77.2795)
		(width 0.254)
		(layer "B.Cu")
		(net "P3V3_DEV_EN")
	)
	(segment
		(start 50.751994 -77.978)
		(end 51.005994 -78.232)
		(width 0.254)
		(layer "B.Cu")
		(net "P3V3_DEV_EN")
	)
	(segment
		(start 44.746672 -77.597)
		(end 44.746672 -78.398878)
		(width 0.254)
		(layer "F.Cu")
		(net "P3V3_DEV_RF")
	)
	(segment
		(start 44.782994 -76.6445)
		(end 44.782994 -77.560678)
		(width 0.254)
		(layer "F.Cu")
		(net "P3V3_DEV_RF")
	)
	(segment
		(start 44.782994 -77.560678)
		(end 44.746672 -77.597)
		(width 0.254)
		(layer "F.Cu")
		(net "P3V3_DEV_RF")
	)
	(via
		(at 45.163994 -78.613)
		(size 0.7112)
		(drill 0.3556)
		(layers "F.Cu" "B.Cu")
		(net "P3V3_DEV_RF")
	)
	(via
		(at 44.746672 -77.597)
		(size 0.5588)
		(drill 0.3048)
		(layers "F.Cu" "B.Cu")
		(net "P3V3_DEV_RF")
	)
	(segment
		(start 44.746672 -77.597)
		(end 44.746672 -78.195678)
		(width 0.254)
		(layer "B.Cu")
		(net "P3V3_DEV_RF")
	)
	(segment
		(start 44.782994 -77.560678)
		(end 44.746672 -77.597)
		(width 0.254)
		(layer "B.Cu")
		(net "P3V3_DEV_RF")
	)
	(segment
		(start 44.746672 -78.195678)
		(end 45.163994 -78.613)
		(width 0.254)
		(layer "B.Cu")
		(net "P3V3_DEV_RF")
	)
	(segment
		(start 44.782994 -76.6445)
		(end 44.782994 -77.560678)
		(width 0.254)
		(layer "B.Cu")
		(net "P3V3_DEV_RF")
	)
	(segment
		(start 43.933872 -77.763878)
		(end 43.766994 -77.597)
		(width 0.254)
		(layer "F.Cu")
		(net "P3V3_DEV_TRIP")
	)
	(segment
		(start 44.746672 -78.899004)
		(end 44.176188 -78.899004)
		(width 0.254)
		(layer "F.Cu")
		(net "P3V3_DEV_TRIP")
	)
	(segment
		(start 44.176188 -78.899004)
		(end 43.933872 -78.656688)
		(width 0.254)
		(layer "F.Cu")
		(net "P3V3_DEV_TRIP")
	)
	(segment
		(start 43.933872 -78.656688)
		(end 43.933872 -77.763878)
		(width 0.254)
		(layer "F.Cu")
		(net "P3V3_DEV_TRIP")
	)
	(via
		(at 44.147994 -80.01)
		(size 0.7112)
		(drill 0.3556)
		(layers "F.Cu" "B.Cu")
		(net "P3V3_DEV_TRIP")
	)
	(via
		(at 43.766994 -77.597)
		(size 0.5588)
		(drill 0.3048)
		(layers "F.Cu" "B.Cu")
		(net "P3V3_DEV_TRIP")
	)
	(segment
		(start 43.766994 -76.6445)
		(end 43.766994 -77.597)
		(width 0.254)
		(layer "B.Cu")
		(net "P3V3_DEV_TRIP")
	)
	(segment
		(start 43.893994 -79.756)
		(end 44.147994 -80.01)
		(width 0.254)
		(layer "B.Cu")
		(net "P3V3_DEV_TRIP")
	)
	(segment
		(start 43.893994 -77.724)
		(end 43.893994 -79.756)
		(width 0.254)
		(layer "B.Cu")
		(net "P3V3_DEV_TRIP")
	)
	(segment
		(start 43.766994 -77.597)
		(end 43.893994 -77.724)
		(width 0.254)
		(layer "B.Cu")
		(net "P3V3_DEV_TRIP")
	)
	(segment
		(start 44.746672 -79.398876)
		(end 43.91787 -79.398876)
		(width 0.254)
		(layer "F.Cu")
		(net "P3V3_DEV_MODE")
	)
	(segment
		(start 42.750994 -78.232)
		(end 43.131994 -78.613)
		(width 0.254)
		(layer "F.Cu")
		(net "P3V3_DEV_MODE")
	)
	(segment
		(start 43.91787 -79.398876)
		(end 43.131994 -78.613)
		(width 0.254)
		(layer "F.Cu")
		(net "P3V3_DEV_MODE")
	)
	(segment
		(start 42.750994 -76.6445)
		(end 42.750994 -78.232)
		(width 0.254)
		(layer "F.Cu")
		(net "P3V3_DEV_MODE")
	)
	(via
		(at 42.115994 -78.232)
		(size 0.7112)
		(drill 0.3556)
		(layers "F.Cu" "B.Cu")
		(net "P3V3_DEV_MODE")
	)
	(via
		(at 43.131994 -78.613)
		(size 0.5588)
		(drill 0.3048)
		(layers "F.Cu" "B.Cu")
		(net "P3V3_DEV_MODE")
	)
	(segment
		(start 42.496994 -78.613)
		(end 42.115994 -78.232)
		(width 0.254)
		(layer "B.Cu")
		(net "P3V3_DEV_MODE")
	)
	(segment
		(start 43.131994 -78.613)
		(end 42.496994 -78.613)
		(width 0.254)
		(layer "B.Cu")
		(net "P3V3_DEV_MODE")
	)
	(segment
		(start 42.750994 -76.6445)
		(end 42.750994 -77.597)
		(width 0.254)
		(layer "B.Cu")
		(net "P3V3_DEV_MODE")
	)
	(segment
		(start 42.750994 -77.597)
		(end 42.115994 -78.232)
		(width 0.254)
		(layer "B.Cu")
		(net "P3V3_DEV_MODE")
	)
	(segment
		(start 48.783494 -75.8825)
		(end 48.783494 -76.073)
		(width 0.508)
		(layer "F.Cu")
		(net "AGND_P3V3_DEV")
	)
	(segment
		(start 49.481994 -75.184)
		(end 48.783494 -75.8825)
		(width 0.508)
		(layer "F.Cu")
		(net "AGND_P3V3_DEV")
	)
	(segment
		(start 46.078394 -75.5396)
		(end 45.989494 -75.6285)
		(width 0.508)
		(layer "F.Cu")
		(net "AGND_P3V3_DEV")
	)
	(segment
		(start 49.735994 -75.184)
		(end 49.481994 -75.184)
		(width 0.508)
		(layer "F.Cu")
		(net "AGND_P3V3_DEV")
	)
	(segment
		(start 48.250094 -75.5396)
		(end 47.195994 -75.5396)
		(width 0.508)
		(layer "F.Cu")
		(net "AGND_P3V3_DEV")
	)
	(segment
		(start 47.195994 -75.5396)
		(end 46.078394 -75.5396)
		(width 0.508)
		(layer "F.Cu")
		(net "AGND_P3V3_DEV")
	)
	(segment
		(start 48.783494 -76.073)
		(end 48.250094 -75.5396)
		(width 0.508)
		(layer "F.Cu")
		(net "AGND_P3V3_DEV")
	)
	(via
		(at 49.735994 -75.184)
		(size 0.5588)
		(drill 0.3048)
		(layers "F.Cu" "B.Cu")
		(net "AGND_P3V3_DEV")
	)
	(via
		(at 45.989494 -75.6285)
		(size 0.5588)
		(drill 0.3048)
		(layers "F.Cu" "B.Cu")
		(net "AGND_P3V3_DEV")
	)
	(via
		(at 45.989494 -76.708)
		(size 0.7112)
		(drill 0.3556)
		(layers "F.Cu" "B.Cu")
		(net "AGND_P3V3_DEV")
	)
	(segment
		(start 45.989494 -76.708)
		(end 45.989494 -75.6285)
		(width 0.508)
		(layer "B.Cu")
		(net "AGND_P3V3_DEV")
	)
	(segment
		(start 49.164494 -78.74)
		(end 48.529494 -78.105)
		(width 0.508)
		(layer "B.Cu")
		(net "AGND_P3V3_DEV")
	)
	(segment
		(start 45.989494 -77.030326)
		(end 45.989494 -76.708)
		(width 0.508)
		(layer "B.Cu")
		(net "AGND_P3V3_DEV")
	)
	(segment
		(start 49.164494 -80.518)
		(end 49.164494 -78.74)
		(width 0.508)
		(layer "B.Cu")
		(net "AGND_P3V3_DEV")
	)
	(segment
		(start 45.862494 -75.7555)
		(end 44.782994 -75.7555)
		(width 0.508)
		(layer "B.Cu")
		(net "AGND_P3V3_DEV")
	)
	(segment
		(start 47.064168 -78.105)
		(end 45.989494 -77.030326)
		(width 0.508)
		(layer "B.Cu")
		(net "AGND_P3V3_DEV")
	)
	(segment
		(start 42.750994 -75.7555)
		(end 43.766994 -75.7555)
		(width 0.508)
		(layer "B.Cu")
		(net "AGND_P3V3_DEV")
	)
	(segment
		(start 45.989494 -75.6285)
		(end 45.862494 -75.7555)
		(width 0.508)
		(layer "B.Cu")
		(net "AGND_P3V3_DEV")
	)
	(segment
		(start 43.766994 -75.7555)
		(end 44.782994 -75.7555)
		(width 0.508)
		(layer "B.Cu")
		(net "AGND_P3V3_DEV")
	)
	(segment
		(start 48.529494 -78.105)
		(end 47.064168 -78.105)
		(width 0.508)
		(layer "B.Cu")
		(net "AGND_P3V3_DEV")
	)
	(segment
		(start 50.751994 -76.3905)
		(end 49.735994 -75.3745)
		(width 0.508)
		(layer "B.Cu")
		(net "AGND_P3V3_DEV")
	)
	(segment
		(start 49.735994 -75.3745)
		(end 49.735994 -75.184)
		(width 0.508)
		(layer "B.Cu")
		(net "AGND_P3V3_DEV")
	)
	(segment
		(start 41.91 -79.502)
		(end 41.91 -79.1845)
		(width 0.3048)
		(layer "F.Cu")
		(net "P3V3_DEV_VREG")
	)
	(segment
		(start 44.782994 -75.7555)
		(end 44.782994 -74.676)
		(width 0.508)
		(layer "F.Cu")
		(net "P3V3_DEV_VREG")
	)
	(segment
		(start 44.746672 -80.398874)
		(end 42.806874 -80.398874)
		(width 0.3048)
		(layer "F.Cu")
		(net "P3V3_DEV_VREG")
	)
	(segment
		(start 41.290494 -79.1845)
		(end 40.845994 -78.74)
		(width 0.508)
		(layer "F.Cu")
		(net "P3V3_DEV_VREG")
	)
	(segment
		(start 41.91 -79.1845)
		(end 41.290494 -79.1845)
		(width 0.508)
		(layer "F.Cu")
		(net "P3V3_DEV_VREG")
	)
	(segment
		(start 42.806874 -80.398874)
		(end 41.91 -79.502)
		(width 0.3048)
		(layer "F.Cu")
		(net "P3V3_DEV_VREG")
	)
	(via
		(at 44.782994 -74.676)
		(size 0.5588)
		(drill 0.3048)
		(layers "F.Cu" "B.Cu")
		(net "P3V3_DEV_VREG")
	)
	(via
		(at 40.845994 -78.74)
		(size 0.5588)
		(drill 0.3048)
		(layers "F.Cu" "B.Cu")
		(net "P3V3_DEV_VREG")
	)
	(via
		(at 40.972994 -76.708)
		(size 0.7112)
		(drill 0.3556)
		(layers "F.Cu" "B.Cu")
		(net "P3V3_DEV_VREG")
	)
	(segment
		(start 50.521362 -72.9996)
		(end 41.463976 -72.9996)
		(width 0.508)
		(layer "B.Cu")
		(net "P3V3_DEV_VREG")
	)
	(segment
		(start 53.1495 -78.613)
		(end 53.1495 -75.627738)
		(width 0.508)
		(layer "B.Cu")
		(net "P3V3_DEV_VREG")
	)
	(segment
		(start 40.972994 -78.613)
		(end 40.972994 -76.708)
		(width 0.508)
		(layer "B.Cu")
		(net "P3V3_DEV_VREG")
	)
	(segment
		(start 41.463976 -72.9996)
		(end 40.388794 -74.074782)
		(width 0.508)
		(layer "B.Cu")
		(net "P3V3_DEV_VREG")
	)
	(segment
		(start 53.1495 -75.627738)
		(end 50.521362 -72.9996)
		(width 0.508)
		(layer "B.Cu")
		(net "P3V3_DEV_VREG")
	)
	(segment
		(start 42.369994 -74.676)
		(end 44.782994 -74.676)
		(width 0.508)
		(layer "B.Cu")
		(net "P3V3_DEV_VREG")
	)
	(segment
		(start 41.861994 -75.819)
		(end 41.861994 -75.184)
		(width 0.508)
		(layer "B.Cu")
		(net "P3V3_DEV_VREG")
	)
	(segment
		(start 40.972994 -76.708)
		(end 41.861994 -75.819)
		(width 0.508)
		(layer "B.Cu")
		(net "P3V3_DEV_VREG")
	)
	(segment
		(start 40.388794 -74.074782)
		(end 40.388794 -76.1238)
		(width 0.508)
		(layer "B.Cu")
		(net "P3V3_DEV_VREG")
	)
	(segment
		(start 40.845994 -78.74)
		(end 40.972994 -78.613)
		(width 0.508)
		(layer "B.Cu")
		(net "P3V3_DEV_VREG")
	)
	(segment
		(start 40.388794 -76.1238)
		(end 40.972994 -76.708)
		(width 0.508)
		(layer "B.Cu")
		(net "P3V3_DEV_VREG")
	)
	(segment
		(start 41.861994 -75.184)
		(end 42.369994 -74.676)
		(width 0.508)
		(layer "B.Cu")
		(net "P3V3_DEV_VREG")
	)
	(segment
		(start 43.401996 -79.899002)
		(end 43.131994 -79.629)
		(width 0.3048)
		(layer "F.Cu")
		(net "P3V3_DEV_VDD")
	)
	(segment
		(start 44.746672 -79.899002)
		(end 43.401996 -79.899002)
		(width 0.3048)
		(layer "F.Cu")
		(net "P3V3_DEV_VDD")
	)
	(via
		(at 41.529 -79.5782)
		(size 0.7112)
		(drill 0.3556)
		(layers "F.Cu" "B.Cu")
		(net "P3V3_DEV_VDD")
	)
	(via
		(at 43.131994 -79.629)
		(size 0.5588)
		(drill 0.3048)
		(layers "F.Cu" "B.Cu")
		(net "P3V3_DEV_VDD")
	)
	(segment
		(start 41.529 -79.5782)
		(end 39.575994 -79.5782)
		(width 0.508)
		(layer "B.Cu")
		(net "P3V3_DEV_VDD")
	)
	(segment
		(start 37.975794 -79.5782)
		(end 37.924994 -79.629)
		(width 0.508)
		(layer "B.Cu")
		(net "P3V3_DEV_VDD")
	)
	(segment
		(start 39.575994 -79.5782)
		(end 37.975794 -79.5782)
		(width 0.508)
		(layer "B.Cu")
		(net "P3V3_DEV_VDD")
	)
	(segment
		(start 43.081194 -79.5782)
		(end 43.131994 -79.629)
		(width 0.508)
		(layer "B.Cu")
		(net "P3V3_DEV_VDD")
	)
	(segment
		(start 41.529 -79.5782)
		(end 43.081194 -79.5782)
		(width 0.508)
		(layer "B.Cu")
		(net "P3V3_DEV_VDD")
	)
	(via
		(at 43.131994 -82.423)
		(size 0.5588)
		(drill 0.3048)
		(layers "F.Cu" "B.Cu")
		(net "P3V3_DEV_VIN")
	)
	(via
		(at 42.115994 -82.423)
		(size 0.5588)
		(drill 0.3048)
		(layers "F.Cu" "B.Cu")
		(net "P3V3_DEV_VIN")
	)
	(via
		(at 35.433 -81.534)
		(size 0.7112)
		(drill 0.3556)
		(layers "F.Cu" "B.Cu")
		(net "P3V3_DEV_VIN")
	)
	(via
		(at 41.099994 -82.423)
		(size 0.5588)
		(drill 0.3048)
		(layers "F.Cu" "B.Cu")
		(net "P3V3_DEV_VIN")
	)
	(via
		(at 39.067994 -82.423)
		(size 0.5588)
		(drill 0.3048)
		(layers "F.Cu" "B.Cu")
		(net "P3V3_DEV_VIN")
	)
	(via
		(at 36.019994 -82.423)
		(size 0.5588)
		(drill 0.3048)
		(layers "F.Cu" "B.Cu")
		(net "P3V3_DEV_VIN")
	)
	(via
		(at 37.035994 -82.423)
		(size 0.5588)
		(drill 0.3048)
		(layers "F.Cu" "B.Cu")
		(net "P3V3_DEV_VIN")
	)
	(via
		(at 44.147994 -82.423)
		(size 0.7112)
		(drill 0.3556)
		(layers "F.Cu" "B.Cu")
		(net "P3V3_DEV_VIN")
	)
	(via
		(at 34.925 -82.423)
		(size 0.5588)
		(drill 0.3048)
		(layers "F.Cu" "B.Cu")
		(net "P3V3_DEV_VIN")
	)
	(via
		(at 38.051994 -82.423)
		(size 0.5588)
		(drill 0.3048)
		(layers "F.Cu" "B.Cu")
		(net "P3V3_DEV_VIN")
	)
	(via
		(at 40.083994 -82.423)
		(size 0.5588)
		(drill 0.3048)
		(layers "F.Cu" "B.Cu")
		(net "P3V3_DEV_VIN")
	)
	(segment
		(start 52.832 -80.469994)
		(end 52.832 -81.28)
		(width 0.508)
		(layer "B.Cu")
		(net "P3V3_DEV_VBST_RC")
	)
	(segment
		(start 53.545994 -79.756)
		(end 52.832 -80.469994)
		(width 0.508)
		(layer "B.Cu")
		(net "P3V3_DEV_VBST_RC")
	)
	(segment
		(start 72.725026 -25.189942)
		(end 71.737982 -25.189942)
		(width 0.136652)
		(layer "F.Cu")
		(net "D85_PCIE_B_RX1_P")
	)
	(segment
		(start 69.664326 -25.163272)
		(end 69.3674 -24.866346)
		(width 0.136652)
		(layer "F.Cu")
		(net "D85_PCIE_B_RX1_P")
	)
	(segment
		(start 71.529956 -25.292812)
		(end 69.977 -25.292812)
		(width 0.136652)
		(layer "F.Cu")
		(net "D85_PCIE_B_RX1_P")
	)
	(segment
		(start 71.64832 -25.227026)
		(end 71.619618 -25.255728)
		(width 0.136652)
		(layer "F.Cu")
		(net "D85_PCIE_B_RX1_P")
	)
	(via
		(at 82.611976 -15.075154)
		(size 0.508)
		(drill 0.254)
		(layers "F.Cu" "B.Cu")
		(net "D85_PCIE_B_RX1_P")
	)
	(via
		(at 69.3674 -24.866346)
		(size 0.508)
		(drill 0.254)
		(layers "F.Cu" "B.Cu")
		(net "D85_PCIE_B_RX1_P")
	)
	(arc
		(start 69.977 -25.292812)
		(mid 69.807772 -25.25915)
		(end 69.664326 -25.163272)
		(width 0.136652)
		(layer "F.Cu")
		(net "D85_PCIE_B_RX1_P")
	)
	(arc
		(start 71.737982 -25.189942)
		(mid 71.689464 -25.199575)
		(end 71.64832 -25.227026)
		(width 0.136652)
		(layer "F.Cu")
		(net "D85_PCIE_B_RX1_P")
	)
	(arc
		(start 71.619618 -25.255728)
		(mid 71.578467 -25.283161)
		(end 71.529956 -25.292812)
		(width 0.136652)
		(layer "F.Cu")
		(net "D85_PCIE_B_RX1_P")
	)
	(segment
		(start 81.380076 -15.075154)
		(end 82.611976 -15.075154)
		(width 0.136652)
		(layer "B.Cu")
		(net "D85_PCIE_B_RX1_P")
	)
	(segment
		(start 69.614034 -25.11298)
		(end 69.3674 -24.866346)
		(width 0.13335)
		(layer "In2.Cu")
		(net "D85_PCIE_B_RX1_P")
	)
	(segment
		(start 82.611976 -15.075154)
		(end 82.518758 -15.168118)
		(width 0.13335)
		(layer "In2.Cu")
		(net "D85_PCIE_B_RX1_P")
	)
	(segment
		(start 71.88581 -19.80819)
		(end 71.208646 -20.485608)
		(width 0.13335)
		(layer "In2.Cu")
		(net "D85_PCIE_B_RX1_P")
	)
	(segment
		(start 70.588124 -21.414486)
		(end 70.463918 -21.714206)
		(width 0.13335)
		(layer "In2.Cu")
		(net "D85_PCIE_B_RX1_P")
	)
	(segment
		(start 79.959962 -15.593822)
		(end 76.53782 -19.015964)
		(width 0.13335)
		(layer "In2.Cu")
		(net "D85_PCIE_B_RX1_P")
	)
	(segment
		(start 79.959962 -15.593568)
		(end 79.959962 -15.593822)
		(width 0.13335)
		(layer "In2.Cu")
		(net "D85_PCIE_B_RX1_P")
	)
	(segment
		(start 76.317856 -19.10715)
		(end 73.235566 -19.10715)
		(width 0.13335)
		(layer "In2.Cu")
		(net "D85_PCIE_B_RX1_P")
	)
	(segment
		(start 70.33895 -22.342602)
		(end 70.33895 -25.009348)
		(width 0.13335)
		(layer "In2.Cu")
		(net "D85_PCIE_B_RX1_P")
	)
	(segment
		(start 70.08495 -25.263348)
		(end 69.977 -25.263348)
		(width 0.13335)
		(layer "In2.Cu")
		(net "D85_PCIE_B_RX1_P")
	)
	(segment
		(start 82.169254 -15.313152)
		(end 80.638142 -15.313152)
		(width 0.13335)
		(layer "In2.Cu")
		(net "D85_PCIE_B_RX1_P")
	)
	(arc
		(start 70.463918 -21.714206)
		(mid 70.370497 -22.02225)
		(end 70.33895 -22.342602)
		(width 0.13335)
		(layer "In2.Cu")
		(net "D85_PCIE_B_RX1_P")
	)
	(arc
		(start 80.638142 -15.313152)
		(mid 80.271153 -15.38591)
		(end 79.959962 -15.593568)
		(width 0.13335)
		(layer "In2.Cu")
		(net "D85_PCIE_B_RX1_P")
	)
	(arc
		(start 82.518758 -15.168118)
		(mid 82.35842 -15.275375)
		(end 82.169254 -15.313152)
		(width 0.13335)
		(layer "In2.Cu")
		(net "D85_PCIE_B_RX1_P")
	)
	(arc
		(start 76.53782 -19.015964)
		(mid 76.4369 -19.083426)
		(end 76.317856 -19.10715)
		(width 0.13335)
		(layer "In2.Cu")
		(net "D85_PCIE_B_RX1_P")
	)
	(arc
		(start 73.235566 -19.10715)
		(mid 73.017511 -19.128649)
		(end 72.80783 -19.19224)
		(width 0.13335)
		(layer "In2.Cu")
		(net "D85_PCIE_B_RX1_P")
	)
	(arc
		(start 70.33895 -25.009348)
		(mid 70.264555 -25.188953)
		(end 70.08495 -25.263348)
		(width 0.13335)
		(layer "In2.Cu")
		(net "D85_PCIE_B_RX1_P")
	)
	(arc
		(start 69.977 -25.263348)
		(mid 69.780556 -25.224273)
		(end 69.614034 -25.11298)
		(width 0.13335)
		(layer "In2.Cu")
		(net "D85_PCIE_B_RX1_P")
	)
	(arc
		(start 72.80783 -19.19224)
		(mid 72.316457 -19.454764)
		(end 71.88581 -19.80819)
		(width 0.13335)
		(layer "In2.Cu")
		(net "D85_PCIE_B_RX1_P")
	)
	(arc
		(start 71.208646 -20.485608)
		(mid 70.85267 -20.919506)
		(end 70.588124 -21.414486)
		(width 0.13335)
		(layer "In2.Cu")
		(net "D85_PCIE_B_RX1_P")
	)
	(segment
		(start 71.626984 -25.65273)
		(end 71.598282 -25.624028)
		(width 0.136652)
		(layer "F.Cu")
		(net "D85_PCIE_B_RX1_N")
	)
	(segment
		(start 69.614034 -25.737312)
		(end 69.3674 -25.983946)
		(width 0.136652)
		(layer "F.Cu")
		(net "D85_PCIE_B_RX1_N")
	)
	(segment
		(start 71.50862 -25.586944)
		(end 69.977 -25.586944)
		(width 0.136652)
		(layer "F.Cu")
		(net "D85_PCIE_B_RX1_N")
	)
	(segment
		(start 72.725026 -25.689814)
		(end 71.716646 -25.689814)
		(width 0.136652)
		(layer "F.Cu")
		(net "D85_PCIE_B_RX1_N")
	)
	(via
		(at 82.611976 -15.875)
		(size 0.508)
		(drill 0.254)
		(layers "F.Cu" "B.Cu")
		(net "D85_PCIE_B_RX1_N")
	)
	(via
		(at 69.3674 -25.983946)
		(size 0.508)
		(drill 0.254)
		(layers "F.Cu" "B.Cu")
		(net "D85_PCIE_B_RX1_N")
	)
	(arc
		(start 71.598282 -25.624028)
		(mid 71.557131 -25.596595)
		(end 71.50862 -25.586944)
		(width 0.136652)
		(layer "F.Cu")
		(net "D85_PCIE_B_RX1_N")
	)
	(arc
		(start 69.977 -25.586944)
		(mid 69.780556 -25.626019)
		(end 69.614034 -25.737312)
		(width 0.136652)
		(layer "F.Cu")
		(net "D85_PCIE_B_RX1_N")
	)
	(arc
		(start 71.716646 -25.689814)
		(mid 71.668128 -25.680181)
		(end 71.626984 -25.65273)
		(width 0.136652)
		(layer "F.Cu")
		(net "D85_PCIE_B_RX1_N")
	)
	(segment
		(start 81.380076 -15.875)
		(end 82.611976 -15.875)
		(width 0.136652)
		(layer "B.Cu")
		(net "D85_PCIE_B_RX1_N")
	)
	(segment
		(start 69.61378 -25.73782)
		(end 69.3674 -25.983946)
		(width 0.13335)
		(layer "In2.Cu")
		(net "D85_PCIE_B_RX1_N")
	)
	(segment
		(start 82.169 -15.637002)
		(end 80.638142 -15.637002)
		(width 0.13335)
		(layer "In2.Cu")
		(net "D85_PCIE_B_RX1_N")
	)
	(segment
		(start 76.317856 -19.431)
		(end 73.23582 -19.431)
		(width 0.13335)
		(layer "In2.Cu")
		(net "D85_PCIE_B_RX1_N")
	)
	(segment
		(start 72.114918 -20.037298)
		(end 71.437754 -20.714716)
		(width 0.13335)
		(layer "In2.Cu")
		(net "D85_PCIE_B_RX1_N")
	)
	(segment
		(start 80.18907 -15.82293)
		(end 76.766928 -19.245072)
		(width 0.13335)
		(layer "In2.Cu")
		(net "D85_PCIE_B_RX1_N")
	)
	(segment
		(start 70.6628 -22.342602)
		(end 70.6628 -25.009348)
		(width 0.13335)
		(layer "In2.Cu")
		(net "D85_PCIE_B_RX1_N")
	)
	(segment
		(start 70.887336 -21.538438)
		(end 70.76313 -21.838158)
		(width 0.13335)
		(layer "In2.Cu")
		(net "D85_PCIE_B_RX1_N")
	)
	(segment
		(start 70.08495 -25.587198)
		(end 69.977 -25.587198)
		(width 0.13335)
		(layer "In2.Cu")
		(net "D85_PCIE_B_RX1_N")
	)
	(segment
		(start 82.611976 -15.875)
		(end 82.518758 -15.782036)
		(width 0.13335)
		(layer "In2.Cu")
		(net "D85_PCIE_B_RX1_N")
	)
	(arc
		(start 71.437754 -20.714716)
		(mid 71.121973 -21.099469)
		(end 70.887336 -21.538438)
		(width 0.13335)
		(layer "In2.Cu")
		(net "D85_PCIE_B_RX1_N")
	)
	(arc
		(start 70.6628 -25.009348)
		(mid 70.493552 -25.41795)
		(end 70.08495 -25.587198)
		(width 0.13335)
		(layer "In2.Cu")
		(net "D85_PCIE_B_RX1_N")
	)
	(arc
		(start 69.977 -25.587198)
		(mid 69.780415 -25.626395)
		(end 69.61378 -25.73782)
		(width 0.13335)
		(layer "In2.Cu")
		(net "D85_PCIE_B_RX1_N")
	)
	(arc
		(start 80.638142 -15.637002)
		(mid 80.395124 -15.685323)
		(end 80.18907 -15.82293)
		(width 0.13335)
		(layer "In2.Cu")
		(net "D85_PCIE_B_RX1_N")
	)
	(arc
		(start 82.518758 -15.782036)
		(mid 82.358303 -15.67473)
		(end 82.169 -15.637002)
		(width 0.13335)
		(layer "In2.Cu")
		(net "D85_PCIE_B_RX1_N")
	)
	(arc
		(start 70.76313 -21.838158)
		(mid 70.688095 -22.085436)
		(end 70.6628 -22.342602)
		(width 0.13335)
		(layer "In2.Cu")
		(net "D85_PCIE_B_RX1_N")
	)
	(arc
		(start 76.766928 -19.245072)
		(mid 76.560878 -19.382687)
		(end 76.317856 -19.431)
		(width 0.13335)
		(layer "In2.Cu")
		(net "D85_PCIE_B_RX1_N")
	)
	(arc
		(start 73.23582 -19.431)
		(mid 73.080822 -19.446251)
		(end 72.931782 -19.491452)
		(width 0.13335)
		(layer "In2.Cu")
		(net "D85_PCIE_B_RX1_N")
	)
	(arc
		(start 72.931782 -19.491452)
		(mid 72.496438 -19.724101)
		(end 72.114918 -20.037298)
		(width 0.13335)
		(layer "In2.Cu")
		(net "D85_PCIE_B_RX1_N")
	)
	(segment
		(start 73.641204 -24.138382)
		(end 73.630028 -24.149558)
		(width 0.136652)
		(layer "F.Cu")
		(net "D85_PCIE_B_TX1_P")
	)
	(segment
		(start 79.1083 -20.1803)
		(end 75.645772 -23.643082)
		(width 0.136652)
		(layer "F.Cu")
		(net "D85_PCIE_B_TX1_P")
	)
	(segment
		(start 82.0166 -18.022062)
		(end 81.529682 -18.022062)
		(width 0.136652)
		(layer "F.Cu")
		(net "D85_PCIE_B_TX1_P")
	)
	(segment
		(start 74.573384 -24.087074)
		(end 73.76541 -24.087074)
		(width 0.136652)
		(layer "F.Cu")
		(net "D85_PCIE_B_TX1_P")
	)
	(segment
		(start 73.533 -24.189944)
		(end 72.725026 -24.189944)
		(width 0.136652)
		(layer "F.Cu")
		(net "D85_PCIE_B_TX1_P")
	)
	(segment
		(start 82.611976 -18.275046)
		(end 82.601054 -18.264124)
		(width 0.136652)
		(layer "F.Cu")
		(net "D85_PCIE_B_TX1_P")
	)
	(segment
		(start 81.08061 -18.20799)
		(end 79.1083 -20.1803)
		(width 0.136652)
		(layer "F.Cu")
		(net "D85_PCIE_B_TX1_P")
	)
	(segment
		(start 75.645772 -23.643082)
		(end 75.645518 -23.643082)
		(width 0.136652)
		(layer "F.Cu")
		(net "D85_PCIE_B_TX1_P")
	)
	(via
		(at 82.611976 -18.275046)
		(size 0.508)
		(drill 0.254)
		(layers "F.Cu" "B.Cu")
		(net "D85_PCIE_B_TX1_P")
	)
	(arc
		(start 81.529682 -18.022062)
		(mid 81.286664 -18.070383)
		(end 81.08061 -18.20799)
		(width 0.136652)
		(layer "F.Cu")
		(net "D85_PCIE_B_TX1_P")
	)
	(arc
		(start 73.76541 -24.087074)
		(mid 73.698229 -24.100419)
		(end 73.641204 -24.138382)
		(width 0.136652)
		(layer "F.Cu")
		(net "D85_PCIE_B_TX1_P")
	)
	(arc
		(start 73.630028 -24.149558)
		(mid 73.585554 -24.179465)
		(end 73.533 -24.189944)
		(width 0.136652)
		(layer "F.Cu")
		(net "D85_PCIE_B_TX1_P")
	)
	(arc
		(start 82.601054 -18.264124)
		(mid 82.332904 -18.084952)
		(end 82.0166 -18.022062)
		(width 0.136652)
		(layer "F.Cu")
		(net "D85_PCIE_B_TX1_P")
	)
	(arc
		(start 75.645518 -23.643082)
		(mid 75.153604 -23.971676)
		(end 74.573384 -24.087074)
		(width 0.136652)
		(layer "F.Cu")
		(net "D85_PCIE_B_TX1_P")
	)
	(segment
		(start 81.380076 -18.275046)
		(end 82.611976 -18.275046)
		(width 0.136652)
		(layer "B.Cu")
		(net "D85_PCIE_B_TX1_P")
	)
	(segment
		(start 80.872584 -17.999964)
		(end 75.437492 -23.435056)
		(width 0.136652)
		(layer "F.Cu")
		(net "D85_PCIE_B_TX1_N")
	)
	(segment
		(start 82.0166 -17.72793)
		(end 81.529682 -17.72793)
		(width 0.136652)
		(layer "F.Cu")
		(net "D85_PCIE_B_TX1_N")
	)
	(segment
		(start 73.509378 -23.689818)
		(end 72.725026 -23.689818)
		(width 0.136652)
		(layer "F.Cu")
		(net "D85_PCIE_B_TX1_N")
	)
	(segment
		(start 82.611976 -17.474946)
		(end 82.601054 -17.485868)
		(width 0.136652)
		(layer "F.Cu")
		(net "D85_PCIE_B_TX1_N")
	)
	(segment
		(start 74.573384 -23.792942)
		(end 73.758298 -23.792942)
		(width 0.136652)
		(layer "F.Cu")
		(net "D85_PCIE_B_TX1_N")
	)
	(via
		(at 82.611976 -17.474946)
		(size 0.508)
		(drill 0.254)
		(layers "F.Cu" "B.Cu")
		(net "D85_PCIE_B_TX1_N")
	)
	(arc
		(start 82.601054 -17.485868)
		(mid 82.332904 -17.66504)
		(end 82.0166 -17.72793)
		(width 0.136652)
		(layer "F.Cu")
		(net "D85_PCIE_B_TX1_N")
	)
	(arc
		(start 75.437492 -23.435056)
		(mid 75.041036 -23.69996)
		(end 74.573384 -23.792942)
		(width 0.136652)
		(layer "F.Cu")
		(net "D85_PCIE_B_TX1_N")
	)
	(arc
		(start 73.758298 -23.792942)
		(mid 73.690937 -23.779543)
		(end 73.633838 -23.74138)
		(width 0.136652)
		(layer "F.Cu")
		(net "D85_PCIE_B_TX1_N")
	)
	(arc
		(start 81.529682 -17.72793)
		(mid 81.17409 -17.798626)
		(end 80.872584 -17.999964)
		(width 0.136652)
		(layer "F.Cu")
		(net "D85_PCIE_B_TX1_N")
	)
	(arc
		(start 73.633838 -23.74138)
		(mid 73.576735 -23.703225)
		(end 73.509378 -23.689818)
		(width 0.136652)
		(layer "F.Cu")
		(net "D85_PCIE_B_TX1_N")
	)
	(segment
		(start 81.380076 -17.474946)
		(end 82.611976 -17.474946)
		(width 0.136652)
		(layer "B.Cu")
		(net "D85_PCIE_B_TX1_N")
	)
	(segment
		(start 71.497952 -28.292806)
		(end 70.485 -28.292806)
		(width 0.136652)
		(layer "F.Cu")
		(net "D85_PCIE_B_RX0_P")
	)
	(segment
		(start 72.725026 -28.189936)
		(end 71.705978 -28.189936)
		(width 0.136652)
		(layer "F.Cu")
		(net "D85_PCIE_B_RX0_P")
	)
	(segment
		(start 70.172326 -28.163266)
		(end 69.8754 -27.86634)
		(width 0.136652)
		(layer "F.Cu")
		(net "D85_PCIE_B_RX0_P")
	)
	(segment
		(start 71.616316 -28.22702)
		(end 71.587614 -28.255722)
		(width 0.136652)
		(layer "F.Cu")
		(net "D85_PCIE_B_RX0_P")
	)
	(via
		(at 82.611976 -19.874992)
		(size 0.508)
		(drill 0.254)
		(layers "F.Cu" "B.Cu")
		(net "D85_PCIE_B_RX0_P")
	)
	(via
		(at 69.8754 -27.86634)
		(size 0.508)
		(drill 0.254)
		(layers "F.Cu" "B.Cu")
		(net "D85_PCIE_B_RX0_P")
	)
	(arc
		(start 71.587614 -28.255722)
		(mid 71.546463 -28.283155)
		(end 71.497952 -28.292806)
		(width 0.136652)
		(layer "F.Cu")
		(net "D85_PCIE_B_RX0_P")
	)
	(arc
		(start 70.485 -28.292806)
		(mid 70.315772 -28.259144)
		(end 70.172326 -28.163266)
		(width 0.136652)
		(layer "F.Cu")
		(net "D85_PCIE_B_RX0_P")
	)
	(arc
		(start 71.705978 -28.189936)
		(mid 71.65746 -28.199569)
		(end 71.616316 -28.22702)
		(width 0.136652)
		(layer "F.Cu")
		(net "D85_PCIE_B_RX0_P")
	)
	(segment
		(start 81.380076 -19.874992)
		(end 82.611976 -19.874992)
		(width 0.136652)
		(layer "B.Cu")
		(net "D85_PCIE_B_RX0_P")
	)
	(segment
		(start 82.611976 -19.874992)
		(end 82.60842 -19.878802)
		(width 0.13335)
		(layer "In2.Cu")
		(net "D85_PCIE_B_RX0_P")
	)
	(segment
		(start 70.122034 -28.112974)
		(end 69.8754 -27.86634)
		(width 0.13335)
		(layer "In2.Cu")
		(net "D85_PCIE_B_RX0_P")
	)
	(segment
		(start 70.869556 -28.263342)
		(end 70.485 -28.263342)
		(width 0.13335)
		(layer "In2.Cu")
		(net "D85_PCIE_B_RX0_P")
	)
	(segment
		(start 82.042 -20.113244)
		(end 73.477374 -20.113244)
		(width 0.13335)
		(layer "In2.Cu")
		(net "D85_PCIE_B_RX0_P")
	)
	(segment
		(start 71.465948 -21.82241)
		(end 71.394574 -21.994622)
		(width 0.13335)
		(layer "In2.Cu")
		(net "D85_PCIE_B_RX0_P")
	)
	(segment
		(start 72.384158 -20.675346)
		(end 71.926704 -21.1328)
		(width 0.13335)
		(layer "In2.Cu")
		(net "D85_PCIE_B_RX0_P")
	)
	(segment
		(start 71.30415 -22.44979)
		(end 71.30415 -27.829002)
		(width 0.13335)
		(layer "In2.Cu")
		(net "D85_PCIE_B_RX0_P")
	)
	(arc
		(start 71.926704 -21.1328)
		(mid 71.66238 -21.454923)
		(end 71.465948 -21.82241)
		(width 0.13335)
		(layer "In2.Cu")
		(net "D85_PCIE_B_RX0_P")
	)
	(arc
		(start 70.485 -28.263342)
		(mid 70.288556 -28.224267)
		(end 70.122034 -28.112974)
		(width 0.13335)
		(layer "In2.Cu")
		(net "D85_PCIE_B_RX0_P")
	)
	(arc
		(start 82.60842 -19.878802)
		(mid 82.348529 -20.052362)
		(end 82.042 -20.113244)
		(width 0.13335)
		(layer "In2.Cu")
		(net "D85_PCIE_B_RX0_P")
	)
	(arc
		(start 73.119234 -20.184618)
		(mid 72.727498 -20.393735)
		(end 72.384158 -20.675346)
		(width 0.13335)
		(layer "In2.Cu")
		(net "D85_PCIE_B_RX0_P")
	)
	(arc
		(start 71.394574 -21.994622)
		(mid 71.326933 -22.217751)
		(end 71.30415 -22.44979)
		(width 0.13335)
		(layer "In2.Cu")
		(net "D85_PCIE_B_RX0_P")
	)
	(arc
		(start 71.30415 -27.829002)
		(mid 71.271024 -27.995066)
		(end 71.176896 -28.135834)
		(width 0.13335)
		(layer "In2.Cu")
		(net "D85_PCIE_B_RX0_P")
	)
	(arc
		(start 73.477374 -20.113244)
		(mid 73.294791 -20.131306)
		(end 73.119234 -20.184618)
		(width 0.13335)
		(layer "In2.Cu")
		(net "D85_PCIE_B_RX0_P")
	)
	(arc
		(start 71.176896 -28.135834)
		(mid 71.035917 -28.23019)
		(end 70.869556 -28.263342)
		(width 0.13335)
		(layer "In2.Cu")
		(net "D85_PCIE_B_RX0_P")
	)
	(segment
		(start 71.655178 -28.652724)
		(end 71.626476 -28.624022)
		(width 0.136652)
		(layer "F.Cu")
		(net "D85_PCIE_B_RX0_N")
	)
	(segment
		(start 71.536814 -28.586938)
		(end 70.485 -28.586938)
		(width 0.136652)
		(layer "F.Cu")
		(net "D85_PCIE_B_RX0_N")
	)
	(segment
		(start 72.725026 -28.689808)
		(end 71.74484 -28.689808)
		(width 0.136652)
		(layer "F.Cu")
		(net "D85_PCIE_B_RX0_N")
	)
	(segment
		(start 70.122034 -28.737306)
		(end 69.8754 -28.98394)
		(width 0.136652)
		(layer "F.Cu")
		(net "D85_PCIE_B_RX0_N")
	)
	(via
		(at 69.8754 -28.98394)
		(size 0.508)
		(drill 0.254)
		(layers "F.Cu" "B.Cu")
		(net "D85_PCIE_B_RX0_N")
	)
	(via
		(at 82.611976 -20.675092)
		(size 0.508)
		(drill 0.254)
		(layers "F.Cu" "B.Cu")
		(net "D85_PCIE_B_RX0_N")
	)
	(arc
		(start 71.626476 -28.624022)
		(mid 71.585325 -28.596589)
		(end 71.536814 -28.586938)
		(width 0.136652)
		(layer "F.Cu")
		(net "D85_PCIE_B_RX0_N")
	)
	(arc
		(start 71.74484 -28.689808)
		(mid 71.696322 -28.680175)
		(end 71.655178 -28.652724)
		(width 0.136652)
		(layer "F.Cu")
		(net "D85_PCIE_B_RX0_N")
	)
	(arc
		(start 70.485 -28.586938)
		(mid 70.288556 -28.626013)
		(end 70.122034 -28.737306)
		(width 0.136652)
		(layer "F.Cu")
		(net "D85_PCIE_B_RX0_N")
	)
	(segment
		(start 81.380076 -20.675092)
		(end 82.611976 -20.675092)
		(width 0.136652)
		(layer "B.Cu")
		(net "D85_PCIE_B_RX0_N")
	)
	(segment
		(start 82.611976 -20.675092)
		(end 82.608674 -20.67179)
		(width 0.13335)
		(layer "In2.Cu")
		(net "D85_PCIE_B_RX0_N")
	)
	(segment
		(start 70.12178 -28.737814)
		(end 69.8754 -28.98394)
		(width 0.13335)
		(layer "In2.Cu")
		(net "D85_PCIE_B_RX0_N")
	)
	(segment
		(start 71.628 -22.44979)
		(end 71.628 -27.829002)
		(width 0.13335)
		(layer "In2.Cu")
		(net "D85_PCIE_B_RX0_N")
	)
	(segment
		(start 71.76516 -21.946362)
		(end 71.693786 -22.118574)
		(width 0.13335)
		(layer "In2.Cu")
		(net "D85_PCIE_B_RX0_N")
	)
	(segment
		(start 70.869556 -28.587192)
		(end 70.485 -28.587192)
		(width 0.13335)
		(layer "In2.Cu")
		(net "D85_PCIE_B_RX0_N")
	)
	(segment
		(start 72.613266 -20.904454)
		(end 72.155812 -21.361908)
		(width 0.13335)
		(layer "In2.Cu")
		(net "D85_PCIE_B_RX0_N")
	)
	(segment
		(start 82.042 -20.437094)
		(end 73.477628 -20.437094)
		(width 0.13335)
		(layer "In2.Cu")
		(net "D85_PCIE_B_RX0_N")
	)
	(arc
		(start 70.485 -28.587192)
		(mid 70.288415 -28.626389)
		(end 70.12178 -28.737814)
		(width 0.13335)
		(layer "In2.Cu")
		(net "D85_PCIE_B_RX0_N")
	)
	(arc
		(start 73.477628 -20.437094)
		(mid 73.358102 -20.448907)
		(end 73.243186 -20.48383)
		(width 0.13335)
		(layer "In2.Cu")
		(net "D85_PCIE_B_RX0_N")
	)
	(arc
		(start 73.243186 -20.48383)
		(mid 72.907464 -20.663054)
		(end 72.613266 -20.904454)
		(width 0.13335)
		(layer "In2.Cu")
		(net "D85_PCIE_B_RX0_N")
	)
	(arc
		(start 72.155812 -21.361908)
		(mid 71.931717 -21.634904)
		(end 71.76516 -21.946362)
		(width 0.13335)
		(layer "In2.Cu")
		(net "D85_PCIE_B_RX0_N")
	)
	(arc
		(start 82.608674 -20.67179)
		(mid 82.348682 -20.498069)
		(end 82.042 -20.437094)
		(width 0.13335)
		(layer "In2.Cu")
		(net "D85_PCIE_B_RX0_N")
	)
	(arc
		(start 71.406004 -28.364942)
		(mid 71.159894 -28.529451)
		(end 70.869556 -28.587192)
		(width 0.13335)
		(layer "In2.Cu")
		(net "D85_PCIE_B_RX0_N")
	)
	(arc
		(start 71.693786 -22.118574)
		(mid 71.644579 -22.280942)
		(end 71.628 -22.44979)
		(width 0.13335)
		(layer "In2.Cu")
		(net "D85_PCIE_B_RX0_N")
	)
	(arc
		(start 71.628 -27.829002)
		(mid 71.570306 -28.119052)
		(end 71.406004 -28.364942)
		(width 0.13335)
		(layer "In2.Cu")
		(net "D85_PCIE_B_RX0_N")
	)
	(segment
		(start 82.611976 -23.075138)
		(end 82.493358 -22.95652)
		(width 0.136652)
		(layer "F.Cu")
		(net "D85_PCIE_B_TX0_P")
	)
	(segment
		(start 78.499716 -26.249884)
		(end 78.499462 -26.249884)
		(width 0.136652)
		(layer "F.Cu")
		(net "D85_PCIE_B_TX0_P")
	)
	(segment
		(start 73.509632 -27.189938)
		(end 72.725026 -27.189938)
		(width 0.136652)
		(layer "F.Cu")
		(net "D85_PCIE_B_TX0_P")
	)
	(segment
		(start 76.47813 -27.087068)
		(end 73.758044 -27.087068)
		(width 0.136652)
		(layer "F.Cu")
		(net "D85_PCIE_B_TX0_P")
	)
	(segment
		(start 81.756758 -22.992842)
		(end 78.499716 -26.249884)
		(width 0.136652)
		(layer "F.Cu")
		(net "D85_PCIE_B_TX0_P")
	)
	(via
		(at 82.611976 -23.075138)
		(size 0.508)
		(drill 0.254)
		(layers "F.Cu" "B.Cu")
		(net "D85_PCIE_B_TX0_P")
	)
	(arc
		(start 73.758044 -27.087068)
		(mid 73.690975 -27.100409)
		(end 73.634092 -27.138376)
		(width 0.136652)
		(layer "F.Cu")
		(net "D85_PCIE_B_TX0_P")
	)
	(arc
		(start 78.499462 -26.249884)
		(mid 77.572067 -26.86955)
		(end 76.47813 -27.087068)
		(width 0.136652)
		(layer "F.Cu")
		(net "D85_PCIE_B_TX0_P")
	)
	(arc
		(start 82.493358 -22.95652)
		(mid 82.344541 -22.857084)
		(end 82.169 -22.822154)
		(width 0.136652)
		(layer "F.Cu")
		(net "D85_PCIE_B_TX0_P")
	)
	(arc
		(start 73.634092 -27.138376)
		(mid 73.576989 -27.176531)
		(end 73.509632 -27.189938)
		(width 0.136652)
		(layer "F.Cu")
		(net "D85_PCIE_B_TX0_P")
	)
	(arc
		(start 82.169 -22.822154)
		(mid 81.945908 -22.866512)
		(end 81.756758 -22.992842)
		(width 0.136652)
		(layer "F.Cu")
		(net "D85_PCIE_B_TX0_P")
	)
	(segment
		(start 81.380076 -23.075138)
		(end 82.611976 -23.075138)
		(width 0.136652)
		(layer "B.Cu")
		(net "D85_PCIE_B_TX0_P")
	)
	(segment
		(start 80.170274 -24.163274)
		(end 78.291436 -26.041858)
		(width 0.136652)
		(layer "F.Cu")
		(net "D85_PCIE_B_TX0_N")
	)
	(segment
		(start 73.509378 -26.689812)
		(end 72.725026 -26.689812)
		(width 0.136652)
		(layer "F.Cu")
		(net "D85_PCIE_B_TX0_N")
	)
	(segment
		(start 76.47813 -26.792936)
		(end 73.758298 -26.792936)
		(width 0.136652)
		(layer "F.Cu")
		(net "D85_PCIE_B_TX0_N")
	)
	(segment
		(start 81.548732 -22.784816)
		(end 80.170274 -24.163274)
		(width 0.136652)
		(layer "F.Cu")
		(net "D85_PCIE_B_TX0_N")
	)
	(segment
		(start 82.611976 -22.275038)
		(end 82.493358 -22.393656)
		(width 0.136652)
		(layer "F.Cu")
		(net "D85_PCIE_B_TX0_N")
	)
	(via
		(at 82.611976 -22.275038)
		(size 0.508)
		(drill 0.254)
		(layers "F.Cu" "B.Cu")
		(net "D85_PCIE_B_TX0_N")
	)
	(arc
		(start 73.758298 -26.792936)
		(mid 73.690937 -26.779537)
		(end 73.633838 -26.741374)
		(width 0.136652)
		(layer "F.Cu")
		(net "D85_PCIE_B_TX0_N")
	)
	(arc
		(start 82.493358 -22.393656)
		(mid 82.344541 -22.493092)
		(end 82.169 -22.528022)
		(width 0.136652)
		(layer "F.Cu")
		(net "D85_PCIE_B_TX0_N")
	)
	(arc
		(start 82.169 -22.528022)
		(mid 81.833334 -22.594754)
		(end 81.548732 -22.784816)
		(width 0.136652)
		(layer "F.Cu")
		(net "D85_PCIE_B_TX0_N")
	)
	(arc
		(start 73.633838 -26.741374)
		(mid 73.576735 -26.703219)
		(end 73.509378 -26.689812)
		(width 0.136652)
		(layer "F.Cu")
		(net "D85_PCIE_B_TX0_N")
	)
	(arc
		(start 78.291436 -26.041858)
		(mid 77.459484 -26.59775)
		(end 76.47813 -26.792936)
		(width 0.136652)
		(layer "F.Cu")
		(net "D85_PCIE_B_TX0_N")
	)
	(segment
		(start 81.380076 -22.275038)
		(end 82.611976 -22.275038)
		(width 0.136652)
		(layer "B.Cu")
		(net "D85_PCIE_B_TX0_N")
	)
	(segment
		(start 71.529956 -52.89296)
		(end 69.977 -52.89296)
		(width 0.136652)
		(layer "F.Cu")
		(net "D85_PCIE_A_RX1_P")
	)
	(segment
		(start 69.664326 -52.76342)
		(end 69.3674 -52.466494)
		(width 0.136652)
		(layer "F.Cu")
		(net "D85_PCIE_A_RX1_P")
	)
	(segment
		(start 72.725026 -52.79009)
		(end 71.737982 -52.79009)
		(width 0.136652)
		(layer "F.Cu")
		(net "D85_PCIE_A_RX1_P")
	)
	(segment
		(start 71.64832 -52.827174)
		(end 71.619618 -52.855876)
		(width 0.136652)
		(layer "F.Cu")
		(net "D85_PCIE_A_RX1_P")
	)
	(via
		(at 69.3674 -52.466494)
		(size 0.508)
		(drill 0.254)
		(layers "F.Cu" "B.Cu")
		(net "D85_PCIE_A_RX1_P")
	)
	(via
		(at 82.611976 -24.675084)
		(size 0.508)
		(drill 0.254)
		(layers "F.Cu" "B.Cu")
		(net "D85_PCIE_A_RX1_P")
	)
	(arc
		(start 71.619618 -52.855876)
		(mid 71.578467 -52.883309)
		(end 71.529956 -52.89296)
		(width 0.136652)
		(layer "F.Cu")
		(net "D85_PCIE_A_RX1_P")
	)
	(arc
		(start 69.977 -52.89296)
		(mid 69.807772 -52.859298)
		(end 69.664326 -52.76342)
		(width 0.136652)
		(layer "F.Cu")
		(net "D85_PCIE_A_RX1_P")
	)
	(arc
		(start 71.737982 -52.79009)
		(mid 71.689464 -52.799723)
		(end 71.64832 -52.827174)
		(width 0.136652)
		(layer "F.Cu")
		(net "D85_PCIE_A_RX1_P")
	)
	(segment
		(start 81.380076 -24.675084)
		(end 82.611976 -24.675084)
		(width 0.136652)
		(layer "B.Cu")
		(net "D85_PCIE_A_RX1_P")
	)
	(segment
		(start 70.589394 -47.700184)
		(end 70.4723 -47.981616)
		(width 0.13335)
		(layer "In2.Cu")
		(net "D85_PCIE_A_RX1_P")
	)
	(segment
		(start 78.9178 -28.458668)
		(end 78.9178 -38.099746)
		(width 0.13335)
		(layer "In2.Cu")
		(net "D85_PCIE_A_RX1_P")
	)
	(segment
		(start 82.169 -24.913336)
		(end 82.086958 -24.913336)
		(width 0.13335)
		(layer "In2.Cu")
		(net "D85_PCIE_A_RX1_P")
	)
	(segment
		(start 70.08495 -52.863496)
		(end 69.977 -52.863496)
		(width 0.13335)
		(layer "In2.Cu")
		(net "D85_PCIE_A_RX1_P")
	)
	(segment
		(start 78.9178 -38.099746)
		(end 78.917546 -38.099492)
		(width 0.13335)
		(layer "In2.Cu")
		(net "D85_PCIE_A_RX1_P")
	)
	(segment
		(start 79.098394 -27.76093)
		(end 79.017114 -27.957526)
		(width 0.13335)
		(layer "In2.Cu")
		(net "D85_PCIE_A_RX1_P")
	)
	(segment
		(start 70.33895 -48.65116)
		(end 70.33895 -52.609496)
		(width 0.13335)
		(layer "In2.Cu")
		(net "D85_PCIE_A_RX1_P")
	)
	(segment
		(start 81.408778 -25.193752)
		(end 79.614014 -26.98877)
		(width 0.13335)
		(layer "In2.Cu")
		(net "D85_PCIE_A_RX1_P")
	)
	(segment
		(start 78.23454 -39.748714)
		(end 71.2089 -46.774354)
		(width 0.13335)
		(layer "In2.Cu")
		(net "D85_PCIE_A_RX1_P")
	)
	(segment
		(start 69.614034 -52.713128)
		(end 69.3674 -52.466494)
		(width 0.13335)
		(layer "In2.Cu")
		(net "D85_PCIE_A_RX1_P")
	)
	(segment
		(start 82.611976 -24.675084)
		(end 82.518504 -24.768556)
		(width 0.13335)
		(layer "In2.Cu")
		(net "D85_PCIE_A_RX1_P")
	)
	(arc
		(start 70.33895 -52.609496)
		(mid 70.264555 -52.789101)
		(end 70.08495 -52.863496)
		(width 0.13335)
		(layer "In2.Cu")
		(net "D85_PCIE_A_RX1_P")
	)
	(arc
		(start 82.086958 -24.913336)
		(mid 81.719969 -24.986094)
		(end 81.408778 -25.193752)
		(width 0.13335)
		(layer "In2.Cu")
		(net "D85_PCIE_A_RX1_P")
	)
	(arc
		(start 82.518504 -24.768556)
		(mid 82.35815 -24.875701)
		(end 82.169 -24.913336)
		(width 0.13335)
		(layer "In2.Cu")
		(net "D85_PCIE_A_RX1_P")
	)
	(arc
		(start 70.4723 -47.981616)
		(mid 70.372537 -48.309798)
		(end 70.33895 -48.65116)
		(width 0.13335)
		(layer "In2.Cu")
		(net "D85_PCIE_A_RX1_P")
	)
	(arc
		(start 78.917546 -38.099492)
		(mid 78.740099 -38.992051)
		(end 78.23454 -39.748714)
		(width 0.13335)
		(layer "In2.Cu")
		(net "D85_PCIE_A_RX1_P")
	)
	(arc
		(start 69.977 -52.863496)
		(mid 69.780556 -52.824421)
		(end 69.614034 -52.713128)
		(width 0.13335)
		(layer "In2.Cu")
		(net "D85_PCIE_A_RX1_P")
	)
	(arc
		(start 79.614014 -26.98877)
		(mid 79.318095 -27.349406)
		(end 79.098394 -27.76093)
		(width 0.13335)
		(layer "In2.Cu")
		(net "D85_PCIE_A_RX1_P")
	)
	(arc
		(start 71.2089 -46.774354)
		(mid 70.853719 -47.206869)
		(end 70.589394 -47.700184)
		(width 0.13335)
		(layer "In2.Cu")
		(net "D85_PCIE_A_RX1_P")
	)
	(arc
		(start 79.017114 -27.957526)
		(mid 78.942833 -28.203215)
		(end 78.9178 -28.458668)
		(width 0.13335)
		(layer "In2.Cu")
		(net "D85_PCIE_A_RX1_P")
	)
	(segment
		(start 71.50862 -53.187092)
		(end 69.977 -53.187092)
		(width 0.136652)
		(layer "F.Cu")
		(net "D85_PCIE_A_RX1_N")
	)
	(segment
		(start 71.626984 -53.252878)
		(end 71.598282 -53.224176)
		(width 0.136652)
		(layer "F.Cu")
		(net "D85_PCIE_A_RX1_N")
	)
	(segment
		(start 69.614034 -53.33746)
		(end 69.3674 -53.584094)
		(width 0.136652)
		(layer "F.Cu")
		(net "D85_PCIE_A_RX1_N")
	)
	(segment
		(start 72.725026 -53.289962)
		(end 71.716646 -53.289962)
		(width 0.136652)
		(layer "F.Cu")
		(net "D85_PCIE_A_RX1_N")
	)
	(via
		(at 82.611976 -25.475184)
		(size 0.508)
		(drill 0.254)
		(layers "F.Cu" "B.Cu")
		(net "D85_PCIE_A_RX1_N")
	)
	(via
		(at 69.3674 -53.584094)
		(size 0.508)
		(drill 0.254)
		(layers "F.Cu" "B.Cu")
		(net "D85_PCIE_A_RX1_N")
	)
	(arc
		(start 69.977 -53.187092)
		(mid 69.780556 -53.226167)
		(end 69.614034 -53.33746)
		(width 0.136652)
		(layer "F.Cu")
		(net "D85_PCIE_A_RX1_N")
	)
	(arc
		(start 71.716646 -53.289962)
		(mid 71.668128 -53.280329)
		(end 71.626984 -53.252878)
		(width 0.136652)
		(layer "F.Cu")
		(net "D85_PCIE_A_RX1_N")
	)
	(arc
		(start 71.598282 -53.224176)
		(mid 71.557131 -53.196743)
		(end 71.50862 -53.187092)
		(width 0.136652)
		(layer "F.Cu")
		(net "D85_PCIE_A_RX1_N")
	)
	(segment
		(start 81.380076 -25.475184)
		(end 82.611976 -25.475184)
		(width 0.136652)
		(layer "B.Cu")
		(net "D85_PCIE_A_RX1_N")
	)
	(segment
		(start 69.61378 -53.337968)
		(end 69.3674 -53.584094)
		(width 0.13335)
		(layer "In2.Cu")
		(net "D85_PCIE_A_RX1_N")
	)
	(segment
		(start 81.637886 -25.423114)
		(end 79.843122 -27.217878)
		(width 0.13335)
		(layer "In2.Cu")
		(net "D85_PCIE_A_RX1_N")
	)
	(segment
		(start 70.08495 -53.187346)
		(end 69.977 -53.187346)
		(width 0.13335)
		(layer "In2.Cu")
		(net "D85_PCIE_A_RX1_N")
	)
	(segment
		(start 82.611976 -25.475184)
		(end 82.518758 -25.38222)
		(width 0.13335)
		(layer "In2.Cu")
		(net "D85_PCIE_A_RX1_N")
	)
	(segment
		(start 82.169 -25.237186)
		(end 82.086958 -25.237186)
		(width 0.13335)
		(layer "In2.Cu")
		(net "D85_PCIE_A_RX1_N")
	)
	(segment
		(start 79.39786 -27.884882)
		(end 79.31658 -28.081478)
		(width 0.13335)
		(layer "In2.Cu")
		(net "D85_PCIE_A_RX1_N")
	)
	(segment
		(start 70.6628 -48.65116)
		(end 70.6628 -52.609496)
		(width 0.13335)
		(layer "In2.Cu")
		(net "D85_PCIE_A_RX1_N")
	)
	(segment
		(start 79.24165 -28.458668)
		(end 79.24165 -38.099492)
		(width 0.13335)
		(layer "In2.Cu")
		(net "D85_PCIE_A_RX1_N")
	)
	(segment
		(start 78.463648 -39.977822)
		(end 71.438008 -47.003462)
		(width 0.13335)
		(layer "In2.Cu")
		(net "D85_PCIE_A_RX1_N")
	)
	(segment
		(start 70.888606 -47.824644)
		(end 70.771512 -48.106076)
		(width 0.13335)
		(layer "In2.Cu")
		(net "D85_PCIE_A_RX1_N")
	)
	(arc
		(start 70.6628 -52.609496)
		(mid 70.493552 -53.018098)
		(end 70.08495 -53.187346)
		(width 0.13335)
		(layer "In2.Cu")
		(net "D85_PCIE_A_RX1_N")
	)
	(arc
		(start 71.438008 -47.003462)
		(mid 71.122987 -47.387078)
		(end 70.888606 -47.824644)
		(width 0.13335)
		(layer "In2.Cu")
		(net "D85_PCIE_A_RX1_N")
	)
	(arc
		(start 82.086958 -25.237186)
		(mid 81.84394 -25.285507)
		(end 81.637886 -25.423114)
		(width 0.13335)
		(layer "In2.Cu")
		(net "D85_PCIE_A_RX1_N")
	)
	(arc
		(start 79.31658 -28.081478)
		(mid 79.260561 -28.266387)
		(end 79.24165 -28.458668)
		(width 0.13335)
		(layer "In2.Cu")
		(net "D85_PCIE_A_RX1_N")
	)
	(arc
		(start 69.977 -53.187346)
		(mid 69.780415 -53.226543)
		(end 69.61378 -53.337968)
		(width 0.13335)
		(layer "In2.Cu")
		(net "D85_PCIE_A_RX1_N")
	)
	(arc
		(start 82.518758 -25.38222)
		(mid 82.358303 -25.274914)
		(end 82.169 -25.237186)
		(width 0.13335)
		(layer "In2.Cu")
		(net "D85_PCIE_A_RX1_N")
	)
	(arc
		(start 79.24165 -38.099492)
		(mid 79.039449 -39.116026)
		(end 78.463648 -39.977822)
		(width 0.13335)
		(layer "In2.Cu")
		(net "D85_PCIE_A_RX1_N")
	)
	(arc
		(start 79.843122 -27.217878)
		(mid 79.587583 -27.529413)
		(end 79.39786 -27.884882)
		(width 0.13335)
		(layer "In2.Cu")
		(net "D85_PCIE_A_RX1_N")
	)
	(arc
		(start 70.771512 -48.106076)
		(mid 70.690232 -48.373247)
		(end 70.6628 -48.65116)
		(width 0.13335)
		(layer "In2.Cu")
		(net "D85_PCIE_A_RX1_N")
	)
	(segment
		(start 76.3524 -45.703744)
		(end 76.3524 -50.424588)
		(width 0.136652)
		(layer "F.Cu")
		(net "D85_PCIE_A_TX1_P")
	)
	(segment
		(start 73.641204 -51.73853)
		(end 73.630028 -51.749706)
		(width 0.136652)
		(layer "F.Cu")
		(net "D85_PCIE_A_TX1_P")
	)
	(segment
		(start 73.533 -51.790092)
		(end 72.725026 -51.790092)
		(width 0.136652)
		(layer "F.Cu")
		(net "D85_PCIE_A_TX1_P")
	)
	(segment
		(start 81.411826 -27.808174)
		(end 80.710024 -28.509976)
		(width 0.136652)
		(layer "F.Cu")
		(net "D85_PCIE_A_TX1_P")
	)
	(segment
		(start 75.089766 -51.687222)
		(end 73.76541 -51.687222)
		(width 0.136652)
		(layer "F.Cu")
		(net "D85_PCIE_A_TX1_P")
	)
	(segment
		(start 80.161384 -29.329126)
		(end 79.062326 -31.966916)
		(width 0.136652)
		(layer "F.Cu")
		(net "D85_PCIE_A_TX1_P")
	)
	(segment
		(start 82.611976 -27.874976)
		(end 82.493612 -27.756866)
		(width 0.136652)
		(layer "F.Cu")
		(net "D85_PCIE_A_TX1_P")
	)
	(segment
		(start 82.169 -27.622246)
		(end 81.860898 -27.622246)
		(width 0.136652)
		(layer "F.Cu")
		(net "D85_PCIE_A_TX1_P")
	)
	(segment
		(start 78.867 -32.9438)
		(end 78.867 -42.662856)
		(width 0.136652)
		(layer "F.Cu")
		(net "D85_PCIE_A_TX1_P")
	)
	(segment
		(start 78.681072 -43.111928)
		(end 76.538328 -45.254672)
		(width 0.136652)
		(layer "F.Cu")
		(net "D85_PCIE_A_TX1_P")
	)
	(via
		(at 82.611976 -27.874976)
		(size 0.508)
		(drill 0.254)
		(layers "F.Cu" "B.Cu")
		(net "D85_PCIE_A_TX1_P")
	)
	(arc
		(start 76.538328 -45.254672)
		(mid 76.400713 -45.460722)
		(end 76.3524 -45.703744)
		(width 0.136652)
		(layer "F.Cu")
		(net "D85_PCIE_A_TX1_P")
	)
	(arc
		(start 73.76541 -51.687222)
		(mid 73.698229 -51.700567)
		(end 73.641204 -51.73853)
		(width 0.136652)
		(layer "F.Cu")
		(net "D85_PCIE_A_TX1_P")
	)
	(arc
		(start 80.710024 -28.509976)
		(mid 80.395572 -28.892673)
		(end 80.161384 -29.329126)
		(width 0.136652)
		(layer "F.Cu")
		(net "D85_PCIE_A_TX1_P")
	)
	(arc
		(start 79.062326 -31.966916)
		(mid 78.916281 -32.445686)
		(end 78.867 -32.9438)
		(width 0.136652)
		(layer "F.Cu")
		(net "D85_PCIE_A_TX1_P")
	)
	(arc
		(start 82.493612 -27.756866)
		(mid 82.344694 -27.657269)
		(end 82.169 -27.622246)
		(width 0.136652)
		(layer "F.Cu")
		(net "D85_PCIE_A_TX1_P")
	)
	(arc
		(start 78.867 -42.662856)
		(mid 78.818679 -42.905874)
		(end 78.681072 -43.111928)
		(width 0.136652)
		(layer "F.Cu")
		(net "D85_PCIE_A_TX1_P")
	)
	(arc
		(start 76.3524 -50.424588)
		(mid 75.982583 -51.317405)
		(end 75.089766 -51.687222)
		(width 0.136652)
		(layer "F.Cu")
		(net "D85_PCIE_A_TX1_P")
	)
	(arc
		(start 73.630028 -51.749706)
		(mid 73.585554 -51.779613)
		(end 73.533 -51.790092)
		(width 0.136652)
		(layer "F.Cu")
		(net "D85_PCIE_A_TX1_P")
	)
	(arc
		(start 81.860898 -27.622246)
		(mid 81.61788 -27.670567)
		(end 81.411826 -27.808174)
		(width 0.136652)
		(layer "F.Cu")
		(net "D85_PCIE_A_TX1_P")
	)
	(segment
		(start 81.380076 -27.874976)
		(end 82.611976 -27.874976)
		(width 0.136652)
		(layer "B.Cu")
		(net "D85_PCIE_A_TX1_P")
	)
	(segment
		(start 82.611976 -27.07513)
		(end 82.493358 -27.193748)
		(width 0.136652)
		(layer "F.Cu")
		(net "D85_PCIE_A_TX1_N")
	)
	(segment
		(start 76.058268 -45.703744)
		(end 76.058268 -50.424588)
		(width 0.136652)
		(layer "F.Cu")
		(net "D85_PCIE_A_TX1_N")
	)
	(segment
		(start 73.509378 -51.289966)
		(end 72.725026 -51.289966)
		(width 0.136652)
		(layer "F.Cu")
		(net "D85_PCIE_A_TX1_N")
	)
	(segment
		(start 78.572868 -32.9438)
		(end 78.572868 -42.662856)
		(width 0.136652)
		(layer "F.Cu")
		(net "D85_PCIE_A_TX1_N")
	)
	(segment
		(start 75.089766 -51.39309)
		(end 73.758298 -51.39309)
		(width 0.136652)
		(layer "F.Cu")
		(net "D85_PCIE_A_TX1_N")
	)
	(segment
		(start 82.169 -27.328114)
		(end 81.860898 -27.328114)
		(width 0.136652)
		(layer "F.Cu")
		(net "D85_PCIE_A_TX1_N")
	)
	(segment
		(start 81.2038 -27.600148)
		(end 80.501998 -28.30195)
		(width 0.136652)
		(layer "F.Cu")
		(net "D85_PCIE_A_TX1_N")
	)
	(segment
		(start 78.473046 -42.903902)
		(end 76.330302 -45.046646)
		(width 0.136652)
		(layer "F.Cu")
		(net "D85_PCIE_A_TX1_N")
	)
	(segment
		(start 79.889604 -29.215842)
		(end 78.790546 -31.853632)
		(width 0.136652)
		(layer "F.Cu")
		(net "D85_PCIE_A_TX1_N")
	)
	(via
		(at 82.611976 -27.07513)
		(size 0.508)
		(drill 0.254)
		(layers "F.Cu" "B.Cu")
		(net "D85_PCIE_A_TX1_N")
	)
	(arc
		(start 73.758298 -51.39309)
		(mid 73.690937 -51.379691)
		(end 73.633838 -51.341528)
		(width 0.136652)
		(layer "F.Cu")
		(net "D85_PCIE_A_TX1_N")
	)
	(arc
		(start 78.790546 -31.853632)
		(mid 78.627716 -32.387937)
		(end 78.572868 -32.9438)
		(width 0.136652)
		(layer "F.Cu")
		(net "D85_PCIE_A_TX1_N")
	)
	(arc
		(start 76.058268 -50.424588)
		(mid 75.7746 -51.109422)
		(end 75.089766 -51.39309)
		(width 0.136652)
		(layer "F.Cu")
		(net "D85_PCIE_A_TX1_N")
	)
	(arc
		(start 76.330302 -45.046646)
		(mid 76.128967 -45.348154)
		(end 76.058268 -45.703744)
		(width 0.136652)
		(layer "F.Cu")
		(net "D85_PCIE_A_TX1_N")
	)
	(arc
		(start 80.501998 -28.30195)
		(mid 80.151046 -28.728905)
		(end 79.889604 -29.215842)
		(width 0.136652)
		(layer "F.Cu")
		(net "D85_PCIE_A_TX1_N")
	)
	(arc
		(start 78.572868 -42.662856)
		(mid 78.546921 -42.793301)
		(end 78.473046 -42.903902)
		(width 0.136652)
		(layer "F.Cu")
		(net "D85_PCIE_A_TX1_N")
	)
	(arc
		(start 81.860898 -27.328114)
		(mid 81.505306 -27.39881)
		(end 81.2038 -27.600148)
		(width 0.136652)
		(layer "F.Cu")
		(net "D85_PCIE_A_TX1_N")
	)
	(arc
		(start 82.493358 -27.193748)
		(mid 82.344541 -27.293184)
		(end 82.169 -27.328114)
		(width 0.136652)
		(layer "F.Cu")
		(net "D85_PCIE_A_TX1_N")
	)
	(arc
		(start 73.633838 -51.341528)
		(mid 73.576735 -51.303373)
		(end 73.509378 -51.289966)
		(width 0.136652)
		(layer "F.Cu")
		(net "D85_PCIE_A_TX1_N")
	)
	(segment
		(start 81.380076 -27.07513)
		(end 82.611976 -27.07513)
		(width 0.136652)
		(layer "B.Cu")
		(net "D85_PCIE_A_TX1_N")
	)
	(segment
		(start 71.655178 -56.252872)
		(end 71.626476 -56.22417)
		(width 0.136652)
		(layer "F.Cu")
		(net "D85_PCIE_A_RX0_N")
	)
	(segment
		(start 72.725026 -56.289956)
		(end 71.74484 -56.289956)
		(width 0.136652)
		(layer "F.Cu")
		(net "D85_PCIE_A_RX0_N")
	)
	(segment
		(start 71.536814 -56.187086)
		(end 70.485 -56.187086)
		(width 0.136652)
		(layer "F.Cu")
		(net "D85_PCIE_A_RX0_N")
	)
	(segment
		(start 70.122034 -56.337454)
		(end 69.8754 -56.584088)
		(width 0.136652)
		(layer "F.Cu")
		(net "D85_PCIE_A_RX0_N")
	)
	(via
		(at 69.8754 -56.584088)
		(size 0.508)
		(drill 0.254)
		(layers "F.Cu" "B.Cu")
		(net "D85_PCIE_A_RX0_N")
	)
	(via
		(at 82.611976 -38.275006)
		(size 0.508)
		(drill 0.254)
		(layers "F.Cu" "B.Cu")
		(net "D85_PCIE_A_RX0_N")
	)
	(arc
		(start 71.626476 -56.22417)
		(mid 71.585325 -56.196737)
		(end 71.536814 -56.187086)
		(width 0.136652)
		(layer "F.Cu")
		(net "D85_PCIE_A_RX0_N")
	)
	(arc
		(start 70.485 -56.187086)
		(mid 70.288556 -56.226161)
		(end 70.122034 -56.337454)
		(width 0.136652)
		(layer "F.Cu")
		(net "D85_PCIE_A_RX0_N")
	)
	(arc
		(start 71.74484 -56.289956)
		(mid 71.696322 -56.280323)
		(end 71.655178 -56.252872)
		(width 0.136652)
		(layer "F.Cu")
		(net "D85_PCIE_A_RX0_N")
	)
	(segment
		(start 81.380076 -38.275006)
		(end 82.611976 -38.275006)
		(width 0.136652)
		(layer "B.Cu")
		(net "D85_PCIE_A_RX0_N")
	)
	(segment
		(start 82.169254 -38.037008)
		(end 81.294986 -38.037008)
		(width 0.13335)
		(layer "In2.Cu")
		(net "D85_PCIE_A_RX0_N")
	)
	(segment
		(start 80.540606 -38.791388)
		(end 80.540606 -43.02125)
		(width 0.13335)
		(layer "In2.Cu")
		(net "D85_PCIE_A_RX0_N")
	)
	(segment
		(start 71.628254 -49.230788)
		(end 71.628 -49.230534)
		(width 0.13335)
		(layer "In2.Cu")
		(net "D85_PCIE_A_RX0_N")
	)
	(segment
		(start 76.421996 -47.13986)
		(end 72.795638 -47.13986)
		(width 0.13335)
		(layer "In2.Cu")
		(net "D85_PCIE_A_RX0_N")
	)
	(segment
		(start 81.075022 -38.128448)
		(end 80.631792 -38.571424)
		(width 0.13335)
		(layer "In2.Cu")
		(net "D85_PCIE_A_RX0_N")
	)
	(segment
		(start 71.628 -49.230534)
		(end 71.628 -55.42915)
		(width 0.13335)
		(layer "In2.Cu")
		(net "D85_PCIE_A_RX0_N")
	)
	(segment
		(start 70.12178 -56.337962)
		(end 69.8754 -56.584088)
		(width 0.13335)
		(layer "In2.Cu")
		(net "D85_PCIE_A_RX0_N")
	)
	(segment
		(start 80.354678 -43.470322)
		(end 76.871068 -46.953932)
		(width 0.13335)
		(layer "In2.Cu")
		(net "D85_PCIE_A_RX0_N")
	)
	(segment
		(start 72.575674 -47.2313)
		(end 72.371966 -47.434754)
		(width 0.13335)
		(layer "In2.Cu")
		(net "D85_PCIE_A_RX0_N")
	)
	(segment
		(start 70.869556 -56.18734)
		(end 70.485 -56.18734)
		(width 0.13335)
		(layer "In2.Cu")
		(net "D85_PCIE_A_RX0_N")
	)
	(segment
		(start 82.611976 -38.275006)
		(end 82.518758 -38.182042)
		(width 0.13335)
		(layer "In2.Cu")
		(net "D85_PCIE_A_RX0_N")
	)
	(arc
		(start 71.406004 -55.96509)
		(mid 71.159894 -56.129599)
		(end 70.869556 -56.18734)
		(width 0.13335)
		(layer "In2.Cu")
		(net "D85_PCIE_A_RX0_N")
	)
	(arc
		(start 70.485 -56.18734)
		(mid 70.288415 -56.226537)
		(end 70.12178 -56.337962)
		(width 0.13335)
		(layer "In2.Cu")
		(net "D85_PCIE_A_RX0_N")
	)
	(arc
		(start 71.628 -55.42915)
		(mid 71.570306 -55.7192)
		(end 71.406004 -55.96509)
		(width 0.13335)
		(layer "In2.Cu")
		(net "D85_PCIE_A_RX0_N")
	)
	(arc
		(start 80.540606 -43.02125)
		(mid 80.492285 -43.264268)
		(end 80.354678 -43.470322)
		(width 0.13335)
		(layer "In2.Cu")
		(net "D85_PCIE_A_RX0_N")
	)
	(arc
		(start 82.518758 -38.182042)
		(mid 82.35842 -38.074785)
		(end 82.169254 -38.037008)
		(width 0.13335)
		(layer "In2.Cu")
		(net "D85_PCIE_A_RX0_N")
	)
	(arc
		(start 72.371966 -47.434754)
		(mid 71.821451 -48.258796)
		(end 71.628254 -49.230788)
		(width 0.13335)
		(layer "In2.Cu")
		(net "D85_PCIE_A_RX0_N")
	)
	(arc
		(start 72.795638 -47.13986)
		(mid 72.676591 -47.163745)
		(end 72.575674 -47.2313)
		(width 0.13335)
		(layer "In2.Cu")
		(net "D85_PCIE_A_RX0_N")
	)
	(arc
		(start 80.631792 -38.571424)
		(mid 80.56433 -38.672344)
		(end 80.540606 -38.791388)
		(width 0.13335)
		(layer "In2.Cu")
		(net "D85_PCIE_A_RX0_N")
	)
	(arc
		(start 76.871068 -46.953932)
		(mid 76.665018 -47.091547)
		(end 76.421996 -47.13986)
		(width 0.13335)
		(layer "In2.Cu")
		(net "D85_PCIE_A_RX0_N")
	)
	(arc
		(start 81.294986 -38.037008)
		(mid 81.175939 -38.060893)
		(end 81.075022 -38.128448)
		(width 0.13335)
		(layer "In2.Cu")
		(net "D85_PCIE_A_RX0_N")
	)
	(segment
		(start 73.641204 -54.738524)
		(end 73.630028 -54.7497)
		(width 0.136652)
		(layer "F.Cu")
		(net "D85_PCIE_A_TX0_P")
	)
	(segment
		(start 80.459326 -41.850818)
		(end 80.459326 -42.634662)
		(width 0.136652)
		(layer "F.Cu")
		(net "D85_PCIE_A_TX0_P")
	)
	(segment
		(start 74.744072 -54.687216)
		(end 73.76541 -54.687216)
		(width 0.136652)
		(layer "F.Cu")
		(net "D85_PCIE_A_TX0_P")
	)
	(segment
		(start 79.610966 -55.044086)
		(end 79.555086 -55.099966)
		(width 0.136652)
		(layer "F.Cu")
		(net "D85_PCIE_A_TX0_P")
	)
	(segment
		(start 78.897988 -55.372)
		(end 75.955144 -55.372)
		(width 0.136652)
		(layer "F.Cu")
		(net "D85_PCIE_A_TX0_P")
	)
	(segment
		(start 77.595222 -48.85817)
		(end 79.610966 -50.873914)
		(width 0.136652)
		(layer "F.Cu")
		(net "D85_PCIE_A_TX0_P")
	)
	(segment
		(start 82.001106 -40.422068)
		(end 81.888076 -40.422068)
		(width 0.136652)
		(layer "F.Cu")
		(net "D85_PCIE_A_TX0_P")
	)
	(segment
		(start 75.506072 -55.186072)
		(end 75.193144 -54.873144)
		(width 0.136652)
		(layer "F.Cu")
		(net "D85_PCIE_A_TX0_P")
	)
	(segment
		(start 77.4954 -46.124876)
		(end 77.4954 -48.617124)
		(width 0.136652)
		(layer "F.Cu")
		(net "D85_PCIE_A_TX0_P")
	)
	(segment
		(start 79.883 -51.531012)
		(end 79.883 -54.386988)
		(width 0.136652)
		(layer "F.Cu")
		(net "D85_PCIE_A_TX0_P")
	)
	(segment
		(start 73.533 -54.790086)
		(end 72.725026 -54.790086)
		(width 0.136652)
		(layer "F.Cu")
		(net "D85_PCIE_A_TX0_P")
	)
	(segment
		(start 81.439004 -40.607996)
		(end 80.645254 -41.401746)
		(width 0.136652)
		(layer "F.Cu")
		(net "D85_PCIE_A_TX0_P")
	)
	(segment
		(start 80.187292 -43.29176)
		(end 77.595222 -45.88383)
		(width 0.136652)
		(layer "F.Cu")
		(net "D85_PCIE_A_TX0_P")
	)
	(via
		(at 82.611976 -40.675052)
		(size 0.508)
		(drill 0.254)
		(layers "F.Cu" "B.Cu")
		(net "D85_PCIE_A_TX0_P")
	)
	(arc
		(start 79.555086 -55.099966)
		(mid 79.253578 -55.301301)
		(end 78.897988 -55.372)
		(width 0.136652)
		(layer "F.Cu")
		(net "D85_PCIE_A_TX0_P")
	)
	(arc
		(start 82.611976 -40.675052)
		(mid 82.331706 -40.487782)
		(end 82.001106 -40.422068)
		(width 0.136652)
		(layer "F.Cu")
		(net "D85_PCIE_A_TX0_P")
	)
	(arc
		(start 75.193144 -54.873144)
		(mid 74.987094 -54.735529)
		(end 74.744072 -54.687216)
		(width 0.136652)
		(layer "F.Cu")
		(net "D85_PCIE_A_TX0_P")
	)
	(arc
		(start 77.595222 -45.88383)
		(mid 77.521326 -45.994423)
		(end 77.4954 -46.124876)
		(width 0.136652)
		(layer "F.Cu")
		(net "D85_PCIE_A_TX0_P")
	)
	(arc
		(start 73.76541 -54.687216)
		(mid 73.698229 -54.700561)
		(end 73.641204 -54.738524)
		(width 0.136652)
		(layer "F.Cu")
		(net "D85_PCIE_A_TX0_P")
	)
	(arc
		(start 80.645254 -41.401746)
		(mid 80.507639 -41.607796)
		(end 80.459326 -41.850818)
		(width 0.136652)
		(layer "F.Cu")
		(net "D85_PCIE_A_TX0_P")
	)
	(arc
		(start 81.888076 -40.422068)
		(mid 81.645058 -40.470389)
		(end 81.439004 -40.607996)
		(width 0.136652)
		(layer "F.Cu")
		(net "D85_PCIE_A_TX0_P")
	)
	(arc
		(start 79.610966 -50.873914)
		(mid 79.812301 -51.175422)
		(end 79.883 -51.531012)
		(width 0.136652)
		(layer "F.Cu")
		(net "D85_PCIE_A_TX0_P")
	)
	(arc
		(start 73.630028 -54.7497)
		(mid 73.585554 -54.779607)
		(end 73.533 -54.790086)
		(width 0.136652)
		(layer "F.Cu")
		(net "D85_PCIE_A_TX0_P")
	)
	(arc
		(start 79.883 -54.386988)
		(mid 79.812304 -54.74258)
		(end 79.610966 -55.044086)
		(width 0.136652)
		(layer "F.Cu")
		(net "D85_PCIE_A_TX0_P")
	)
	(arc
		(start 77.4954 -48.617124)
		(mid 77.521347 -48.747569)
		(end 77.595222 -48.85817)
		(width 0.136652)
		(layer "F.Cu")
		(net "D85_PCIE_A_TX0_P")
	)
	(arc
		(start 80.459326 -42.634662)
		(mid 80.38863 -42.990254)
		(end 80.187292 -43.29176)
		(width 0.136652)
		(layer "F.Cu")
		(net "D85_PCIE_A_TX0_P")
	)
	(arc
		(start 75.955144 -55.372)
		(mid 75.712126 -55.323679)
		(end 75.506072 -55.186072)
		(width 0.136652)
		(layer "F.Cu")
		(net "D85_PCIE_A_TX0_P")
	)
	(segment
		(start 81.380076 -40.675052)
		(end 82.611976 -40.675052)
		(width 0.136652)
		(layer "B.Cu")
		(net "D85_PCIE_A_TX0_P")
	)
	(segment
		(start 74.744072 -54.393084)
		(end 73.758298 -54.393084)
		(width 0.136652)
		(layer "F.Cu")
		(net "D85_PCIE_A_TX0_N")
	)
	(segment
		(start 73.509378 -54.28996)
		(end 72.725026 -54.28996)
		(width 0.136652)
		(layer "F.Cu")
		(net "D85_PCIE_A_TX0_N")
	)
	(segment
		(start 77.201268 -46.124876)
		(end 77.201268 -48.617124)
		(width 0.136652)
		(layer "F.Cu")
		(net "D85_PCIE_A_TX0_N")
	)
	(segment
		(start 78.897988 -55.077868)
		(end 75.955144 -55.077868)
		(width 0.136652)
		(layer "F.Cu")
		(net "D85_PCIE_A_TX0_N")
	)
	(segment
		(start 80.165194 -41.850818)
		(end 80.165194 -42.634662)
		(width 0.136652)
		(layer "F.Cu")
		(net "D85_PCIE_A_TX0_N")
	)
	(segment
		(start 79.588868 -51.531012)
		(end 79.588868 -54.386988)
		(width 0.136652)
		(layer "F.Cu")
		(net "D85_PCIE_A_TX0_N")
	)
	(segment
		(start 79.40294 -54.83606)
		(end 79.34706 -54.89194)
		(width 0.136652)
		(layer "F.Cu")
		(net "D85_PCIE_A_TX0_N")
	)
	(segment
		(start 75.714098 -54.978046)
		(end 75.40117 -54.665118)
		(width 0.136652)
		(layer "F.Cu")
		(net "D85_PCIE_A_TX0_N")
	)
	(segment
		(start 81.230978 -40.39997)
		(end 80.437228 -41.19372)
		(width 0.136652)
		(layer "F.Cu")
		(net "D85_PCIE_A_TX0_N")
	)
	(segment
		(start 77.387196 -49.066196)
		(end 79.40294 -51.08194)
		(width 0.136652)
		(layer "F.Cu")
		(net "D85_PCIE_A_TX0_N")
	)
	(segment
		(start 82.001106 -40.127936)
		(end 81.888076 -40.127936)
		(width 0.136652)
		(layer "F.Cu")
		(net "D85_PCIE_A_TX0_N")
	)
	(segment
		(start 79.979266 -43.083734)
		(end 77.387196 -45.675804)
		(width 0.136652)
		(layer "F.Cu")
		(net "D85_PCIE_A_TX0_N")
	)
	(via
		(at 82.611976 -39.874952)
		(size 0.508)
		(drill 0.254)
		(layers "F.Cu" "B.Cu")
		(net "D85_PCIE_A_TX0_N")
	)
	(arc
		(start 77.387196 -45.675804)
		(mid 77.249581 -45.881854)
		(end 77.201268 -46.124876)
		(width 0.136652)
		(layer "F.Cu")
		(net "D85_PCIE_A_TX0_N")
	)
	(arc
		(start 77.201268 -48.617124)
		(mid 77.249589 -48.860142)
		(end 77.387196 -49.066196)
		(width 0.136652)
		(layer "F.Cu")
		(net "D85_PCIE_A_TX0_N")
	)
	(arc
		(start 75.955144 -55.077868)
		(mid 75.824699 -55.051921)
		(end 75.714098 -54.978046)
		(width 0.136652)
		(layer "F.Cu")
		(net "D85_PCIE_A_TX0_N")
	)
	(arc
		(start 73.633838 -54.341522)
		(mid 73.576735 -54.303367)
		(end 73.509378 -54.28996)
		(width 0.136652)
		(layer "F.Cu")
		(net "D85_PCIE_A_TX0_N")
	)
	(arc
		(start 73.758298 -54.393084)
		(mid 73.690937 -54.379685)
		(end 73.633838 -54.341522)
		(width 0.136652)
		(layer "F.Cu")
		(net "D85_PCIE_A_TX0_N")
	)
	(arc
		(start 75.40117 -54.665118)
		(mid 75.099662 -54.463783)
		(end 74.744072 -54.393084)
		(width 0.136652)
		(layer "F.Cu")
		(net "D85_PCIE_A_TX0_N")
	)
	(arc
		(start 79.40294 -51.08194)
		(mid 79.540555 -51.28799)
		(end 79.588868 -51.531012)
		(width 0.136652)
		(layer "F.Cu")
		(net "D85_PCIE_A_TX0_N")
	)
	(arc
		(start 80.165194 -42.634662)
		(mid 80.116873 -42.87768)
		(end 79.979266 -43.083734)
		(width 0.136652)
		(layer "F.Cu")
		(net "D85_PCIE_A_TX0_N")
	)
	(arc
		(start 79.588868 -54.386988)
		(mid 79.540547 -54.630006)
		(end 79.40294 -54.83606)
		(width 0.136652)
		(layer "F.Cu")
		(net "D85_PCIE_A_TX0_N")
	)
	(arc
		(start 82.611976 -39.874952)
		(mid 82.331706 -40.062222)
		(end 82.001106 -40.127936)
		(width 0.136652)
		(layer "F.Cu")
		(net "D85_PCIE_A_TX0_N")
	)
	(arc
		(start 79.34706 -54.89194)
		(mid 79.14101 -55.029555)
		(end 78.897988 -55.077868)
		(width 0.136652)
		(layer "F.Cu")
		(net "D85_PCIE_A_TX0_N")
	)
	(arc
		(start 81.888076 -40.127936)
		(mid 81.532484 -40.198632)
		(end 81.230978 -40.39997)
		(width 0.136652)
		(layer "F.Cu")
		(net "D85_PCIE_A_TX0_N")
	)
	(arc
		(start 80.437228 -41.19372)
		(mid 80.235893 -41.495228)
		(end 80.165194 -41.850818)
		(width 0.136652)
		(layer "F.Cu")
		(net "D85_PCIE_A_TX0_N")
	)
	(segment
		(start 81.380076 -39.874952)
		(end 82.611976 -39.874952)
		(width 0.136652)
		(layer "B.Cu")
		(net "D85_PCIE_A_TX0_N")
	)
	(segment
		(start 73.583546 -49.790096)
		(end 72.725026 -49.790096)
		(width 0.136652)
		(layer "F.Cu")
		(net "D85_PCIE_A_REFCLK_P")
	)
	(via
		(at 73.9902 -49.621694)
		(size 0.508)
		(drill 0.254)
		(layers "F.Cu" "B.Cu")
		(net "D85_PCIE_A_REFCLK_P")
	)
	(via
		(at 82.611976 -43.075098)
		(size 0.508)
		(drill 0.254)
		(layers "F.Cu" "B.Cu")
		(net "D85_PCIE_A_REFCLK_P")
	)
	(arc
		(start 73.9902 -49.621694)
		(mid 73.803611 -49.746305)
		(end 73.583546 -49.790096)
		(width 0.136652)
		(layer "F.Cu")
		(net "D85_PCIE_A_REFCLK_P")
	)
	(segment
		(start 82.611976 -43.075098)
		(end 81.380076 -43.075098)
		(width 0.136652)
		(layer "B.Cu")
		(net "D85_PCIE_A_REFCLK_P")
	)
	(segment
		(start 79.18704 -43.02506)
		(end 79.58709 -43.02506)
		(width 0.13335)
		(layer "In5.Cu")
		(net "D85_PCIE_A_REFCLK_P")
	)
	(segment
		(start 74.848466 -44.150534)
		(end 75.131422 -43.867578)
		(width 0.13335)
		(layer "In5.Cu")
		(net "D85_PCIE_A_REFCLK_P")
	)
	(segment
		(start 78.41107 -42.8371)
		(end 78.81112 -42.8371)
		(width 0.13335)
		(layer "In5.Cu")
		(net "D85_PCIE_A_REFCLK_P")
	)
	(segment
		(start 72.800718 -46.198282)
		(end 72.936608 -46.062392)
		(width 0.13335)
		(layer "In5.Cu")
		(net "D85_PCIE_A_REFCLK_P")
	)
	(segment
		(start 72.83196 -49.125886)
		(end 72.83196 -48.725836)
		(width 0.13335)
		(layer "In5.Cu")
		(net "D85_PCIE_A_REFCLK_P")
	)
	(segment
		(start 82.518758 -42.982134)
		(end 82.611976 -43.075098)
		(width 0.13335)
		(layer "In5.Cu")
		(net "D85_PCIE_A_REFCLK_P")
	)
	(segment
		(start 79.96301 -42.8371)
		(end 80.36306 -42.8371)
		(width 0.13335)
		(layer "In5.Cu")
		(net "D85_PCIE_A_REFCLK_P")
	)
	(segment
		(start 72.83196 -47.573946)
		(end 72.83196 -47.173896)
		(width 0.13335)
		(layer "In5.Cu")
		(net "D85_PCIE_A_REFCLK_P")
	)
	(segment
		(start 75.530202 -43.734736)
		(end 75.812904 -43.45178)
		(width 0.13335)
		(layer "In5.Cu")
		(net "D85_PCIE_A_REFCLK_P")
	)
	(segment
		(start 75.946 -43.053)
		(end 76.054458 -42.944796)
		(width 0.13335)
		(layer "In5.Cu")
		(net "D85_PCIE_A_REFCLK_P")
	)
	(segment
		(start 72.644 -46.797976)
		(end 72.644 -46.576488)
		(width 0.13335)
		(layer "In5.Cu")
		(net "D85_PCIE_A_REFCLK_P")
	)
	(segment
		(start 80.73898 -43.02506)
		(end 81.13903 -43.02506)
		(width 0.13335)
		(layer "In5.Cu")
		(net "D85_PCIE_A_REFCLK_P")
	)
	(segment
		(start 73.2028 -49.855374)
		(end 72.96785 -49.855374)
		(width 0.13335)
		(layer "In5.Cu")
		(net "D85_PCIE_A_REFCLK_P")
	)
	(segment
		(start 77.6351 -43.02506)
		(end 78.03515 -43.02506)
		(width 0.13335)
		(layer "In5.Cu")
		(net "D85_PCIE_A_REFCLK_P")
	)
	(segment
		(start 72.644 -48.349916)
		(end 72.644 -47.949866)
		(width 0.13335)
		(layer "In5.Cu")
		(net "D85_PCIE_A_REFCLK_P")
	)
	(segment
		(start 74.432668 -44.832016)
		(end 74.715624 -44.54906)
		(width 0.13335)
		(layer "In5.Cu")
		(net "D85_PCIE_A_REFCLK_P")
	)
	(segment
		(start 73.335388 -45.929296)
		(end 73.618344 -45.646594)
		(width 0.13335)
		(layer "In5.Cu")
		(net "D85_PCIE_A_REFCLK_P")
	)
	(segment
		(start 73.751186 -45.247814)
		(end 74.034142 -44.964858)
		(width 0.13335)
		(layer "In5.Cu")
		(net "D85_PCIE_A_REFCLK_P")
	)
	(segment
		(start 81.51495 -42.8371)
		(end 82.169 -42.8371)
		(width 0.13335)
		(layer "In5.Cu")
		(net "D85_PCIE_A_REFCLK_P")
	)
	(segment
		(start 76.315062 -42.8371)
		(end 77.25918 -42.8371)
		(width 0.13335)
		(layer "In5.Cu")
		(net "D85_PCIE_A_REFCLK_P")
	)
	(arc
		(start 72.83196 -48.725836)
		(mid 72.806805 -48.620926)
		(end 72.73798 -48.537876)
		(width 0.13335)
		(layer "In5.Cu")
		(net "D85_PCIE_A_REFCLK_P")
	)
	(arc
		(start 78.03515 -43.02506)
		(mid 78.14006 -42.999905)
		(end 78.22311 -42.93108)
		(width 0.13335)
		(layer "In5.Cu")
		(net "D85_PCIE_A_REFCLK_P")
	)
	(arc
		(start 72.73798 -48.537876)
		(mid 72.669244 -48.454782)
		(end 72.644 -48.349916)
		(width 0.13335)
		(layer "In5.Cu")
		(net "D85_PCIE_A_REFCLK_P")
	)
	(arc
		(start 73.684638 -45.447204)
		(mid 73.694815 -45.339804)
		(end 73.751186 -45.247814)
		(width 0.13335)
		(layer "In5.Cu")
		(net "D85_PCIE_A_REFCLK_P")
	)
	(arc
		(start 80.36306 -42.8371)
		(mid 80.46797 -42.862255)
		(end 80.55102 -42.93108)
		(width 0.13335)
		(layer "In5.Cu")
		(net "D85_PCIE_A_REFCLK_P")
	)
	(arc
		(start 81.13903 -43.02506)
		(mid 81.24394 -42.999905)
		(end 81.32699 -42.93108)
		(width 0.13335)
		(layer "In5.Cu")
		(net "D85_PCIE_A_REFCLK_P")
	)
	(arc
		(start 73.618344 -45.646594)
		(mid 73.674592 -45.55458)
		(end 73.684638 -45.447204)
		(width 0.13335)
		(layer "In5.Cu")
		(net "D85_PCIE_A_REFCLK_P")
	)
	(arc
		(start 82.169 -42.8371)
		(mid 82.358295 -42.874847)
		(end 82.518758 -42.982134)
		(width 0.13335)
		(layer "In5.Cu")
		(net "D85_PCIE_A_REFCLK_P")
	)
	(arc
		(start 72.73798 -49.313846)
		(mid 72.806716 -49.230752)
		(end 72.83196 -49.125886)
		(width 0.13335)
		(layer "In5.Cu")
		(net "D85_PCIE_A_REFCLK_P")
	)
	(arc
		(start 78.22311 -42.93108)
		(mid 78.306204 -42.862344)
		(end 78.41107 -42.8371)
		(width 0.13335)
		(layer "In5.Cu")
		(net "D85_PCIE_A_REFCLK_P")
	)
	(arc
		(start 72.73798 -46.985936)
		(mid 72.669244 -46.902842)
		(end 72.644 -46.797976)
		(width 0.13335)
		(layer "In5.Cu")
		(net "D85_PCIE_A_REFCLK_P")
	)
	(arc
		(start 76.054458 -42.944796)
		(mid 76.174067 -42.865065)
		(end 76.315062 -42.8371)
		(width 0.13335)
		(layer "In5.Cu")
		(net "D85_PCIE_A_REFCLK_P")
	)
	(arc
		(start 78.81112 -42.8371)
		(mid 78.91603 -42.862255)
		(end 78.99908 -42.93108)
		(width 0.13335)
		(layer "In5.Cu")
		(net "D85_PCIE_A_REFCLK_P")
	)
	(arc
		(start 72.96785 -49.855374)
		(mid 72.851986 -49.832327)
		(end 72.753728 -49.766728)
		(width 0.13335)
		(layer "In5.Cu")
		(net "D85_PCIE_A_REFCLK_P")
	)
	(arc
		(start 72.936608 -46.062392)
		(mid 73.028588 -46.005989)
		(end 73.135998 -45.995844)
		(width 0.13335)
		(layer "In5.Cu")
		(net "D85_PCIE_A_REFCLK_P")
	)
	(arc
		(start 77.25918 -42.8371)
		(mid 77.36409 -42.862255)
		(end 77.44714 -42.93108)
		(width 0.13335)
		(layer "In5.Cu")
		(net "D85_PCIE_A_REFCLK_P")
	)
	(arc
		(start 72.73798 -47.761906)
		(mid 72.806716 -47.678812)
		(end 72.83196 -47.573946)
		(width 0.13335)
		(layer "In5.Cu")
		(net "D85_PCIE_A_REFCLK_P")
	)
	(arc
		(start 74.715624 -44.54906)
		(mid 74.772027 -44.45708)
		(end 74.782172 -44.34967)
		(width 0.13335)
		(layer "In5.Cu")
		(net "D85_PCIE_A_REFCLK_P")
	)
	(arc
		(start 72.644 -46.576488)
		(mid 72.684734 -46.371796)
		(end 72.800718 -46.198282)
		(width 0.13335)
		(layer "In5.Cu")
		(net "D85_PCIE_A_REFCLK_P")
	)
	(arc
		(start 75.330812 -43.80103)
		(mid 75.438187 -43.790982)
		(end 75.530202 -43.734736)
		(width 0.13335)
		(layer "In5.Cu")
		(net "D85_PCIE_A_REFCLK_P")
	)
	(arc
		(start 79.77505 -42.93108)
		(mid 79.858144 -42.862344)
		(end 79.96301 -42.8371)
		(width 0.13335)
		(layer "In5.Cu")
		(net "D85_PCIE_A_REFCLK_P")
	)
	(arc
		(start 72.644 -47.949866)
		(mid 72.669155 -47.844956)
		(end 72.73798 -47.761906)
		(width 0.13335)
		(layer "In5.Cu")
		(net "D85_PCIE_A_REFCLK_P")
	)
	(arc
		(start 74.782172 -44.34967)
		(mid 74.7923 -44.242452)
		(end 74.848466 -44.150534)
		(width 0.13335)
		(layer "In5.Cu")
		(net "D85_PCIE_A_REFCLK_P")
	)
	(arc
		(start 78.99908 -42.93108)
		(mid 79.082174 -42.999816)
		(end 79.18704 -43.02506)
		(width 0.13335)
		(layer "In5.Cu")
		(net "D85_PCIE_A_REFCLK_P")
	)
	(arc
		(start 75.812904 -43.45178)
		(mid 75.869307 -43.3598)
		(end 75.879452 -43.25239)
		(width 0.13335)
		(layer "In5.Cu")
		(net "D85_PCIE_A_REFCLK_P")
	)
	(arc
		(start 75.131422 -43.867578)
		(mid 75.223402 -43.811175)
		(end 75.330812 -43.80103)
		(width 0.13335)
		(layer "In5.Cu")
		(net "D85_PCIE_A_REFCLK_P")
	)
	(arc
		(start 73.9902 -49.621694)
		(mid 73.613471 -49.795716)
		(end 73.2028 -49.855374)
		(width 0.13335)
		(layer "In5.Cu")
		(net "D85_PCIE_A_REFCLK_P")
	)
	(arc
		(start 74.233278 -44.898564)
		(mid 74.340678 -44.888387)
		(end 74.432668 -44.832016)
		(width 0.13335)
		(layer "In5.Cu")
		(net "D85_PCIE_A_REFCLK_P")
	)
	(arc
		(start 81.32699 -42.93108)
		(mid 81.410084 -42.862344)
		(end 81.51495 -42.8371)
		(width 0.13335)
		(layer "In5.Cu")
		(net "D85_PCIE_A_REFCLK_P")
	)
	(arc
		(start 75.879452 -43.25239)
		(mid 75.889629 -43.14499)
		(end 75.946 -43.053)
		(width 0.13335)
		(layer "In5.Cu")
		(net "D85_PCIE_A_REFCLK_P")
	)
	(arc
		(start 72.644 -49.501806)
		(mid 72.669155 -49.396896)
		(end 72.73798 -49.313846)
		(width 0.13335)
		(layer "In5.Cu")
		(net "D85_PCIE_A_REFCLK_P")
	)
	(arc
		(start 77.44714 -42.93108)
		(mid 77.530234 -42.999816)
		(end 77.6351 -43.02506)
		(width 0.13335)
		(layer "In5.Cu")
		(net "D85_PCIE_A_REFCLK_P")
	)
	(arc
		(start 73.135998 -45.995844)
		(mid 73.243398 -45.985667)
		(end 73.335388 -45.929296)
		(width 0.13335)
		(layer "In5.Cu")
		(net "D85_PCIE_A_REFCLK_P")
	)
	(arc
		(start 74.034142 -44.964858)
		(mid 74.126026 -44.90859)
		(end 74.233278 -44.898564)
		(width 0.13335)
		(layer "In5.Cu")
		(net "D85_PCIE_A_REFCLK_P")
	)
	(arc
		(start 72.753728 -49.766728)
		(mid 72.672513 -49.645181)
		(end 72.644 -49.501806)
		(width 0.13335)
		(layer "In5.Cu")
		(net "D85_PCIE_A_REFCLK_P")
	)
	(arc
		(start 79.58709 -43.02506)
		(mid 79.692 -42.999905)
		(end 79.77505 -42.93108)
		(width 0.13335)
		(layer "In5.Cu")
		(net "D85_PCIE_A_REFCLK_P")
	)
	(arc
		(start 72.83196 -47.173896)
		(mid 72.806805 -47.068986)
		(end 72.73798 -46.985936)
		(width 0.13335)
		(layer "In5.Cu")
		(net "D85_PCIE_A_REFCLK_P")
	)
	(arc
		(start 80.55102 -42.93108)
		(mid 80.634114 -42.999816)
		(end 80.73898 -43.02506)
		(width 0.13335)
		(layer "In5.Cu")
		(net "D85_PCIE_A_REFCLK_P")
	)
	(segment
		(start 73.533 -50.289968)
		(end 72.725026 -50.289968)
		(width 0.136652)
		(layer "F.Cu")
		(net "D85_PCIE_A_REFCLK_N")
	)
	(via
		(at 73.9902 -50.434494)
		(size 0.508)
		(drill 0.254)
		(layers "F.Cu" "B.Cu")
		(net "D85_PCIE_A_REFCLK_N")
	)
	(via
		(at 82.611976 -42.274998)
		(size 0.508)
		(drill 0.254)
		(layers "F.Cu" "B.Cu")
		(net "D85_PCIE_A_REFCLK_N")
	)
	(arc
		(start 73.9902 -50.434494)
		(mid 73.772747 -50.326973)
		(end 73.533 -50.289968)
		(width 0.136652)
		(layer "F.Cu")
		(net "D85_PCIE_A_REFCLK_N")
	)
	(segment
		(start 82.611976 -42.274998)
		(end 81.380076 -42.274998)
		(width 0.136652)
		(layer "B.Cu")
		(net "D85_PCIE_A_REFCLK_N")
	)
	(segment
		(start 75.716892 -42.823638)
		(end 75.825604 -42.71518)
		(width 0.13335)
		(layer "In5.Cu")
		(net "D85_PCIE_A_REFCLK_N")
	)
	(segment
		(start 72.32015 -49.501806)
		(end 72.32015 -46.576488)
		(width 0.13335)
		(layer "In5.Cu")
		(net "D85_PCIE_A_REFCLK_N")
	)
	(segment
		(start 73.025 -50.179224)
		(end 72.944736 -50.179224)
		(width 0.13335)
		(layer "In5.Cu")
		(net "D85_PCIE_A_REFCLK_N")
	)
	(segment
		(start 72.57161 -45.969174)
		(end 74.144124 -44.39666)
		(width 0.13335)
		(layer "In5.Cu")
		(net "D85_PCIE_A_REFCLK_N")
	)
	(segment
		(start 76.315062 -42.51325)
		(end 81.788 -42.51325)
		(width 0.13335)
		(layer "In5.Cu")
		(net "D85_PCIE_A_REFCLK_N")
	)
	(segment
		(start 72.540622 -50.011838)
		(end 72.52462 -49.995836)
		(width 0.13335)
		(layer "In5.Cu")
		(net "D85_PCIE_A_REFCLK_N")
	)
	(segment
		(start 74.144124 -44.39666)
		(end 75.716892 -42.823638)
		(width 0.13335)
		(layer "In5.Cu")
		(net "D85_PCIE_A_REFCLK_N")
	)
	(arc
		(start 72.52462 -49.995836)
		(mid 72.373252 -49.769158)
		(end 72.32015 -49.501806)
		(width 0.13335)
		(layer "In5.Cu")
		(net "D85_PCIE_A_REFCLK_N")
	)
	(arc
		(start 72.32015 -46.576488)
		(mid 72.385437 -46.247796)
		(end 72.57161 -45.969174)
		(width 0.13335)
		(layer "In5.Cu")
		(net "D85_PCIE_A_REFCLK_N")
	)
	(arc
		(start 73.9902 -50.434494)
		(mid 73.524191 -50.24413)
		(end 73.025 -50.179224)
		(width 0.13335)
		(layer "In5.Cu")
		(net "D85_PCIE_A_REFCLK_N")
	)
	(arc
		(start 72.944736 -50.179224)
		(mid 72.726032 -50.135721)
		(end 72.540622 -50.011838)
		(width 0.13335)
		(layer "In5.Cu")
		(net "D85_PCIE_A_REFCLK_N")
	)
	(arc
		(start 81.788 -42.51325)
		(mid 82.216867 -42.452495)
		(end 82.611976 -42.274998)
		(width 0.13335)
		(layer "In5.Cu")
		(net "D85_PCIE_A_REFCLK_N")
	)
	(arc
		(start 75.825604 -42.71518)
		(mid 76.050299 -42.565671)
		(end 76.315062 -42.51325)
		(width 0.13335)
		(layer "In5.Cu")
		(net "D85_PCIE_A_REFCLK_N")
	)
	(segment
		(start 73.746868 -22.58695)
		(end 73.8378 -22.58695)
		(width 0.136652)
		(layer "F.Cu")
		(net "D85_PCIE_B_REFCLK_N")
	)
	(segment
		(start 73.628504 -22.652736)
		(end 73.657206 -22.624034)
		(width 0.136652)
		(layer "F.Cu")
		(net "D85_PCIE_B_REFCLK_N")
	)
	(segment
		(start 72.725026 -22.68982)
		(end 73.538842 -22.68982)
		(width 0.136652)
		(layer "F.Cu")
		(net "D85_PCIE_B_REFCLK_N")
	)
	(via
		(at 74.93 -22.834346)
		(size 0.508)
		(drill 0.254)
		(layers "F.Cu" "B.Cu")
		(net "D85_PCIE_B_REFCLK_N")
	)
	(via
		(at 76.9112 -33.691322)
		(size 0.508)
		(drill 0.254)
		(layers "F.Cu" "B.Cu")
		(net "D85_PCIE_B_REFCLK_N")
	)
	(arc
		(start 73.538842 -22.68982)
		(mid 73.58736 -22.680187)
		(end 73.628504 -22.652736)
		(width 0.136652)
		(layer "F.Cu")
		(net "D85_PCIE_B_REFCLK_N")
	)
	(arc
		(start 73.657206 -22.624034)
		(mid 73.698357 -22.596601)
		(end 73.746868 -22.58695)
		(width 0.136652)
		(layer "F.Cu")
		(net "D85_PCIE_B_REFCLK_N")
	)
	(arc
		(start 73.8378 -22.58695)
		(mid 74.397735 -22.649571)
		(end 74.93 -22.834346)
		(width 0.136652)
		(layer "F.Cu")
		(net "D85_PCIE_B_REFCLK_N")
	)
	(segment
		(start 77.373988 -34.103056)
		(end 77.376528 -34.103056)
		(width 0.136652)
		(layer "B.Cu")
		(net "D85_PCIE_B_REFCLK_N")
	)
	(segment
		(start 77.987144 -33.850072)
		(end 78.769972 -33.850072)
		(width 0.136652)
		(layer "B.Cu")
		(net "D85_PCIE_B_REFCLK_N")
	)
	(arc
		(start 76.9112 -33.691322)
		(mid 77.064237 -33.985292)
		(end 77.373988 -34.103056)
		(width 0.136652)
		(layer "B.Cu")
		(net "D85_PCIE_B_REFCLK_N")
	)
	(arc
		(start 77.376528 -34.103056)
		(mid 77.541771 -34.070187)
		(end 77.681836 -33.976564)
		(width 0.136652)
		(layer "B.Cu")
		(net "D85_PCIE_B_REFCLK_N")
	)
	(arc
		(start 77.681836 -33.976564)
		(mid 77.821913 -33.882968)
		(end 77.987144 -33.850072)
		(width 0.136652)
		(layer "B.Cu")
		(net "D85_PCIE_B_REFCLK_N")
	)
	(segment
		(start 79.44104 -26.798524)
		(end 79.44104 -26.398474)
		(width 0.13335)
		(layer "In5.Cu")
		(net "D85_PCIE_B_REFCLK_N")
	)
	(segment
		(start 79.44104 -29.902404)
		(end 79.44104 -29.502354)
		(width 0.13335)
		(layer "In5.Cu")
		(net "D85_PCIE_B_REFCLK_N")
	)
	(segment
		(start 79.410306 -22.422866)
		(end 77.540358 -22.422866)
		(width 0.13335)
		(layer "In5.Cu")
		(net "D85_PCIE_B_REFCLK_N")
	)
	(segment
		(start 79.629 -22.918674)
		(end 79.629 -22.635718)
		(width 0.13335)
		(layer "In5.Cu")
		(net "D85_PCIE_B_REFCLK_N")
	)
	(segment
		(start 79.498698 -22.440646)
		(end 79.497174 -22.440138)
		(width 0.13335)
		(layer "In5.Cu")
		(net "D85_PCIE_B_REFCLK_N")
	)
	(segment
		(start 79.44104 -25.246584)
		(end 79.44104 -24.846534)
		(width 0.13335)
		(layer "In5.Cu")
		(net "D85_PCIE_B_REFCLK_N")
	)
	(segment
		(start 79.629 -27.574494)
		(end 79.629 -27.174444)
		(width 0.13335)
		(layer "In5.Cu")
		(net "D85_PCIE_B_REFCLK_N")
	)
	(segment
		(start 75.76185 -22.589998)
		(end 75.420474 -22.589998)
		(width 0.13335)
		(layer "In5.Cu")
		(net "D85_PCIE_B_REFCLK_N")
	)
	(segment
		(start 78.37297 -33.900364)
		(end 78.77302 -33.900364)
		(width 0.13335)
		(layer "In5.Cu")
		(net "D85_PCIE_B_REFCLK_N")
	)
	(segment
		(start 79.44104 -28.350464)
		(end 79.44104 -27.950414)
		(width 0.13335)
		(layer "In5.Cu")
		(net "D85_PCIE_B_REFCLK_N")
	)
	(segment
		(start 79.629 -24.470614)
		(end 79.629 -24.070564)
		(width 0.13335)
		(layer "In5.Cu")
		(net "D85_PCIE_B_REFCLK_N")
	)
	(segment
		(start 77.851 -34.088324)
		(end 77.99705 -34.088324)
		(width 0.13335)
		(layer "In5.Cu")
		(net "D85_PCIE_B_REFCLK_N")
	)
	(segment
		(start 77.164438 -22.610826)
		(end 76.764388 -22.610826)
		(width 0.13335)
		(layer "In5.Cu")
		(net "D85_PCIE_B_REFCLK_N")
	)
	(segment
		(start 79.44104 -31.454344)
		(end 79.44104 -31.054294)
		(width 0.13335)
		(layer "In5.Cu")
		(net "D85_PCIE_B_REFCLK_N")
	)
	(segment
		(start 79.629 -33.782254)
		(end 79.629 -33.382204)
		(width 0.13335)
		(layer "In5.Cu")
		(net "D85_PCIE_B_REFCLK_N")
	)
	(segment
		(start 79.629 -30.678374)
		(end 79.629 -30.278324)
		(width 0.13335)
		(layer "In5.Cu")
		(net "D85_PCIE_B_REFCLK_N")
	)
	(segment
		(start 79.629 -29.126434)
		(end 79.629 -28.726384)
		(width 0.13335)
		(layer "In5.Cu")
		(net "D85_PCIE_B_REFCLK_N")
	)
	(segment
		(start 76.186792 -22.461728)
		(end 75.960224 -22.551898)
		(width 0.13335)
		(layer "In5.Cu")
		(net "D85_PCIE_B_REFCLK_N")
	)
	(segment
		(start 79.629 -26.022554)
		(end 79.629 -25.622504)
		(width 0.13335)
		(layer "In5.Cu")
		(net "D85_PCIE_B_REFCLK_N")
	)
	(segment
		(start 79.14894 -34.088324)
		(end 79.32293 -34.088324)
		(width 0.13335)
		(layer "In5.Cu")
		(net "D85_PCIE_B_REFCLK_N")
	)
	(segment
		(start 79.44104 -33.006284)
		(end 79.44104 -32.606234)
		(width 0.13335)
		(layer "In5.Cu")
		(net "D85_PCIE_B_REFCLK_N")
	)
	(segment
		(start 75.000358 -22.763988)
		(end 74.93 -22.834346)
		(width 0.13335)
		(layer "In5.Cu")
		(net "D85_PCIE_B_REFCLK_N")
	)
	(segment
		(start 79.44104 -23.694644)
		(end 79.44104 -23.294594)
		(width 0.13335)
		(layer "In5.Cu")
		(net "D85_PCIE_B_REFCLK_N")
	)
	(segment
		(start 79.629 -32.230314)
		(end 79.629 -31.830264)
		(width 0.13335)
		(layer "In5.Cu")
		(net "D85_PCIE_B_REFCLK_N")
	)
	(arc
		(start 75.420474 -22.589998)
		(mid 75.193119 -22.635222)
		(end 75.000358 -22.763988)
		(width 0.13335)
		(layer "In5.Cu")
		(net "D85_PCIE_B_REFCLK_N")
	)
	(arc
		(start 77.99705 -34.088324)
		(mid 78.10196 -34.063169)
		(end 78.18501 -33.994344)
		(width 0.13335)
		(layer "In5.Cu")
		(net "D85_PCIE_B_REFCLK_N")
	)
	(arc
		(start 75.960224 -22.551898)
		(mid 75.862849 -22.580395)
		(end 75.76185 -22.589998)
		(width 0.13335)
		(layer "In5.Cu")
		(net "D85_PCIE_B_REFCLK_N")
	)
	(arc
		(start 79.629 -31.830264)
		(mid 79.603845 -31.725354)
		(end 79.53502 -31.642304)
		(width 0.13335)
		(layer "In5.Cu")
		(net "D85_PCIE_B_REFCLK_N")
	)
	(arc
		(start 79.53502 -30.090364)
		(mid 79.466284 -30.00727)
		(end 79.44104 -29.902404)
		(width 0.13335)
		(layer "In5.Cu")
		(net "D85_PCIE_B_REFCLK_N")
	)
	(arc
		(start 79.44104 -29.502354)
		(mid 79.466195 -29.397444)
		(end 79.53502 -29.314394)
		(width 0.13335)
		(layer "In5.Cu")
		(net "D85_PCIE_B_REFCLK_N")
	)
	(arc
		(start 79.53502 -26.986484)
		(mid 79.466284 -26.90339)
		(end 79.44104 -26.798524)
		(width 0.13335)
		(layer "In5.Cu")
		(net "D85_PCIE_B_REFCLK_N")
	)
	(arc
		(start 77.352398 -22.516846)
		(mid 77.269304 -22.585582)
		(end 77.164438 -22.610826)
		(width 0.13335)
		(layer "In5.Cu")
		(net "D85_PCIE_B_REFCLK_N")
	)
	(arc
		(start 79.44104 -27.950414)
		(mid 79.466195 -27.845504)
		(end 79.53502 -27.762454)
		(width 0.13335)
		(layer "In5.Cu")
		(net "D85_PCIE_B_REFCLK_N")
	)
	(arc
		(start 79.53502 -23.106634)
		(mid 79.603756 -23.02354)
		(end 79.629 -22.918674)
		(width 0.13335)
		(layer "In5.Cu")
		(net "D85_PCIE_B_REFCLK_N")
	)
	(arc
		(start 79.539338 -33.998662)
		(mid 79.605681 -33.899373)
		(end 79.629 -33.782254)
		(width 0.13335)
		(layer "In5.Cu")
		(net "D85_PCIE_B_REFCLK_N")
	)
	(arc
		(start 79.53502 -27.762454)
		(mid 79.603756 -27.67936)
		(end 79.629 -27.574494)
		(width 0.13335)
		(layer "In5.Cu")
		(net "D85_PCIE_B_REFCLK_N")
	)
	(arc
		(start 79.629 -28.726384)
		(mid 79.603845 -28.621474)
		(end 79.53502 -28.538424)
		(width 0.13335)
		(layer "In5.Cu")
		(net "D85_PCIE_B_REFCLK_N")
	)
	(arc
		(start 79.629 -33.382204)
		(mid 79.603845 -33.277294)
		(end 79.53502 -33.194244)
		(width 0.13335)
		(layer "In5.Cu")
		(net "D85_PCIE_B_REFCLK_N")
	)
	(arc
		(start 79.53502 -26.210514)
		(mid 79.603756 -26.12742)
		(end 79.629 -26.022554)
		(width 0.13335)
		(layer "In5.Cu")
		(net "D85_PCIE_B_REFCLK_N")
	)
	(arc
		(start 79.44104 -32.606234)
		(mid 79.466195 -32.501324)
		(end 79.53502 -32.418274)
		(width 0.13335)
		(layer "In5.Cu")
		(net "D85_PCIE_B_REFCLK_N")
	)
	(arc
		(start 77.540358 -22.422866)
		(mid 77.435448 -22.448021)
		(end 77.352398 -22.516846)
		(width 0.13335)
		(layer "In5.Cu")
		(net "D85_PCIE_B_REFCLK_N")
	)
	(arc
		(start 79.44104 -26.398474)
		(mid 79.466195 -26.293564)
		(end 79.53502 -26.210514)
		(width 0.13335)
		(layer "In5.Cu")
		(net "D85_PCIE_B_REFCLK_N")
	)
	(arc
		(start 79.53502 -29.314394)
		(mid 79.603756 -29.2313)
		(end 79.629 -29.126434)
		(width 0.13335)
		(layer "In5.Cu")
		(net "D85_PCIE_B_REFCLK_N")
	)
	(arc
		(start 79.32293 -34.088324)
		(mid 79.440058 -34.065026)
		(end 79.539338 -33.998662)
		(width 0.13335)
		(layer "In5.Cu")
		(net "D85_PCIE_B_REFCLK_N")
	)
	(arc
		(start 79.497174 -22.440138)
		(mid 79.454594 -22.427197)
		(end 79.410306 -22.422866)
		(width 0.13335)
		(layer "In5.Cu")
		(net "D85_PCIE_B_REFCLK_N")
	)
	(arc
		(start 79.53502 -30.866334)
		(mid 79.603756 -30.78324)
		(end 79.629 -30.678374)
		(width 0.13335)
		(layer "In5.Cu")
		(net "D85_PCIE_B_REFCLK_N")
	)
	(arc
		(start 78.77302 -33.900364)
		(mid 78.87793 -33.925519)
		(end 78.96098 -33.994344)
		(width 0.13335)
		(layer "In5.Cu")
		(net "D85_PCIE_B_REFCLK_N")
	)
	(arc
		(start 78.96098 -33.994344)
		(mid 79.044074 -34.06308)
		(end 79.14894 -34.088324)
		(width 0.13335)
		(layer "In5.Cu")
		(net "D85_PCIE_B_REFCLK_N")
	)
	(arc
		(start 79.44104 -24.846534)
		(mid 79.466195 -24.741624)
		(end 79.53502 -24.658574)
		(width 0.13335)
		(layer "In5.Cu")
		(net "D85_PCIE_B_REFCLK_N")
	)
	(arc
		(start 79.53502 -25.434544)
		(mid 79.466284 -25.35145)
		(end 79.44104 -25.246584)
		(width 0.13335)
		(layer "In5.Cu")
		(net "D85_PCIE_B_REFCLK_N")
	)
	(arc
		(start 76.576428 -22.516846)
		(mid 76.493334 -22.44811)
		(end 76.388468 -22.422866)
		(width 0.13335)
		(layer "In5.Cu")
		(net "D85_PCIE_B_REFCLK_N")
	)
	(arc
		(start 76.9112 -33.691322)
		(mid 77.340895 -33.984996)
		(end 77.851 -34.088324)
		(width 0.13335)
		(layer "In5.Cu")
		(net "D85_PCIE_B_REFCLK_N")
	)
	(arc
		(start 79.53502 -23.882604)
		(mid 79.466284 -23.79951)
		(end 79.44104 -23.694644)
		(width 0.13335)
		(layer "In5.Cu")
		(net "D85_PCIE_B_REFCLK_N")
	)
	(arc
		(start 79.629 -24.070564)
		(mid 79.603845 -23.965654)
		(end 79.53502 -23.882604)
		(width 0.13335)
		(layer "In5.Cu")
		(net "D85_PCIE_B_REFCLK_N")
	)
	(arc
		(start 79.53502 -24.658574)
		(mid 79.603756 -24.57548)
		(end 79.629 -24.470614)
		(width 0.13335)
		(layer "In5.Cu")
		(net "D85_PCIE_B_REFCLK_N")
	)
	(arc
		(start 79.629 -30.278324)
		(mid 79.603845 -30.173414)
		(end 79.53502 -30.090364)
		(width 0.13335)
		(layer "In5.Cu")
		(net "D85_PCIE_B_REFCLK_N")
	)
	(arc
		(start 78.18501 -33.994344)
		(mid 78.268104 -33.925608)
		(end 78.37297 -33.900364)
		(width 0.13335)
		(layer "In5.Cu")
		(net "D85_PCIE_B_REFCLK_N")
	)
	(arc
		(start 79.44104 -31.054294)
		(mid 79.466195 -30.949384)
		(end 79.53502 -30.866334)
		(width 0.13335)
		(layer "In5.Cu")
		(net "D85_PCIE_B_REFCLK_N")
	)
	(arc
		(start 76.764388 -22.610826)
		(mid 76.659478 -22.585671)
		(end 76.576428 -22.516846)
		(width 0.13335)
		(layer "In5.Cu")
		(net "D85_PCIE_B_REFCLK_N")
	)
	(arc
		(start 79.53502 -31.642304)
		(mid 79.466284 -31.55921)
		(end 79.44104 -31.454344)
		(width 0.13335)
		(layer "In5.Cu")
		(net "D85_PCIE_B_REFCLK_N")
	)
	(arc
		(start 79.629 -25.622504)
		(mid 79.603845 -25.517594)
		(end 79.53502 -25.434544)
		(width 0.13335)
		(layer "In5.Cu")
		(net "D85_PCIE_B_REFCLK_N")
	)
	(arc
		(start 79.53502 -32.418274)
		(mid 79.603756 -32.33518)
		(end 79.629 -32.230314)
		(width 0.13335)
		(layer "In5.Cu")
		(net "D85_PCIE_B_REFCLK_N")
	)
	(arc
		(start 79.53502 -28.538424)
		(mid 79.466284 -28.45533)
		(end 79.44104 -28.350464)
		(width 0.13335)
		(layer "In5.Cu")
		(net "D85_PCIE_B_REFCLK_N")
	)
	(arc
		(start 79.629 -27.174444)
		(mid 79.603845 -27.069534)
		(end 79.53502 -26.986484)
		(width 0.13335)
		(layer "In5.Cu")
		(net "D85_PCIE_B_REFCLK_N")
	)
	(arc
		(start 76.388468 -22.422866)
		(mid 76.285776 -22.432685)
		(end 76.186792 -22.461728)
		(width 0.13335)
		(layer "In5.Cu")
		(net "D85_PCIE_B_REFCLK_N")
	)
	(arc
		(start 79.53502 -33.194244)
		(mid 79.466284 -33.11115)
		(end 79.44104 -33.006284)
		(width 0.13335)
		(layer "In5.Cu")
		(net "D85_PCIE_B_REFCLK_N")
	)
	(arc
		(start 79.44104 -23.294594)
		(mid 79.466195 -23.189684)
		(end 79.53502 -23.106634)
		(width 0.13335)
		(layer "In5.Cu")
		(net "D85_PCIE_B_REFCLK_N")
	)
	(arc
		(start 79.629 -22.635718)
		(mid 79.59342 -22.51844)
		(end 79.498698 -22.440646)
		(width 0.13335)
		(layer "In5.Cu")
		(net "D85_PCIE_B_REFCLK_N")
	)
	(segment
		(start 73.621392 -22.227032)
		(end 73.650094 -22.255734)
		(width 0.136652)
		(layer "F.Cu")
		(net "D85_PCIE_B_REFCLK_P")
	)
	(segment
		(start 73.739756 -22.292818)
		(end 74.0156 -22.292818)
		(width 0.136652)
		(layer "F.Cu")
		(net "D85_PCIE_B_REFCLK_P")
	)
	(segment
		(start 72.725026 -22.189948)
		(end 73.53173 -22.189948)
		(width 0.136652)
		(layer "F.Cu")
		(net "D85_PCIE_B_REFCLK_P")
	)
	(via
		(at 76.9112 -34.808922)
		(size 0.508)
		(drill 0.254)
		(layers "F.Cu" "B.Cu")
		(net "D85_PCIE_B_REFCLK_P")
	)
	(via
		(at 74.93 -22.021546)
		(size 0.508)
		(drill 0.254)
		(layers "F.Cu" "B.Cu")
		(net "D85_PCIE_B_REFCLK_P")
	)
	(arc
		(start 73.53173 -22.189948)
		(mid 73.580248 -22.199581)
		(end 73.621392 -22.227032)
		(width 0.136652)
		(layer "F.Cu")
		(net "D85_PCIE_B_REFCLK_P")
	)
	(arc
		(start 73.650094 -22.255734)
		(mid 73.691245 -22.283167)
		(end 73.739756 -22.292818)
		(width 0.136652)
		(layer "F.Cu")
		(net "D85_PCIE_B_REFCLK_P")
	)
	(arc
		(start 74.0156 -22.292818)
		(mid 74.492493 -22.223566)
		(end 74.93 -22.021546)
		(width 0.136652)
		(layer "F.Cu")
		(net "D85_PCIE_B_REFCLK_P")
	)
	(segment
		(start 77.373988 -34.397188)
		(end 77.398372 -34.397188)
		(width 0.136652)
		(layer "B.Cu")
		(net "D85_PCIE_B_REFCLK_P")
	)
	(segment
		(start 78.008988 -34.650172)
		(end 78.769972 -34.650172)
		(width 0.136652)
		(layer "B.Cu")
		(net "D85_PCIE_B_REFCLK_P")
	)
	(arc
		(start 77.70368 -34.52368)
		(mid 77.843757 -34.617276)
		(end 78.008988 -34.650172)
		(width 0.136652)
		(layer "B.Cu")
		(net "D85_PCIE_B_REFCLK_P")
	)
	(arc
		(start 76.9112 -34.808922)
		(mid 77.064237 -34.514952)
		(end 77.373988 -34.397188)
		(width 0.136652)
		(layer "B.Cu")
		(net "D85_PCIE_B_REFCLK_P")
	)
	(arc
		(start 77.398372 -34.397188)
		(mid 77.563615 -34.430057)
		(end 77.70368 -34.52368)
		(width 0.136652)
		(layer "B.Cu")
		(net "D85_PCIE_B_REFCLK_P")
	)
	(segment
		(start 79.410052 -22.099016)
		(end 76.388214 -22.099016)
		(width 0.13335)
		(layer "In5.Cu")
		(net "D85_PCIE_B_REFCLK_P")
	)
	(segment
		(start 79.95285 -33.782254)
		(end 79.95285 -22.635718)
		(width 0.13335)
		(layer "In5.Cu")
		(net "D85_PCIE_B_REFCLK_P")
	)
	(segment
		(start 75.761596 -22.266148)
		(end 75.433682 -22.266148)
		(width 0.13335)
		(layer "In5.Cu")
		(net "D85_PCIE_B_REFCLK_P")
	)
	(segment
		(start 76.066904 -22.160738)
		(end 75.840336 -22.250908)
		(width 0.13335)
		(layer "In5.Cu")
		(net "D85_PCIE_B_REFCLK_P")
	)
	(segment
		(start 77.6224 -34.412174)
		(end 79.32293 -34.412174)
		(width 0.13335)
		(layer "In5.Cu")
		(net "D85_PCIE_B_REFCLK_P")
	)
	(segment
		(start 79.609696 -22.1361)
		(end 79.608172 -22.135592)
		(width 0.13335)
		(layer "In5.Cu")
		(net "D85_PCIE_B_REFCLK_P")
	)
	(segment
		(start 74.991468 -22.083014)
		(end 74.93 -22.021546)
		(width 0.13335)
		(layer "In5.Cu")
		(net "D85_PCIE_B_REFCLK_P")
	)
	(arc
		(start 79.768446 -34.22777)
		(mid 79.904942 -34.02335)
		(end 79.95285 -33.782254)
		(width 0.13335)
		(layer "In5.Cu")
		(net "D85_PCIE_B_REFCLK_P")
	)
	(arc
		(start 75.840336 -22.250908)
		(mid 75.801692 -22.262279)
		(end 75.761596 -22.266148)
		(width 0.13335)
		(layer "In5.Cu")
		(net "D85_PCIE_B_REFCLK_P")
	)
	(arc
		(start 76.9112 -34.808922)
		(mid 77.215222 -34.518103)
		(end 77.6224 -34.412174)
		(width 0.13335)
		(layer "In5.Cu")
		(net "D85_PCIE_B_REFCLK_P")
	)
	(arc
		(start 76.388214 -22.099016)
		(mid 76.224627 -22.114611)
		(end 76.066904 -22.160738)
		(width 0.13335)
		(layer "In5.Cu")
		(net "D85_PCIE_B_REFCLK_P")
	)
	(arc
		(start 79.95285 -22.635718)
		(mid 79.858789 -22.332682)
		(end 79.609696 -22.1361)
		(width 0.13335)
		(layer "In5.Cu")
		(net "D85_PCIE_B_REFCLK_P")
	)
	(arc
		(start 75.433682 -22.266148)
		(mid 75.194372 -22.218546)
		(end 74.991468 -22.083014)
		(width 0.13335)
		(layer "In5.Cu")
		(net "D85_PCIE_B_REFCLK_P")
	)
	(arc
		(start 79.32293 -34.412174)
		(mid 79.564044 -34.364307)
		(end 79.768446 -34.22777)
		(width 0.13335)
		(layer "In5.Cu")
		(net "D85_PCIE_B_REFCLK_P")
	)
	(arc
		(start 79.608172 -22.135592)
		(mid 79.510801 -22.108152)
		(end 79.410052 -22.099016)
		(width 0.13335)
		(layer "In5.Cu")
		(net "D85_PCIE_B_REFCLK_P")
	)
	(segment
		(start 14.2875 -82.598006)
		(end 13.335 -82.598006)
		(width 0.508)
		(layer "F.Cu")
		(net "GND")
	)
	(segment
		(start 29.739844 -75.18019)
		(end 29.972 -75.412346)
		(width 0.3048)
		(layer "F.Cu")
		(net "GND")
	)
	(segment
		(start 72.725026 -61.289946)
		(end 74.041 -61.289946)
		(width 0.3048)
		(layer "F.Cu")
		(net "GND")
	)
	(segment
		(start 72.725026 -53.790088)
		(end 73.835006 -53.790088)
		(width 0.3048)
		(layer "F.Cu")
		(net "GND")
	)
	(segment
		(start 41.91 -78.2955)
		(end 41.91 -77.264006)
		(width 0.508)
		(layer "F.Cu")
		(net "GND")
	)
	(segment
		(start 72.725026 -30.689804)
		(end 71.162926 -30.689804)
		(width 0.3048)
		(layer "F.Cu")
		(net "GND")
	)
	(segment
		(start 17.16151 -78.635606)
		(end 16.383 -78.635606)
		(width 0.3048)
		(layer "F.Cu")
		(net "GND")
	)
	(segment
		(start 70.866 -41.2115)
		(end 71.501 -40.5765)
		(width 0.508)
		(layer "F.Cu")
		(net "GND")
	)
	(segment
		(start 27.813 -71.9455)
		(end 27.517598 -71.9455)
		(width 0.508)
		(layer "F.Cu")
		(net "GND")
	)
	(segment
		(start 72.725026 -50.790094)
		(end 69.469 -50.790094)
		(width 0.3048)
		(layer "F.Cu")
		(net "GND")
	)
	(segment
		(start 72.725026 -23.189946)
		(end 74.0537 -23.189946)
		(width 0.3048)
		(layer "F.Cu")
		(net "GND")
	)
	(segment
		(start 74.823066 -29.972)
		(end 74.041 -29.189934)
		(width 0.508)
		(layer "F.Cu")
		(net "GND")
	)
	(segment
		(start 74.8665 -62.23)
		(end 74.8665 -62.115446)
		(width 0.508)
		(layer "F.Cu")
		(net "GND")
	)
	(segment
		(start 31.24708 -80.315308)
		(end 31.24708 -80.25892)
		(width 0.3556)
		(layer "F.Cu")
		(net "GND")
	)
	(segment
		(start 68.64477 -87.808816)
		(end 73.001378 -87.808816)
		(width 0.508)
		(layer "F.Cu")
		(net "GND")
	)
	(segment
		(start 75.9206 -32.7914)
		(end 75.184 -33.528)
		(width 0.508)
		(layer "F.Cu")
		(net "GND")
	)
	(segment
		(start 31.15945 -81.302606)
		(end 31.15945 -80.402938)
		(width 0.3556)
		(layer "F.Cu")
		(net "GND")
	)
	(segment
		(start 76.34224 -41.2115)
		(end 76.34224 -40.37076)
		(width 0.4064)
		(layer "F.Cu")
		(net "GND")
	)
	(segment
		(start 72.725026 -33.689798)
		(end 71.162926 -33.689798)
		(width 0.3048)
		(layer "F.Cu")
		(net "GND")
	)
	(segment
		(start 76.708 -77.799692)
		(end 76.708 -78.867)
		(width 0.508)
		(layer "F.Cu")
		(net "GND")
	)
	(segment
		(start 72.725026 -29.189934)
		(end 74.041 -29.189934)
		(width 0.3048)
		(layer "F.Cu")
		(net "GND")
	)
	(segment
		(start 60.201302 -4.498848)
		(end 64.55791 -4.498848)
		(width 0.508)
		(layer "F.Cu")
		(net "GND")
	)
	(segment
		(start 70.83044 -41.2115)
		(end 70.866 -41.2115)
		(width 0.508)
		(layer "F.Cu")
		(net "GND")
	)
	(segment
		(start 72.725026 -45.289978)
		(end 71.42099 -45.289978)
		(width 0.3048)
		(layer "F.Cu")
		(net "GND")
	)
	(segment
		(start 60.478162 -37.5285)
		(end 60.14847 -37.198808)
		(width 0.508)
		(layer "F.Cu")
		(net "GND")
	)
	(segment
		(start 73.001378 -87.808816)
		(end 77.357986 -87.808816)
		(width 0.508)
		(layer "F.Cu")
		(net "GND")
	)
	(segment
		(start 26.34361 -78.07452)
		(end 26.34361 -78.73111)
		(width 0.3048)
		(layer "F.Cu")
		(net "GND")
	)
	(segment
		(start 71.12 -44.790106)
		(end 72.725026 -44.790106)
		(width 0.3048)
		(layer "F.Cu")
		(net "GND")
	)
	(segment
		(start 72.725026 -32.189928)
		(end 71.162926 -32.189928)
		(width 0.3048)
		(layer "F.Cu")
		(net "GND")
	)
	(segment
		(start 73.7489 -26.18994)
		(end 74.041 -25.89784)
		(width 0.3048)
		(layer "F.Cu")
		(net "GND")
	)
	(segment
		(start 25.527 -86.090506)
		(end 25.527 -85.265006)
		(width 0.508)
		(layer "F.Cu")
		(net "GND")
	)
	(segment
		(start 72.725026 -58.289952)
		(end 74.041 -58.289952)
		(width 0.3048)
		(layer "F.Cu")
		(net "GND")
	)
	(segment
		(start 47.195994 -76.6064)
		(end 47.195994 -77.2668)
		(width 0.508)
		(layer "F.Cu")
		(net "GND")
	)
	(segment
		(start 72.725026 -35.189922)
		(end 71.162926 -35.189922)
		(width 0.3048)
		(layer "F.Cu")
		(net "GND")
	)
	(segment
		(start 72.725026 -45.790104)
		(end 71.12 -45.790104)
		(width 0.3048)
		(layer "F.Cu")
		(net "GND")
	)
	(segment
		(start 71.950072 -43.690032)
		(end 69.977 -43.690032)
		(width 0.508)
		(layer "F.Cu")
		(net "GND")
	)
	(segment
		(start 73.841864 -55.289958)
		(end 74.041 -55.489094)
		(width 0.3048)
		(layer "F.Cu")
		(net "GND")
	)
	(segment
		(start 26.34361 -78.73111)
		(end 26.3525 -78.74)
		(width 0.3048)
		(layer "F.Cu")
		(net "GND")
	)
	(segment
		(start 6.501384 -80.308704)
		(end 10.857992 -80.308704)
		(width 0.508)
		(layer "F.Cu")
		(net "GND")
	)
	(segment
		(start 26.15819 -77.8891)
		(end 26.34361 -78.07452)
		(width 0.3048)
		(layer "F.Cu")
		(net "GND")
	)
	(segment
		(start 60.201302 -4.498848)
		(end 60.201302 -8.855456)
		(width 0.508)
		(layer "F.Cu")
		(net "GND")
	)
	(segment
		(start 31.15945 -80.402938)
		(end 31.24708 -80.315308)
		(width 0.3556)
		(layer "F.Cu")
		(net "GND")
	)
	(segment
		(start 76.327 -32.7914)
		(end 75.9206 -32.7914)
		(width 0.508)
		(layer "F.Cu")
		(net "GND")
	)
	(segment
		(start 63.33236 -41.23436)
		(end 62.63386 -41.23436)
		(width 0.3556)
		(layer "F.Cu")
		(net "GND")
	)
	(segment
		(start 63.246 -37.5285)
		(end 60.478162 -37.5285)
		(width 0.508)
		(layer "F.Cu")
		(net "GND")
	)
	(segment
		(start 72.725026 -24.689816)
		(end 74.041 -24.689816)
		(width 0.3048)
		(layer "F.Cu")
		(net "GND")
	)
	(segment
		(start 26.15819 -76.9874)
		(end 26.15819 -77.8891)
		(width 0.3048)
		(layer "F.Cu")
		(net "GND")
	)
	(segment
		(start 28.9306 -75.18019)
		(end 29.739844 -75.18019)
		(width 0.3048)
		(layer "F.Cu")
		(net "GND")
	)
	(segment
		(start 2.144776 -80.308704)
		(end 6.501384 -80.308704)
		(width 0.508)
		(layer "F.Cu")
		(net "GND")
	)
	(segment
		(start 72.725026 -26.18994)
		(end 73.7489 -26.18994)
		(width 0.3048)
		(layer "F.Cu")
		(net "GND")
	)
	(segment
		(start 26.162 -71.3105)
		(end 26.162 -70.485)
		(width 0.508)
		(layer "F.Cu")
		(net "GND")
	)
	(segment
		(start 74.8665 -62.115446)
		(end 74.041 -61.289946)
		(width 0.508)
		(layer "F.Cu")
		(net "GND")
	)
	(segment
		(start 72.725026 -59.790076)
		(end 74.041 -59.790076)
		(width 0.3048)
		(layer "F.Cu")
		(net "GND")
	)
	(segment
		(start 73.80097 -27.68981)
		(end 74.041 -27.92984)
		(width 0.3048)
		(layer "F.Cu")
		(net "GND")
	)
	(segment
		(start 71.501 -40.5765)
		(end 73.66 -40.5765)
		(width 0.508)
		(layer "F.Cu")
		(net "GND")
	)
	(segment
		(start 55.844694 -4.498848)
		(end 60.201302 -4.498848)
		(width 0.508)
		(layer "F.Cu")
		(net "GND")
	)
	(segment
		(start 14.7828 -84.122006)
		(end 13.335 -84.122006)
		(width 0.508)
		(layer "F.Cu")
		(net "GND")
	)
	(segment
		(start 72.725026 -56.790082)
		(end 74.041 -56.790082)
		(width 0.3048)
		(layer "F.Cu")
		(net "GND")
	)
	(segment
		(start 30.731206 -76.454)
		(end 30.988 -76.454)
		(width 0.3048)
		(layer "F.Cu")
		(net "GND")
	)
	(segment
		(start 76.708 -78.867)
		(end 76.708 -79.934308)
		(width 0.508)
		(layer "F.Cu")
		(net "GND")
	)
	(segment
		(start 71.950072 -36.789868)
		(end 70.045072 -36.789868)
		(width 0.508)
		(layer "F.Cu")
		(net "GND")
	)
	(segment
		(start 73.001378 -83.452208)
		(end 73.001378 -87.808816)
		(width 0.508)
		(layer "F.Cu")
		(net "GND")
	)
	(segment
		(start 26.3525 -78.74)
		(end 26.3525 -79.5528)
		(width 0.508)
		(layer "F.Cu")
		(net "GND")
	)
	(segment
		(start 16.0655 -74.724006)
		(end 15.113 -74.724006)
		(width 0.508)
		(layer "F.Cu")
		(net "GND")
	)
	(segment
		(start 75.438 -29.972)
		(end 74.823066 -29.972)
		(width 0.508)
		(layer "F.Cu")
		(net "GND")
	)
	(segment
		(start 26.882598 -71.3105)
		(end 26.162 -71.3105)
		(width 0.508)
		(layer "F.Cu")
		(net "GND")
	)
	(segment
		(start 6.501384 -80.308704)
		(end 6.501384 -84.665312)
		(width 0.508)
		(layer "F.Cu")
		(net "GND")
	)
	(segment
		(start 72.725026 -27.68981)
		(end 73.80097 -27.68981)
		(width 0.3048)
		(layer "F.Cu")
		(net "GND")
	)
	(segment
		(start 72.725026 -18.189956)
		(end 71.12 -18.189956)
		(width 0.3048)
		(layer "F.Cu")
		(net "GND")
	)
	(segment
		(start 72.725026 -55.289958)
		(end 73.841864 -55.289958)
		(width 0.3048)
		(layer "F.Cu")
		(net "GND")
	)
	(segment
		(start 72.725026 -52.289964)
		(end 74.041 -52.289964)
		(width 0.3048)
		(layer "F.Cu")
		(net "GND")
	)
	(segment
		(start 63.246 -65.0875)
		(end 63.246 -66.04)
		(width 0.508)
		(layer "F.Cu")
		(net "GND")
	)
	(segment
		(start 71.162926 -62.79007)
		(end 72.725026 -62.79007)
		(width 0.3048)
		(layer "F.Cu")
		(net "GND")
	)
	(segment
		(start 63.881 -41.783)
		(end 63.33236 -41.23436)
		(width 0.3556)
		(layer "F.Cu")
		(net "GND")
	)
	(segment
		(start 76.34224 -40.37076)
		(end 76.708 -40.005)
		(width 0.4064)
		(layer "F.Cu")
		(net "GND")
	)
	(segment
		(start 6.501384 -75.952096)
		(end 6.501384 -80.308704)
		(width 0.508)
		(layer "F.Cu")
		(net "GND")
	)
	(segment
		(start 27.517598 -71.9455)
		(end 26.882598 -71.3105)
		(width 0.508)
		(layer "F.Cu")
		(net "GND")
	)
	(segment
		(start 16.002 -76.184506)
		(end 15.113 -76.184506)
		(width 0.508)
		(layer "F.Cu")
		(net "GND")
	)
	(segment
		(start 73.835006 -53.790088)
		(end 74.041 -53.584094)
		(width 0.3048)
		(layer "F.Cu")
		(net "GND")
	)
	(segment
		(start 31.24708 -80.25892)
		(end 31.496 -80.01)
		(width 0.3556)
		(layer "F.Cu")
		(net "GND")
	)
	(segment
		(start 41.91 -77.264006)
		(end 41.861994 -77.216)
		(width 0.508)
		(layer "F.Cu")
		(net "GND")
	)
	(segment
		(start 75.640692 -78.867)
		(end 76.708 -78.867)
		(width 0.508)
		(layer "F.Cu")
		(net "GND")
	)
	(segment
		(start 29.972 -75.694794)
		(end 30.731206 -76.454)
		(width 0.3048)
		(layer "F.Cu")
		(net "GND")
	)
	(segment
		(start 72.725026 -49.28997)
		(end 69.469 -49.28997)
		(width 0.3048)
		(layer "F.Cu")
		(net "GND")
	)
	(segment
		(start 76.708 -78.867)
		(end 77.775308 -78.867)
		(width 0.508)
		(layer "F.Cu")
		(net "GND")
	)
	(segment
		(start 75.184 -33.528)
		(end 75.184 -33.5915)
		(width 0.508)
		(layer "F.Cu")
		(net "GND")
	)
	(segment
		(start 29.972 -75.412346)
		(end 29.972 -75.694794)
		(width 0.3048)
		(layer "F.Cu")
		(net "GND")
	)
	(segment
		(start 72.725026 -21.689822)
		(end 74.041 -21.689822)
		(width 0.3048)
		(layer "F.Cu")
		(net "GND")
	)
	(via
		(at 22.606 -72.946006)
		(size 0.5588)
		(drill 0.3048)
		(layers "F.Cu" "B.Cu")
		(net "GND")
	)
	(via
		(at 68.961 -76.708)
		(size 0.5588)
		(drill 0.3048)
		(layers "F.Cu" "B.Cu")
		(net "GND")
	)
	(via
		(at 70.83044 -41.2115)
		(size 0.508)
		(drill 0.254)
		(layers "F.Cu" "B.Cu")
		(net "GND")
	)
	(via
		(at 52.07 -91.44)
		(size 0.5588)
		(drill 0.3048)
		(layers "F.Cu" "B.Cu")
		(net "GND")
	)
	(via
		(at 48.211994 -78.867)
		(size 0.5588)
		(drill 0.3048)
		(layers "F.Cu" "B.Cu")
		(net "GND")
	)
	(via
		(at 74.041 -55.489094)
		(size 0.5588)
		(drill 0.3048)
		(layers "F.Cu" "B.Cu")
		(net "GND")
	)
	(via
		(at 71.12 -45.790104)
		(size 0.5588)
		(drill 0.3048)
		(layers "F.Cu" "B.Cu")
		(net "GND")
	)
	(via
		(at 80.01 -5.08)
		(size 0.5588)
		(drill 0.3048)
		(layers "F.Cu" "B.Cu")
		(net "GND")
	)
	(via
		(at 10.16 -68.58)
		(size 0.5588)
		(drill 0.3048)
		(layers "F.Cu" "B.Cu")
		(net "GND")
	)
	(via
		(at 82.611976 -23.874984)
		(size 0.508)
		(drill 0.254)
		(layers "F.Cu" "B.Cu")
		(net "GND")
	)
	(via
		(at 15.113 -76.184506)
		(size 0.5588)
		(drill 0.3048)
		(layers "F.Cu" "B.Cu")
		(net "GND")
	)
	(via
		(at 65.151 -86.36)
		(size 0.5588)
		(drill 0.3048)
		(layers "F.Cu" "B.Cu")
		(net "GND")
	)
	(via
		(at 26.162 -70.485)
		(size 0.508)
		(drill 0.254)
		(layers "F.Cu" "B.Cu")
		(net "GND")
	)
	(via
		(at 80.01 -10.16)
		(size 0.5588)
		(drill 0.3048)
		(layers "F.Cu" "B.Cu")
		(net "GND")
	)
	(via
		(at 75.057 -25.4)
		(size 0.5588)
		(drill 0.3048)
		(layers "F.Cu" "B.Cu")
		(net "GND")
	)
	(via
		(at 46.179994 -78.867)
		(size 0.5588)
		(drill 0.3048)
		(layers "F.Cu" "B.Cu")
		(net "GND")
	)
	(via
		(at 58.42 -44.577)
		(size 0.5588)
		(drill 0.3048)
		(layers "F.Cu" "B.Cu")
		(net "GND")
	)
	(via
		(at 58.42 -45.593)
		(size 0.5588)
		(drill 0.3048)
		(layers "F.Cu" "B.Cu")
		(net "GND")
	)
	(via
		(at 68.58 -1.27)
		(size 0.5588)
		(drill 0.3048)
		(layers "F.Cu" "B.Cu")
		(net "GND")
	)
	(via
		(at 68.961 -74.676)
		(size 0.5588)
		(drill 0.3048)
		(layers "F.Cu" "B.Cu")
		(net "GND")
	)
	(via
		(at 46.179994 -79.883)
		(size 0.5588)
		(drill 0.3048)
		(layers "F.Cu" "B.Cu")
		(net "GND")
	)
	(via
		(at 10.16 -72.39)
		(size 0.5588)
		(drill 0.3048)
		(layers "F.Cu" "B.Cu")
		(net "GND")
	)
	(via
		(at 76.0222 -33.691322)
		(size 0.508)
		(drill 0.254)
		(layers "F.Cu" "B.Cu")
		(net "GND")
	)
	(via
		(at 22.606 -74.978006)
		(size 0.5588)
		(drill 0.3048)
		(layers "F.Cu" "B.Cu")
		(net "GND")
	)
	(via
		(at 87.63 -1.27)
		(size 0.5588)
		(drill 0.3048)
		(layers "F.Cu" "B.Cu")
		(net "GND")
	)
	(via
		(at 58.42 -19.05)
		(size 0.5588)
		(drill 0.3048)
		(layers "F.Cu" "B.Cu")
		(net "GND")
	)
	(via
		(at 71.162926 -35.189922)
		(size 0.5588)
		(drill 0.3048)
		(layers "F.Cu" "B.Cu")
		(net "GND")
	)
	(via
		(at 37.211 -77.089)
		(size 0.5588)
		(drill 0.3048)
		(layers "F.Cu" "B.Cu")
		(net "GND")
	)
	(via
		(at 71.12 -17.189958)
		(size 0.5588)
		(drill 0.3048)
		(layers "F.Cu" "B.Cu")
		(net "GND")
	)
	(via
		(at 74.93 -1.27)
		(size 0.5588)
		(drill 0.3048)
		(layers "F.Cu" "B.Cu")
		(net "GND")
	)
	(via
		(at 78.74 -60.96)
		(size 0.5588)
		(drill 0.3048)
		(layers "F.Cu" "B.Cu")
		(net "GND")
	)
	(via
		(at 24.5745 -79.5655)
		(size 0.508)
		(drill 0.254)
		(layers "F.Cu" "B.Cu")
		(net "GND")
	)
	(via
		(at 68.4911 -53.584094)
		(size 0.508)
		(drill 0.254)
		(layers "F.Cu" "B.Cu")
		(net "GND")
	)
	(via
		(at 57.15 -41.7195)
		(size 0.508)
		(drill 0.254)
		(layers "F.Cu" "B.Cu")
		(net "GND")
	)
	(via
		(at 41.099994 -86.741)
		(size 0.5588)
		(drill 0.3048)
		(layers "F.Cu" "B.Cu")
		(net "GND")
	)
	(via
		(at 82.611976 -21.475192)
		(size 0.508)
		(drill 0.254)
		(layers "F.Cu" "B.Cu")
		(net "GND")
	)
	(via
		(at 40.083994 -86.741)
		(size 0.5588)
		(drill 0.3048)
		(layers "F.Cu" "B.Cu")
		(net "GND")
	)
	(via
		(at 67.31 -68.58)
		(size 0.5588)
		(drill 0.3048)
		(layers "F.Cu" "B.Cu")
		(net "GND")
	)
	(via
		(at 29.21 -91.44)
		(size 0.5588)
		(drill 0.3048)
		(layers "F.Cu" "B.Cu")
		(net "GND")
	)
	(via
		(at 2.54 -83.82)
		(size 0.5588)
		(drill 0.3048)
		(layers "F.Cu" "B.Cu")
		(net "GND")
	)
	(via
		(at 68.9991 -55.466488)
		(size 0.508)
		(drill 0.254)
		(layers "F.Cu" "B.Cu")
		(net "GND")
	)
	(via
		(at 74.93 -68.58)
		(size 0.5588)
		(drill 0.3048)
		(layers "F.Cu" "B.Cu")
		(net "GND")
	)
	(via
		(at 57.15 -27.94)
		(size 0.5588)
		(drill 0.3048)
		(layers "F.Cu" "B.Cu")
		(net "GND")
	)
	(via
		(at 80.391 -63.373)
		(size 0.7112)
		(drill 0.3556)
		(layers "F.Cu" "B.Cu")
		(net "GND")
	)
	(via
		(at 2.54 -91.44)
		(size 0.5588)
		(drill 0.3048)
		(layers "F.Cu" "B.Cu")
		(net "GND")
	)
	(via
		(at 68.4911 -25.983946)
		(size 0.508)
		(drill 0.254)
		(layers "F.Cu" "B.Cu")
		(net "GND")
	)
	(via
		(at 57.15 -40.7035)
		(size 0.508)
		(drill 0.254)
		(layers "F.Cu" "B.Cu")
		(net "GND")
	)
	(via
		(at 77.343 -23.368)
		(size 0.5588)
		(drill 0.3048)
		(layers "F.Cu" "B.Cu")
		(net "GND")
	)
	(via
		(at 59.69 -91.44)
		(size 0.5588)
		(drill 0.3048)
		(layers "F.Cu" "B.Cu")
		(net "GND")
	)
	(via
		(at 86.36 -83.82)
		(size 0.5588)
		(drill 0.3048)
		(layers "F.Cu" "B.Cu")
		(net "GND")
	)
	(via
		(at 35.052 -86.741)
		(size 0.5588)
		(drill 0.3048)
		(layers "F.Cu" "B.Cu")
		(net "GND")
	)
	(via
		(at 31.496 -80.01)
		(size 0.508)
		(drill 0.254)
		(layers "F.Cu" "B.Cu")
		(net "GND")
	)
	(via
		(at 74.041 -24.689816)
		(size 0.5588)
		(drill 0.3048)
		(layers "F.Cu" "B.Cu")
		(net "GND")
	)
	(via
		(at 37.035994 -86.741)
		(size 0.5588)
		(drill 0.3048)
		(layers "F.Cu" "B.Cu")
		(net "GND")
	)
	(via
		(at 71.12 -76.2)
		(size 0.5588)
		(drill 0.3048)
		(layers "F.Cu" "B.Cu")
		(net "GND")
	)
	(via
		(at 48.26 -91.44)
		(size 0.5588)
		(drill 0.3048)
		(layers "F.Cu" "B.Cu")
		(net "GND")
	)
	(via
		(at 37.211 -78.105)
		(size 0.5588)
		(drill 0.3048)
		(layers "F.Cu" "B.Cu")
		(net "GND")
	)
	(via
		(at 69.4944 -61.0235)
		(size 0.508)
		(drill 0.254)
		(layers "F.Cu" "B.Cu")
		(net "GND")
	)
	(via
		(at 78.74 -64.77)
		(size 0.5588)
		(drill 0.3048)
		(layers "F.Cu" "B.Cu")
		(net "GND")
	)
	(via
		(at 34.29 -74.422)
		(size 0.7112)
		(drill 0.3556)
		(layers "F.Cu" "B.Cu")
		(net "GND")
	)
	(via
		(at 31.0134 -71.3105)
		(size 0.508)
		(drill 0.254)
		(layers "F.Cu" "B.Cu")
		(net "GND")
	)
	(via
		(at 10.16 -76.2)
		(size 0.5588)
		(drill 0.3048)
		(layers "F.Cu" "B.Cu")
		(net "GND")
	)
	(via
		(at 38.227 -77.089)
		(size 0.5588)
		(drill 0.3048)
		(layers "F.Cu" "B.Cu")
		(net "GND")
	)
	(via
		(at 70.231 -50.038)
		(size 0.7112)
		(drill 0.3556)
		(layers "F.Cu" "B.Cu")
		(net "GND")
	)
	(via
		(at 68.9991 -27.86634)
		(size 0.508)
		(drill 0.254)
		(layers "F.Cu" "B.Cu")
		(net "GND")
	)
	(via
		(at 48.211994 -82.931)
		(size 0.5588)
		(drill 0.3048)
		(layers "F.Cu" "B.Cu")
		(net "GND")
	)
	(via
		(at 47.195994 -81.915)
		(size 0.5588)
		(drill 0.3048)
		(layers "F.Cu" "B.Cu")
		(net "GND")
	)
	(via
		(at 47.195994 -82.931)
		(size 0.5588)
		(drill 0.3048)
		(layers "F.Cu" "B.Cu")
		(net "GND")
	)
	(via
		(at 35.052 -87.757)
		(size 0.5588)
		(drill 0.3048)
		(layers "F.Cu" "B.Cu")
		(net "GND")
	)
	(via
		(at 22.606 -77.137006)
		(size 0.5588)
		(drill 0.3048)
		(layers "F.Cu" "B.Cu")
		(net "GND")
	)
	(via
		(at 18.288 -85.519006)
		(size 0.5588)
		(drill 0.3048)
		(layers "F.Cu" "B.Cu")
		(net "GND")
	)
	(via
		(at 63.881 -41.783)
		(size 0.508)
		(drill 0.254)
		(layers "F.Cu" "B.Cu")
		(net "GND")
	)
	(via
		(at 74.041 -27.92984)
		(size 0.5588)
		(drill 0.3048)
		(layers "F.Cu" "B.Cu")
		(net "GND")
	)
	(via
		(at 68.58 -8.89)
		(size 0.5588)
		(drill 0.3048)
		(layers "F.Cu" "B.Cu")
		(net "GND")
	)
	(via
		(at 58.42 -63.754)
		(size 0.5588)
		(drill 0.3048)
		(layers "F.Cu" "B.Cu")
		(net "GND")
	)
	(via
		(at 19.0754 -80.185006)
		(size 0.5588)
		(drill 0.3048)
		(layers "F.Cu" "B.Cu")
		(net "GND")
	)
	(via
		(at 22.606 -73.962006)
		(size 0.5588)
		(drill 0.3048)
		(layers "F.Cu" "B.Cu")
		(net "GND")
	)
	(via
		(at 82.611976 -28.675076)
		(size 0.508)
		(drill 0.254)
		(layers "F.Cu" "B.Cu")
		(net "GND")
	)
	(via
		(at 64.77 -8.89)
		(size 0.5588)
		(drill 0.3048)
		(layers "F.Cu" "B.Cu")
		(net "GND")
	)
	(via
		(at 36.019994 -86.741)
		(size 0.5588)
		(drill 0.3048)
		(layers "F.Cu" "B.Cu")
		(net "GND")
	)
	(via
		(at 74.041 -21.689822)
		(size 0.5588)
		(drill 0.3048)
		(layers "F.Cu" "B.Cu")
		(net "GND")
	)
	(via
		(at 30.988 -76.454)
		(size 0.508)
		(drill 0.254)
		(layers "F.Cu" "B.Cu")
		(net "GND")
	)
	(via
		(at 82.55 -83.82)
		(size 0.5588)
		(drill 0.3048)
		(layers "F.Cu" "B.Cu")
		(net "GND")
	)
	(via
		(at 16.383 -78.635606)
		(size 0.5588)
		(drill 0.3048)
		(layers "F.Cu" "B.Cu")
		(net "GND")
	)
	(via
		(at 26.3525 -79.5528)
		(size 0.508)
		(drill 0.254)
		(layers "F.Cu" "B.Cu")
		(net "GND")
	)
	(via
		(at 21.59 -68.58)
		(size 0.5588)
		(drill 0.3048)
		(layers "F.Cu" "B.Cu")
		(net "GND")
	)
	(via
		(at 68.9991 -56.584088)
		(size 0.508)
		(drill 0.254)
		(layers "F.Cu" "B.Cu")
		(net "GND")
	)
	(via
		(at 67.945 -75.692)
		(size 0.5588)
		(drill 0.3048)
		(layers "F.Cu" "B.Cu")
		(net "GND")
	)
	(via
		(at 38.227 -78.105)
		(size 0.5588)
		(drill 0.3048)
		(layers "F.Cu" "B.Cu")
		(net "GND")
	)
	(via
		(at 69.977 -43.690032)
		(size 0.5588)
		(drill 0.3048)
		(layers "F.Cu" "B.Cu")
		(net "GND")
	)
	(via
		(at 72.39 -8.255)
		(size 0.5588)
		(drill 0.3048)
		(layers "F.Cu" "B.Cu")
		(net "GND")
	)
	(via
		(at 47.195994 -78.867)
		(size 0.5588)
		(drill 0.3048)
		(layers "F.Cu" "B.Cu")
		(net "GND")
	)
	(via
		(at 69.469 -49.28997)
		(size 0.508)
		(drill 0.254)
		(layers "F.Cu" "B.Cu")
		(net "GND")
	)
	(via
		(at 74.8665 -49.596294)
		(size 0.508)
		(drill 0.254)
		(layers "F.Cu" "B.Cu")
		(net "GND")
	)
	(via
		(at 82.55 -80.01)
		(size 0.5588)
		(drill 0.3048)
		(layers "F.Cu" "B.Cu")
		(net "GND")
	)
	(via
		(at 80.01 -1.27)
		(size 0.5588)
		(drill 0.3048)
		(layers "F.Cu" "B.Cu")
		(net "GND")
	)
	(via
		(at 43.131994 -87.757)
		(size 0.5588)
		(drill 0.3048)
		(layers "F.Cu" "B.Cu")
		(net "GND")
	)
	(via
		(at 74.168 -46.101)
		(size 0.508)
		(drill 0.254)
		(layers "F.Cu" "B.Cu")
		(net "GND")
	)
	(via
		(at 70.045072 -36.789868)
		(size 0.5588)
		(drill 0.3048)
		(layers "F.Cu" "B.Cu")
		(net "GND")
	)
	(via
		(at 70.045072 -64.390016)
		(size 0.5588)
		(drill 0.3048)
		(layers "F.Cu" "B.Cu")
		(net "GND")
	)
	(via
		(at 68.4911 -52.466494)
		(size 0.508)
		(drill 0.254)
		(layers "F.Cu" "B.Cu")
		(net "GND")
	)
	(via
		(at 58.42 -17.018)
		(size 0.5588)
		(drill 0.3048)
		(layers "F.Cu" "B.Cu")
		(net "GND")
	)
	(via
		(at 61.341 -87.376)
		(size 0.5588)
		(drill 0.3048)
		(layers "F.Cu" "B.Cu")
		(net "GND")
	)
	(via
		(at 13.335 -84.122006)
		(size 0.5588)
		(drill 0.3048)
		(layers "F.Cu" "B.Cu")
		(net "GND")
	)
	(via
		(at 86.36 -87.63)
		(size 0.5588)
		(drill 0.3048)
		(layers "F.Cu" "B.Cu")
		(net "GND")
	)
	(via
		(at 10.16 -87.63)
		(size 0.5588)
		(drill 0.3048)
		(layers "F.Cu" "B.Cu")
		(net "GND")
	)
	(via
		(at 58.42 -18.034)
		(size 0.5588)
		(drill 0.3048)
		(layers "F.Cu" "B.Cu")
		(net "GND")
	)
	(via
		(at 82.55 -72.39)
		(size 0.5588)
		(drill 0.3048)
		(layers "F.Cu" "B.Cu")
		(net "GND")
	)
	(via
		(at 71.162926 -33.689798)
		(size 0.5588)
		(drill 0.3048)
		(layers "F.Cu" "B.Cu")
		(net "GND")
	)
	(via
		(at 68.4911 -24.866346)
		(size 0.508)
		(drill 0.254)
		(layers "F.Cu" "B.Cu")
		(net "GND")
	)
	(via
		(at 82.611976 -41.475152)
		(size 0.508)
		(drill 0.254)
		(layers "F.Cu" "B.Cu")
		(net "GND")
	)
	(via
		(at 13.335 -82.598006)
		(size 0.5588)
		(drill 0.3048)
		(layers "F.Cu" "B.Cu")
		(net "GND")
	)
	(via
		(at 57.15 -16.51)
		(size 0.5588)
		(drill 0.3048)
		(layers "F.Cu" "B.Cu")
		(net "GND")
	)
	(via
		(at 76.2 -8.89)
		(size 0.5588)
		(drill 0.3048)
		(layers "F.Cu" "B.Cu")
		(net "GND")
	)
	(via
		(at 82.55 -87.63)
		(size 0.5588)
		(drill 0.3048)
		(layers "F.Cu" "B.Cu")
		(net "GND")
	)
	(via
		(at 87.63 -5.08)
		(size 0.5588)
		(drill 0.3048)
		(layers "F.Cu" "B.Cu")
		(net "GND")
	)
	(via
		(at 69.469 -50.790094)
		(size 0.508)
		(drill 0.254)
		(layers "F.Cu" "B.Cu")
		(net "GND")
	)
	(via
		(at 46.179994 -81.915)
		(size 0.5588)
		(drill 0.3048)
		(layers "F.Cu" "B.Cu")
		(net "GND")
	)
	(via
		(at 57.15 -8.89)
		(size 0.5588)
		(drill 0.3048)
		(layers "F.Cu" "B.Cu")
		(net "GND")
	)
	(via
		(at 82.611976 -32.675068)
		(size 0.508)
		(drill 0.254)
		(layers "F.Cu" "B.Cu")
		(net "GND")
	)
	(via
		(at 67.945 -77.724)
		(size 0.5588)
		(drill 0.3048)
		(layers "F.Cu" "B.Cu")
		(net "GND")
	)
	(via
		(at 60.325 -87.376)
		(size 0.5588)
		(drill 0.3048)
		(layers "F.Cu" "B.Cu")
		(net "GND")
	)
	(via
		(at 71.12 -44.790106)
		(size 0.5588)
		(drill 0.3048)
		(layers "F.Cu" "B.Cu")
		(net "GND")
	)
	(via
		(at 78.74 -72.39)
		(size 0.5588)
		(drill 0.3048)
		(layers "F.Cu" "B.Cu")
		(net "GND")
	)
	(via
		(at 60.325 -86.36)
		(size 0.5588)
		(drill 0.3048)
		(layers "F.Cu" "B.Cu")
		(net "GND")
	)
	(via
		(at 74.041 -52.289964)
		(size 0.5588)
		(drill 0.3048)
		(layers "F.Cu" "B.Cu")
		(net "GND")
	)
	(via
		(at 82.611976 -36.67506)
		(size 0.508)
		(drill 0.254)
		(layers "F.Cu" "B.Cu")
		(net "GND")
	)
	(via
		(at 82.55 -91.44)
		(size 0.5588)
		(drill 0.3048)
		(layers "F.Cu" "B.Cu")
		(net "GND")
	)
	(via
		(at 71.755 -1.27)
		(size 0.5588)
		(drill 0.3048)
		(layers "F.Cu" "B.Cu")
		(net "GND")
	)
	(via
		(at 69.215 -5.08)
		(size 0.5588)
		(drill 0.3048)
		(layers "F.Cu" "B.Cu")
		(net "GND")
	)
	(via
		(at 82.611976 -26.27503)
		(size 0.508)
		(drill 0.254)
		(layers "F.Cu" "B.Cu")
		(net "GND")
	)
	(via
		(at 46.179994 -80.899)
		(size 0.5588)
		(drill 0.3048)
		(layers "F.Cu" "B.Cu")
		(net "GND")
	)
	(via
		(at 82.55 -57.15)
		(size 0.5588)
		(drill 0.3048)
		(layers "F.Cu" "B.Cu")
		(net "GND")
	)
	(via
		(at 60.325 -23.368)
		(size 0.7112)
		(drill 0.3556)
		(layers "F.Cu" "B.Cu")
		(net "GND")
	)
	(via
		(at 75.057 -52.949094)
		(size 0.5588)
		(drill 0.3048)
		(layers "F.Cu" "B.Cu")
		(net "GND")
	)
	(via
		(at 71.12 -72.39)
		(size 0.5588)
		(drill 0.3048)
		(layers "F.Cu" "B.Cu")
		(net "GND")
	)
	(via
		(at 57.15 -37.9095)
		(size 0.508)
		(drill 0.254)
		(layers "F.Cu" "B.Cu")
		(net "GND")
	)
	(via
		(at 22.606 -83.614006)
		(size 0.5588)
		(drill 0.3048)
		(layers "F.Cu" "B.Cu")
		(net "GND")
	)
	(via
		(at 82.611976 -19.075146)
		(size 0.508)
		(drill 0.254)
		(layers "F.Cu" "B.Cu")
		(net "GND")
	)
	(via
		(at 15.875 -70.993)
		(size 0.7112)
		(drill 0.3556)
		(layers "F.Cu" "B.Cu")
		(net "GND")
	)
	(via
		(at 22.606 -76.121006)
		(size 0.5588)
		(drill 0.3048)
		(layers "F.Cu" "B.Cu")
		(net "GND")
	)
	(via
		(at 63.246 -66.04)
		(size 0.5588)
		(drill 0.3048)
		(layers "F.Cu" "B.Cu")
		(net "GND")
	)
	(via
		(at 15.113 -74.724006)
		(size 0.5588)
		(drill 0.3048)
		(layers "F.Cu" "B.Cu")
		(net "GND")
	)
	(via
		(at 37.035994 -87.757)
		(size 0.5588)
		(drill 0.3048)
		(layers "F.Cu" "B.Cu")
		(net "GND")
	)
	(via
		(at 58.42 -30.988)
		(size 0.5588)
		(drill 0.3048)
		(layers "F.Cu" "B.Cu")
		(net "GND")
	)
	(via
		(at 71.12 -68.58)
		(size 0.5588)
		(drill 0.3048)
		(layers "F.Cu" "B.Cu")
		(net "GND")
	)
	(via
		(at 67.945 -74.676)
		(size 0.5588)
		(drill 0.3048)
		(layers "F.Cu" "B.Cu")
		(net "GND")
	)
	(via
		(at 76.708 -40.005)
		(size 0.508)
		(drill 0.254)
		(layers "F.Cu" "B.Cu")
		(net "GND")
	)
	(via
		(at 64.77 -1.27)
		(size 0.5588)
		(drill 0.3048)
		(layers "F.Cu" "B.Cu")
		(net "GND")
	)
	(via
		(at 74.041 -58.289952)
		(size 0.5588)
		(drill 0.3048)
		(layers "F.Cu" "B.Cu")
		(net "GND")
	)
	(via
		(at 74.8665 -50.459894)
		(size 0.508)
		(drill 0.254)
		(layers "F.Cu" "B.Cu")
		(net "GND")
	)
	(via
		(at 22.606 -84.630006)
		(size 0.5588)
		(drill 0.3048)
		(layers "F.Cu" "B.Cu")
		(net "GND")
	)
	(via
		(at 10.16 -83.82)
		(size 0.5588)
		(drill 0.3048)
		(layers "F.Cu" "B.Cu")
		(net "GND")
	)
	(via
		(at 58.42 -33.02)
		(size 0.5588)
		(drill 0.3048)
		(layers "F.Cu" "B.Cu")
		(net "GND")
	)
	(via
		(at 82.611976 -35.075114)
		(size 0.508)
		(drill 0.254)
		(layers "F.Cu" "B.Cu")
		(net "GND")
	)
	(via
		(at 65.151 -87.376)
		(size 0.5588)
		(drill 0.3048)
		(layers "F.Cu" "B.Cu")
		(net "GND")
	)
	(via
		(at 71.162926 -32.189928)
		(size 0.5588)
		(drill 0.3048)
		(layers "F.Cu" "B.Cu")
		(net "GND")
	)
	(via
		(at 86.36 -72.39)
		(size 0.5588)
		(drill 0.3048)
		(layers "F.Cu" "B.Cu")
		(net "GND")
	)
	(via
		(at 78.74 -57.15)
		(size 0.5588)
		(drill 0.3048)
		(layers "F.Cu" "B.Cu")
		(net "GND")
	)
	(via
		(at 67.31 -72.39)
		(size 0.5588)
		(drill 0.3048)
		(layers "F.Cu" "B.Cu")
		(net "GND")
	)
	(via
		(at 71.162926 -30.689804)
		(size 0.5588)
		(drill 0.3048)
		(layers "F.Cu" "B.Cu")
		(net "GND")
	)
	(via
		(at 71.12 -18.189956)
		(size 0.5588)
		(drill 0.3048)
		(layers "F.Cu" "B.Cu")
		(net "GND")
	)
	(via
		(at 78.74 -91.44)
		(size 0.5588)
		(drill 0.3048)
		(layers "F.Cu" "B.Cu")
		(net "GND")
	)
	(via
		(at 60.833 -11.049)
		(size 0.7112)
		(drill 0.3556)
		(layers "F.Cu" "B.Cu")
		(net "GND")
	)
	(via
		(at 22.606 -71.930006)
		(size 0.5588)
		(drill 0.3048)
		(layers "F.Cu" "B.Cu")
		(net "GND")
	)
	(via
		(at 39.067994 -86.741)
		(size 0.5588)
		(drill 0.3048)
		(layers "F.Cu" "B.Cu")
		(net "GND")
	)
	(via
		(at 36.019994 -87.757)
		(size 0.5588)
		(drill 0.3048)
		(layers "F.Cu" "B.Cu")
		(net "GND")
	)
	(via
		(at 61.341 -86.36)
		(size 0.5588)
		(drill 0.3048)
		(layers "F.Cu" "B.Cu")
		(net "GND")
	)
	(via
		(at 82.611976 -39.075106)
		(size 0.508)
		(drill 0.254)
		(layers "F.Cu" "B.Cu")
		(net "GND")
	)
	(via
		(at 40.083994 -87.757)
		(size 0.5588)
		(drill 0.3048)
		(layers "F.Cu" "B.Cu")
		(net "GND")
	)
	(via
		(at 25.527 -85.265006)
		(size 0.508)
		(drill 0.254)
		(layers "F.Cu" "B.Cu")
		(net "GND")
	)
	(via
		(at 69.977 -16.089884)
		(size 0.5588)
		(drill 0.3048)
		(layers "F.Cu" "B.Cu")
		(net "GND")
	)
	(via
		(at 86.36 -76.2)
		(size 0.5588)
		(drill 0.3048)
		(layers "F.Cu" "B.Cu")
		(net "GND")
	)
	(via
		(at 38.051994 -87.757)
		(size 0.5588)
		(drill 0.3048)
		(layers "F.Cu" "B.Cu")
		(net "GND")
	)
	(via
		(at 78.74 -87.63)
		(size 0.5588)
		(drill 0.3048)
		(layers "F.Cu" "B.Cu")
		(net "GND")
	)
	(via
		(at 66.167 -86.36)
		(size 0.5588)
		(drill 0.3048)
		(layers "F.Cu" "B.Cu")
		(net "GND")
	)
	(via
		(at 78.74 -80.01)
		(size 0.5588)
		(drill 0.3048)
		(layers "F.Cu" "B.Cu")
		(net "GND")
	)
	(via
		(at 77.35951 -35.850068)
		(size 0.5588)
		(drill 0.3048)
		(layers "F.Cu" "B.Cu")
		(net "GND")
	)
	(via
		(at 58.42 -60.579)
		(size 0.5588)
		(drill 0.3048)
		(layers "F.Cu" "B.Cu")
		(net "GND")
	)
	(via
		(at 67.31 -91.44)
		(size 0.5588)
		(drill 0.3048)
		(layers "F.Cu" "B.Cu")
		(net "GND")
	)
	(via
		(at 74.041 -53.584094)
		(size 0.5588)
		(drill 0.3048)
		(layers "F.Cu" "B.Cu")
		(net "GND")
	)
	(via
		(at 78.74 -68.58)
		(size 0.5588)
		(drill 0.3048)
		(layers "F.Cu" "B.Cu")
		(net "GND")
	)
	(via
		(at 68.9991 -28.98394)
		(size 0.508)
		(drill 0.254)
		(layers "F.Cu" "B.Cu")
		(net "GND")
	)
	(via
		(at 86.36 -91.44)
		(size 0.5588)
		(drill 0.3048)
		(layers "F.Cu" "B.Cu")
		(net "GND")
	)
	(via
		(at 17.2466 -80.185006)
		(size 0.5588)
		(drill 0.3048)
		(layers "F.Cu" "B.Cu")
		(net "GND")
	)
	(via
		(at 69.977 -76.708)
		(size 0.5588)
		(drill 0.3048)
		(layers "F.Cu" "B.Cu")
		(net "GND")
	)
	(via
		(at 82.611976 -14.275054)
		(size 0.508)
		(drill 0.254)
		(layers "F.Cu" "B.Cu")
		(net "GND")
	)
	(via
		(at 13.97 -91.44)
		(size 0.5588)
		(drill 0.3048)
		(layers "F.Cu" "B.Cu")
		(net "GND")
	)
	(via
		(at 10.16 -91.44)
		(size 0.5588)
		(drill 0.3048)
		(layers "F.Cu" "B.Cu")
		(net "GND")
	)
	(via
		(at 46.863 -85.852)
		(size 0.5588)
		(drill 0.3048)
		(layers "F.Cu" "B.Cu")
		(net "GND")
	)
	(via
		(at 33.02 -91.44)
		(size 0.5588)
		(drill 0.3048)
		(layers "F.Cu" "B.Cu")
		(net "GND")
	)
	(via
		(at 2.54 -87.63)
		(size 0.5588)
		(drill 0.3048)
		(layers "F.Cu" "B.Cu")
		(net "GND")
	)
	(via
		(at 78.74 -76.2)
		(size 0.5588)
		(drill 0.3048)
		(layers "F.Cu" "B.Cu")
		(net "GND")
	)
	(via
		(at 76.0222 -34.808922)
		(size 0.508)
		(drill 0.254)
		(layers "F.Cu" "B.Cu")
		(net "GND")
	)
	(via
		(at 65.151 -85.344)
		(size 0.5588)
		(drill 0.3048)
		(layers "F.Cu" "B.Cu")
		(net "GND")
	)
	(via
		(at 63.5 -91.44)
		(size 0.5588)
		(drill 0.3048)
		(layers "F.Cu" "B.Cu")
		(net "GND")
	)
	(via
		(at 13.97 -68.58)
		(size 0.5588)
		(drill 0.3048)
		(layers "F.Cu" "B.Cu")
		(net "GND")
	)
	(via
		(at 78.74 -83.82)
		(size 0.5588)
		(drill 0.3048)
		(layers "F.Cu" "B.Cu")
		(net "GND")
	)
	(via
		(at 42.115994 -86.741)
		(size 0.5588)
		(drill 0.3048)
		(layers "F.Cu" "B.Cu")
		(net "GND")
	)
	(via
		(at 68.8975 -35.2425)
		(size 0.508)
		(drill 0.254)
		(layers "F.Cu" "B.Cu")
		(net "GND")
	)
	(via
		(at 60.14847 -37.198808)
		(size 0.508)
		(drill 0.254)
		(layers "F.Cu" "B.Cu")
		(net "GND")
	)
	(via
		(at 57.15 -24.13)
		(size 0.5588)
		(drill 0.3048)
		(layers "F.Cu" "B.Cu")
		(net "GND")
	)
	(via
		(at 41.099994 -87.757)
		(size 0.5588)
		(drill 0.3048)
		(layers "F.Cu" "B.Cu")
		(net "GND")
	)
	(via
		(at 55.88 -91.44)
		(size 0.5588)
		(drill 0.3048)
		(layers "F.Cu" "B.Cu")
		(net "GND")
	)
	(via
		(at 74.0537 -23.189946)
		(size 0.5588)
		(drill 0.3048)
		(layers "F.Cu" "B.Cu")
		(net "GND")
	)
	(via
		(at 39.067994 -87.757)
		(size 0.5588)
		(drill 0.3048)
		(layers "F.Cu" "B.Cu")
		(net "GND")
	)
	(via
		(at 38.051994 -86.741)
		(size 0.5588)
		(drill 0.3048)
		(layers "F.Cu" "B.Cu")
		(net "GND")
	)
	(via
		(at 47.195994 -77.2668)
		(size 0.5588)
		(drill 0.3048)
		(layers "F.Cu" "B.Cu")
		(net "GND")
	)
	(via
		(at 71.162926 -62.79007)
		(size 0.5588)
		(drill 0.3048)
		(layers "F.Cu" "B.Cu")
		(net "GND")
	)
	(via
		(at 17.78 -91.44)
		(size 0.5588)
		(drill 0.3048)
		(layers "F.Cu" "B.Cu")
		(net "GND")
	)
	(via
		(at 79.502 -45.593)
		(size 0.5588)
		(drill 0.3048)
		(layers "F.Cu" "B.Cu")
		(net "GND")
	)
	(via
		(at 74.93 -80.01)
		(size 0.5588)
		(drill 0.3048)
		(layers "F.Cu" "B.Cu")
		(net "GND")
	)
	(via
		(at 68.961 -75.692)
		(size 0.5588)
		(drill 0.3048)
		(layers "F.Cu" "B.Cu")
		(net "GND")
	)
	(via
		(at 35.687 -71.374)
		(size 0.508)
		(drill 0.254)
		(layers "F.Cu" "B.Cu")
		(net "GND")
	)
	(via
		(at 74.041 -56.790082)
		(size 0.5588)
		(drill 0.3048)
		(layers "F.Cu" "B.Cu")
		(net "GND")
	)
	(via
		(at 71.12 -80.01)
		(size 0.5588)
		(drill 0.3048)
		(layers "F.Cu" "B.Cu")
		(net "GND")
	)
	(via
		(at 60.325 -85.344)
		(size 0.5588)
		(drill 0.3048)
		(layers "F.Cu" "B.Cu")
		(net "GND")
	)
	(via
		(at 43.131994 -86.741)
		(size 0.5588)
		(drill 0.3048)
		(layers "F.Cu" "B.Cu")
		(net "GND")
	)
	(via
		(at 58.42 -62.738)
		(size 0.5588)
		(drill 0.3048)
		(layers "F.Cu" "B.Cu")
		(net "GND")
	)
	(via
		(at 44.45 -91.44)
		(size 0.5588)
		(drill 0.3048)
		(layers "F.Cu" "B.Cu")
		(net "GND")
	)
	(via
		(at 58.42 -58.547)
		(size 0.5588)
		(drill 0.3048)
		(layers "F.Cu" "B.Cu")
		(net "GND")
	)
	(via
		(at 66.167 -85.344)
		(size 0.5588)
		(drill 0.3048)
		(layers "F.Cu" "B.Cu")
		(net "GND")
	)
	(via
		(at 77.35951 -24.420068)
		(size 0.5588)
		(drill 0.3048)
		(layers "F.Cu" "B.Cu")
		(net "GND")
	)
	(via
		(at 21.59 -91.44)
		(size 0.5588)
		(drill 0.3048)
		(layers "F.Cu" "B.Cu")
		(net "GND")
	)
	(via
		(at 67.9958 -38.9255)
		(size 0.508)
		(drill 0.254)
		(layers "F.Cu" "B.Cu")
		(net "GND")
	)
	(via
		(at 82.55 -68.58)
		(size 0.5588)
		(drill 0.3048)
		(layers "F.Cu" "B.Cu")
		(net "GND")
	)
	(via
		(at 82.611976 -30.275022)
		(size 0.508)
		(drill 0.254)
		(layers "F.Cu" "B.Cu")
		(net "GND")
	)
	(via
		(at 61.341 -85.344)
		(size 0.5588)
		(drill 0.3048)
		(layers "F.Cu" "B.Cu")
		(net "GND")
	)
	(via
		(at 42.115994 -87.757)
		(size 0.5588)
		(drill 0.3048)
		(layers "F.Cu" "B.Cu")
		(net "GND")
	)
	(via
		(at 67.945 -76.708)
		(size 0.5588)
		(drill 0.3048)
		(layers "F.Cu" "B.Cu")
		(net "GND")
	)
	(via
		(at 77.35951 -15.530068)
		(size 0.5588)
		(drill 0.3048)
		(layers "F.Cu" "B.Cu")
		(net "GND")
	)
	(via
		(at 6.35 -91.44)
		(size 0.5588)
		(drill 0.3048)
		(layers "F.Cu" "B.Cu")
		(net "GND")
	)
	(via
		(at 58.42 -34.163)
		(size 0.5588)
		(drill 0.3048)
		(layers "F.Cu" "B.Cu")
		(net "GND")
	)
	(via
		(at 74.041 -59.790076)
		(size 0.5588)
		(drill 0.3048)
		(layers "F.Cu" "B.Cu")
		(net "GND")
	)
	(via
		(at 47.195994 -79.883)
		(size 0.5588)
		(drill 0.3048)
		(layers "F.Cu" "B.Cu")
		(net "GND")
	)
	(via
		(at 36.83 -91.44)
		(size 0.5588)
		(drill 0.3048)
		(layers "F.Cu" "B.Cu")
		(net "GND")
	)
	(via
		(at 58.42 -61.722)
		(size 0.5588)
		(drill 0.3048)
		(layers "F.Cu" "B.Cu")
		(net "GND")
	)
	(via
		(at 82.611976 -16.6751)
		(size 0.508)
		(drill 0.254)
		(layers "F.Cu" "B.Cu")
		(net "GND")
	)
	(via
		(at 58.42 -36.195)
		(size 0.5588)
		(drill 0.3048)
		(layers "F.Cu" "B.Cu")
		(net "GND")
	)
	(via
		(at 82.55 -64.77)
		(size 0.5588)
		(drill 0.3048)
		(layers "F.Cu" "B.Cu")
		(net "GND")
	)
	(via
		(at 74.041 -25.89784)
		(size 0.5588)
		(drill 0.3048)
		(layers "F.Cu" "B.Cu")
		(net "GND")
	)
	(via
		(at 13.97 -72.39)
		(size 0.5588)
		(drill 0.3048)
		(layers "F.Cu" "B.Cu")
		(net "GND")
	)
	(via
		(at 74.041 -29.189934)
		(size 0.5588)
		(drill 0.3048)
		(layers "F.Cu" "B.Cu")
		(net "GND")
	)
	(via
		(at 25.4 -91.44)
		(size 0.5588)
		(drill 0.3048)
		(layers "F.Cu" "B.Cu")
		(net "GND")
	)
	(via
		(at 58.42 -32.004)
		(size 0.5588)
		(drill 0.3048)
		(layers "F.Cu" "B.Cu")
		(net "GND")
	)
	(via
		(at 68.961 -77.724)
		(size 0.5588)
		(drill 0.3048)
		(layers "F.Cu" "B.Cu")
		(net "GND")
	)
	(via
		(at 69.977 -74.676)
		(size 0.5588)
		(drill 0.3048)
		(layers "F.Cu" "B.Cu")
		(net "GND")
	)
	(via
		(at 25.4 -68.58)
		(size 0.5588)
		(drill 0.3048)
		(layers "F.Cu" "B.Cu")
		(net "GND")
	)
	(via
		(at 48.211994 -80.899)
		(size 0.5588)
		(drill 0.3048)
		(layers "F.Cu" "B.Cu")
		(net "GND")
	)
	(via
		(at 69.977 -77.724)
		(size 0.5588)
		(drill 0.3048)
		(layers "F.Cu" "B.Cu")
		(net "GND")
	)
	(via
		(at 48.211994 -81.915)
		(size 0.5588)
		(drill 0.3048)
		(layers "F.Cu" "B.Cu")
		(net "GND")
	)
	(via
		(at 86.36 -80.01)
		(size 0.5588)
		(drill 0.3048)
		(layers "F.Cu" "B.Cu")
		(net "GND")
	)
	(via
		(at 48.211994 -79.883)
		(size 0.5588)
		(drill 0.3048)
		(layers "F.Cu" "B.Cu")
		(net "GND")
	)
	(via
		(at 66.167 -87.376)
		(size 0.5588)
		(drill 0.3048)
		(layers "F.Cu" "B.Cu")
		(net "GND")
	)
	(via
		(at 57.15 -20.32)
		(size 0.5588)
		(drill 0.3048)
		(layers "F.Cu" "B.Cu")
		(net "GND")
	)
	(via
		(at 74.93 -76.2)
		(size 0.5588)
		(drill 0.3048)
		(layers "F.Cu" "B.Cu")
		(net "GND")
	)
	(via
		(at 74.93 -72.39)
		(size 0.5588)
		(drill 0.3048)
		(layers "F.Cu" "B.Cu")
		(net "GND")
	)
	(via
		(at 39.37 -76.5429)
		(size 0.5588)
		(drill 0.3048)
		(layers "F.Cu" "B.Cu")
		(net "GND")
	)
	(via
		(at 74.041 -61.289946)
		(size 0.5588)
		(drill 0.3048)
		(layers "F.Cu" "B.Cu")
		(net "GND")
	)
	(via
		(at 17.78 -68.58)
		(size 0.5588)
		(drill 0.3048)
		(layers "F.Cu" "B.Cu")
		(net "GND")
	)
	(via
		(at 58.42 -59.563)
		(size 0.5588)
		(drill 0.3048)
		(layers "F.Cu" "B.Cu")
		(net "GND")
	)
	(via
		(at 80.391 -81.407)
		(size 0.7112)
		(drill 0.3556)
		(layers "F.Cu" "B.Cu")
		(net "GND")
	)
	(via
		(at 46.863 -84.836)
		(size 0.5588)
		(drill 0.3048)
		(layers "F.Cu" "B.Cu")
		(net "GND")
	)
	(via
		(at 76.2 -5.08)
		(size 0.5588)
		(drill 0.3048)
		(layers "F.Cu" "B.Cu")
		(net "GND")
	)
	(via
		(at 46.179994 -82.931)
		(size 0.5588)
		(drill 0.3048)
		(layers "F.Cu" "B.Cu")
		(net "GND")
	)
	(via
		(at 18.161 -80.185006)
		(size 0.5588)
		(drill 0.3048)
		(layers "F.Cu" "B.Cu")
		(net "GND")
	)
	(via
		(at 61.976 -70.485)
		(size 0.7112)
		(drill 0.3556)
		(layers "F.Cu" "B.Cu")
		(net "GND")
	)
	(via
		(at 69.977 -75.692)
		(size 0.5588)
		(drill 0.3048)
		(layers "F.Cu" "B.Cu")
		(net "GND")
	)
	(via
		(at 58.42 -46.609)
		(size 0.5588)
		(drill 0.3048)
		(layers "F.Cu" "B.Cu")
		(net "GND")
	)
	(via
		(at 82.55 -76.2)
		(size 0.5588)
		(drill 0.3048)
		(layers "F.Cu" "B.Cu")
		(net "GND")
	)
	(via
		(at 82.55 -60.96)
		(size 0.5588)
		(drill 0.3048)
		(layers "F.Cu" "B.Cu")
		(net "GND")
	)
	(via
		(at 40.64 -91.44)
		(size 0.5588)
		(drill 0.3048)
		(layers "F.Cu" "B.Cu")
		(net "GND")
	)
	(via
		(at 76.327 -32.7914)
		(size 0.508)
		(drill 0.254)
		(layers "F.Cu" "B.Cu")
		(net "GND")
	)
	(via
		(at 41.861994 -77.216)
		(size 0.5588)
		(drill 0.3048)
		(layers "F.Cu" "B.Cu")
		(net "GND")
	)
	(via
		(at 82.372708 -51.810158)
		(size 0.5588)
		(drill 0.3048)
		(layers "F.Cu" "B.Cu")
		(net "GND")
	)
	(via
		(at 47.195994 -80.899)
		(size 0.5588)
		(drill 0.3048)
		(layers "F.Cu" "B.Cu")
		(net "GND")
	)
	(via
		(at 57.15 -12.7)
		(size 0.5588)
		(drill 0.3048)
		(layers "F.Cu" "B.Cu")
		(net "GND")
	)
	(via
		(at 58.42 -35.179)
		(size 0.5588)
		(drill 0.3048)
		(layers "F.Cu" "B.Cu")
		(net "GND")
	)
	(segment
		(start 76.708 -78.867)
		(end 76.708 -79.934308)
		(width 0.508)
		(layer "B.Cu")
		(net "GND")
	)
	(segment
		(start 78.82001 -15.530068)
		(end 77.35951 -15.530068)
		(width 0.508)
		(layer "B.Cu")
		(net "GND")
	)
	(segment
		(start 73.001378 -83.452208)
		(end 73.001378 -87.808816)
		(width 0.508)
		(layer "B.Cu")
		(net "GND")
	)
	(segment
		(start 78.82001 -39.660068)
		(end 77.052932 -39.660068)
		(width 0.508)
		(layer "B.Cu")
		(net "GND")
	)
	(segment
		(start 24.5745 -80.518)
		(end 24.5745 -79.5655)
		(width 0.508)
		(layer "B.Cu")
		(net "GND")
	)
	(segment
		(start 78.82001 -24.420068)
		(end 77.35951 -24.420068)
		(width 0.508)
		(layer "B.Cu")
		(net "GND")
	)
	(segment
		(start 39.575994 -77.6478)
		(end 39.37 -77.441806)
		(width 0.508)
		(layer "B.Cu")
		(net "GND")
	)
	(segment
		(start 81.380076 -30.275022)
		(end 82.611976 -30.275022)
		(width 0.508)
		(layer "B.Cu")
		(net "GND")
	)
	(segment
		(start 77.560932 -23.150068)
		(end 77.343 -23.368)
		(width 0.508)
		(layer "B.Cu")
		(net "GND")
	)
	(segment
		(start 76.708 -77.799692)
		(end 76.708 -78.867)
		(width 0.508)
		(layer "B.Cu")
		(net "GND")
	)
	(segment
		(start 81.380076 -16.6751)
		(end 82.611976 -16.6751)
		(width 0.508)
		(layer "B.Cu")
		(net "GND")
	)
	(segment
		(start 6.501384 -80.308704)
		(end 6.501384 -84.665312)
		(width 0.508)
		(layer "B.Cu")
		(net "GND")
	)
	(segment
		(start 81.380076 -19.075146)
		(end 82.611976 -19.075146)
		(width 0.508)
		(layer "B.Cu")
		(net "GND")
	)
	(segment
		(start 58.244994 -41.7195)
		(end 57.15 -41.7195)
		(width 0.508)
		(layer "B.Cu")
		(net "GND")
	)
	(segment
		(start 73.001378 -87.808816)
		(end 77.357986 -87.808816)
		(width 0.508)
		(layer "B.Cu")
		(net "GND")
	)
	(segment
		(start 24.5745 -81.534)
		(end 24.5745 -80.518)
		(width 0.508)
		(layer "B.Cu")
		(net "GND")
	)
	(segment
		(start 78.82001 -43.470068)
		(end 78.82001 -44.91101)
		(width 0.508)
		(layer "B.Cu")
		(net "GND")
	)
	(segment
		(start 75.640692 -78.867)
		(end 76.708 -78.867)
		(width 0.508)
		(layer "B.Cu")
		(net "GND")
	)
	(segment
		(start 81.380076 -21.475192)
		(end 82.611976 -21.475192)
		(width 0.508)
		(layer "B.Cu")
		(net "GND")
	)
	(segment
		(start 78.82001 -35.850068)
		(end 77.35951 -35.850068)
		(width 0.508)
		(layer "B.Cu")
		(net "GND")
	)
	(segment
		(start 68.64477 -87.808816)
		(end 73.001378 -87.808816)
		(width 0.508)
		(layer "B.Cu")
		(net "GND")
	)
	(segment
		(start 81.380076 -26.27503)
		(end 82.611976 -26.27503)
		(width 0.508)
		(layer "B.Cu")
		(net "GND")
	)
	(segment
		(start 81.380076 -36.67506)
		(end 82.611976 -36.67506)
		(width 0.508)
		(layer "B.Cu")
		(net "GND")
	)
	(segment
		(start 78.82001 -44.91101)
		(end 79.502 -45.593)
		(width 0.508)
		(layer "B.Cu")
		(net "GND")
	)
	(segment
		(start 6.501384 -75.952096)
		(end 6.501384 -80.308704)
		(width 0.508)
		(layer "B.Cu")
		(net "GND")
	)
	(segment
		(start 81.380076 -35.075114)
		(end 82.611976 -35.075114)
		(width 0.508)
		(layer "B.Cu")
		(net "GND")
	)
	(segment
		(start 39.37 -77.441806)
		(end 39.37 -76.5429)
		(width 0.508)
		(layer "B.Cu")
		(net "GND")
	)
	(segment
		(start 78.82001 -23.150068)
		(end 77.560932 -23.150068)
		(width 0.508)
		(layer "B.Cu")
		(net "GND")
	)
	(segment
		(start 60.201302 -4.498848)
		(end 64.55791 -4.498848)
		(width 0.508)
		(layer "B.Cu")
		(net "GND")
	)
	(segment
		(start 64.8335 -41.783)
		(end 63.881 -41.783)
		(width 0.508)
		(layer "B.Cu")
		(net "GND")
	)
	(segment
		(start 77.052932 -39.660068)
		(end 76.708 -40.005)
		(width 0.508)
		(layer "B.Cu")
		(net "GND")
	)
	(segment
		(start 55.844694 -4.498848)
		(end 60.201302 -4.498848)
		(width 0.508)
		(layer "B.Cu")
		(net "GND")
	)
	(segment
		(start 70.83044 -41.2115)
		(end 70.11924 -41.2115)
		(width 0.3048)
		(layer "B.Cu")
		(net "GND")
	)
	(segment
		(start 81.380076 -39.075106)
		(end 82.611976 -39.075106)
		(width 0.508)
		(layer "B.Cu")
		(net "GND")
	)
	(segment
		(start 81.380076 -41.475152)
		(end 82.611976 -41.475152)
		(width 0.508)
		(layer "B.Cu")
		(net "GND")
	)
	(segment
		(start 81.380076 -32.675068)
		(end 82.611976 -32.675068)
		(width 0.508)
		(layer "B.Cu")
		(net "GND")
	)
	(segment
		(start 68.8975 -34.417)
		(end 68.8975 -35.2425)
		(width 0.508)
		(layer "B.Cu")
		(net "GND")
	)
	(segment
		(start 76.708 -78.867)
		(end 77.775308 -78.867)
		(width 0.508)
		(layer "B.Cu")
		(net "GND")
	)
	(segment
		(start 81.380076 -28.675076)
		(end 82.611976 -28.675076)
		(width 0.508)
		(layer "B.Cu")
		(net "GND")
	)
	(segment
		(start 58.244994 -40.7035)
		(end 57.15 -40.7035)
		(width 0.508)
		(layer "B.Cu")
		(net "GND")
	)
	(segment
		(start 67.183 -38.9255)
		(end 67.9958 -38.9255)
		(width 0.508)
		(layer "B.Cu")
		(net "GND")
	)
	(segment
		(start 68.707 -61.0235)
		(end 69.4944 -61.0235)
		(width 0.508)
		(layer "B.Cu")
		(net "GND")
	)
	(segment
		(start 60.201302 -4.498848)
		(end 60.201302 -8.855456)
		(width 0.508)
		(layer "B.Cu")
		(net "GND")
	)
	(segment
		(start 2.144776 -80.308704)
		(end 6.501384 -80.308704)
		(width 0.508)
		(layer "B.Cu")
		(net "GND")
	)
	(segment
		(start 58.244994 -37.9095)
		(end 57.15 -37.9095)
		(width 0.508)
		(layer "B.Cu")
		(net "GND")
	)
	(segment
		(start 81.380076 -23.874984)
		(end 82.611976 -23.874984)
		(width 0.508)
		(layer "B.Cu")
		(net "GND")
	)
	(segment
		(start 6.501384 -80.308704)
		(end 10.857992 -80.308704)
		(width 0.508)
		(layer "B.Cu")
		(net "GND")
	)
	(segment
		(start 81.380076 -14.275054)
		(end 82.611976 -14.275054)
		(width 0.508)
		(layer "B.Cu")
		(net "GND")
	)
	(segment
		(start 6.501384 -80.308704)
		(end 8.838692 -80.308704)
		(width 0.508)
		(layer "In2.Cu")
		(net "GND")
	)
	(segment
		(start 70.66407 -87.808816)
		(end 73.001378 -87.808816)
		(width 0.508)
		(layer "In2.Cu")
		(net "GND")
	)
	(segment
		(start 60.201302 -4.498848)
		(end 62.53861 -4.498848)
		(width 0.508)
		(layer "In2.Cu")
		(net "GND")
	)
	(segment
		(start 6.501384 -77.971396)
		(end 6.501384 -80.308704)
		(width 0.508)
		(layer "In2.Cu")
		(net "GND")
	)
	(segment
		(start 75.640692 -78.867)
		(end 76.708 -78.867)
		(width 0.508)
		(layer "In2.Cu")
		(net "GND")
	)
	(segment
		(start 57.863994 -4.498848)
		(end 60.201302 -4.498848)
		(width 0.508)
		(layer "In2.Cu")
		(net "GND")
	)
	(segment
		(start 6.501384 -80.308704)
		(end 6.501384 -82.646012)
		(width 0.508)
		(layer "In2.Cu")
		(net "GND")
	)
	(segment
		(start 73.001378 -85.471508)
		(end 73.001378 -87.808816)
		(width 0.508)
		(layer "In2.Cu")
		(net "GND")
	)
	(segment
		(start 60.201302 -2.16154)
		(end 60.201302 -4.498848)
		(width 0.508)
		(layer "In2.Cu")
		(net "GND")
	)
	(segment
		(start 60.201302 -4.498848)
		(end 60.201302 -6.836156)
		(width 0.508)
		(layer "In2.Cu")
		(net "GND")
	)
	(segment
		(start 4.164076 -80.308704)
		(end 6.501384 -80.308704)
		(width 0.508)
		(layer "In2.Cu")
		(net "GND")
	)
	(segment
		(start 73.001378 -87.808816)
		(end 73.001378 -90.146124)
		(width 0.508)
		(layer "In2.Cu")
		(net "GND")
	)
	(segment
		(start 76.708 -78.867)
		(end 77.775308 -78.867)
		(width 0.508)
		(layer "In2.Cu")
		(net "GND")
	)
	(segment
		(start 73.001378 -87.808816)
		(end 75.338686 -87.808816)
		(width 0.508)
		(layer "In2.Cu")
		(net "GND")
	)
	(segment
		(start 76.708 -77.799692)
		(end 76.708 -78.867)
		(width 0.508)
		(layer "In2.Cu")
		(net "GND")
	)
	(segment
		(start 76.708 -78.867)
		(end 76.708 -79.934308)
		(width 0.508)
		(layer "In2.Cu")
		(net "GND")
	)
	(segment
		(start 60.201302 -4.498848)
		(end 62.53861 -4.498848)
		(width 0.508)
		(layer "In5.Cu")
		(net "GND")
	)
	(segment
		(start 60.201302 -4.498848)
		(end 60.201302 -6.836156)
		(width 0.508)
		(layer "In5.Cu")
		(net "GND")
	)
	(segment
		(start 6.501384 -80.308704)
		(end 8.838692 -80.308704)
		(width 0.508)
		(layer "In5.Cu")
		(net "GND")
	)
	(segment
		(start 73.001378 -87.808816)
		(end 73.001378 -90.146124)
		(width 0.508)
		(layer "In5.Cu")
		(net "GND")
	)
	(segment
		(start 4.164076 -80.308704)
		(end 6.501384 -80.308704)
		(width 0.508)
		(layer "In5.Cu")
		(net "GND")
	)
	(segment
		(start 60.201302 -2.16154)
		(end 60.201302 -4.498848)
		(width 0.508)
		(layer "In5.Cu")
		(net "GND")
	)
	(segment
		(start 6.501384 -77.971396)
		(end 6.501384 -80.308704)
		(width 0.508)
		(layer "In5.Cu")
		(net "GND")
	)
	(segment
		(start 76.708 -77.799692)
		(end 76.708 -78.867)
		(width 0.508)
		(layer "In5.Cu")
		(net "GND")
	)
	(segment
		(start 73.001378 -87.808816)
		(end 75.338686 -87.808816)
		(width 0.508)
		(layer "In5.Cu")
		(net "GND")
	)
	(segment
		(start 75.640692 -78.867)
		(end 76.708 -78.867)
		(width 0.508)
		(layer "In5.Cu")
		(net "GND")
	)
	(segment
		(start 6.501384 -80.308704)
		(end 6.501384 -82.646012)
		(width 0.508)
		(layer "In5.Cu")
		(net "GND")
	)
	(segment
		(start 70.66407 -87.808816)
		(end 73.001378 -87.808816)
		(width 0.508)
		(layer "In5.Cu")
		(net "GND")
	)
	(segment
		(start 76.708 -78.867)
		(end 77.775308 -78.867)
		(width 0.508)
		(layer "In5.Cu")
		(net "GND")
	)
	(segment
		(start 73.001378 -85.471508)
		(end 73.001378 -87.808816)
		(width 0.508)
		(layer "In5.Cu")
		(net "GND")
	)
	(segment
		(start 57.863994 -4.498848)
		(end 60.201302 -4.498848)
		(width 0.508)
		(layer "In5.Cu")
		(net "GND")
	)
	(segment
		(start 76.708 -78.867)
		(end 76.708 -79.934308)
		(width 0.508)
		(layer "In5.Cu")
		(net "GND")
	)
	(segment
		(start 56.619394 -76.222606)
		(end 56.619394 -72.920606)
		(width 0.508)
		(layer "F.Cu")
		(net "P12V")
	)
	(segment
		(start 52.720494 -77.216)
		(end 55.626 -77.216)
		(width 0.508)
		(layer "F.Cu")
		(net "P12V")
	)
	(segment
		(start 55.626 -77.216)
		(end 56.619394 -76.222606)
		(width 0.508)
		(layer "F.Cu")
		(net "P12V")
	)
	(via
		(at 35.179 -78.105)
		(size 0.5588)
		(drill 0.3048)
		(layers "F.Cu" "B.Cu")
		(net "P12V")
	)
	(via
		(at 35.179 -76.073)
		(size 0.5588)
		(drill 0.3048)
		(layers "F.Cu" "B.Cu")
		(net "P12V")
	)
	(via
		(at 75.565 -12.446)
		(size 0.5588)
		(drill 0.3048)
		(layers "F.Cu" "B.Cu")
		(net "P12V")
	)
	(via
		(at 76.073 -11.684)
		(size 0.5588)
		(drill 0.3048)
		(layers "F.Cu" "B.Cu")
		(net "P12V")
	)
	(via
		(at 34.671 -79.121)
		(size 0.7112)
		(drill 0.3556)
		(layers "F.Cu" "B.Cu")
		(net "P12V")
	)
	(via
		(at 36.195 -76.073)
		(size 0.5588)
		(drill 0.3048)
		(layers "F.Cu" "B.Cu")
		(net "P12V")
	)
	(via
		(at 75.057 -13.208)
		(size 0.5588)
		(drill 0.3048)
		(layers "F.Cu" "B.Cu")
		(net "P12V")
	)
	(via
		(at 36.195 -78.105)
		(size 0.5588)
		(drill 0.3048)
		(layers "F.Cu" "B.Cu")
		(net "P12V")
	)
	(via
		(at 35.179 -77.089)
		(size 0.5588)
		(drill 0.3048)
		(layers "F.Cu" "B.Cu")
		(net "P12V")
	)
	(via
		(at 76.073 -13.208)
		(size 0.5588)
		(drill 0.3048)
		(layers "F.Cu" "B.Cu")
		(net "P12V")
	)
	(via
		(at 36.195 -77.089)
		(size 0.5588)
		(drill 0.3048)
		(layers "F.Cu" "B.Cu")
		(net "P12V")
	)
	(via
		(at 76.581 -12.446)
		(size 0.5588)
		(drill 0.3048)
		(layers "F.Cu" "B.Cu")
		(net "P12V")
	)
	(via
		(at 77.089 -11.684)
		(size 0.5588)
		(drill 0.3048)
		(layers "F.Cu" "B.Cu")
		(net "P12V")
	)
	(via
		(at 34.163 -78.105)
		(size 0.5588)
		(drill 0.3048)
		(layers "F.Cu" "B.Cu")
		(net "P12V")
	)
	(via
		(at 56.619394 -72.920606)
		(size 0.5588)
		(drill 0.3048)
		(layers "F.Cu" "B.Cu")
		(net "P12V")
	)
	(segment
		(start 18.463006 -88.392)
		(end 17.541494 -88.392)
		(width 0.508)
		(layer "F.Cu")
		(net "P3V3_PWR")
	)
	(segment
		(start 14.732 -79.931006)
		(end 14.732 -78.915006)
		(width 0.508)
		(layer "F.Cu")
		(net "P3V3_PWR")
	)
	(segment
		(start 18.8595 -87.995506)
		(end 18.463006 -88.392)
		(width 0.508)
		(layer "F.Cu")
		(net "P3V3_PWR")
	)
	(segment
		(start 17.541494 -88.392)
		(end 15.748 -86.598506)
		(width 0.508)
		(layer "F.Cu")
		(net "P3V3_PWR")
	)
	(segment
		(start 18.8595 -87.63)
		(end 18.8595 -87.995506)
		(width 0.508)
		(layer "F.Cu")
		(net "P3V3_PWR")
	)
	(segment
		(start 58.942478 -82.296)
		(end 56.720994 -82.296)
		(width 0.254)
		(layer "F.Cu")
		(net "P3V3_PWR")
	)
	(segment
		(start 55.372 -74.168)
		(end 54.356 -74.168)
		(width 0.254)
		(layer "F.Cu")
		(net "P3V3_PWR")
	)
	(segment
		(start 56.720994 -82.296)
		(end 56.466994 -82.55)
		(width 0.254)
		(layer "F.Cu")
		(net "P3V3_PWR")
	)
	(via
		(at 62.738 -31.454852)
		(size 0.5588)
		(drill 0.3048)
		(layers "F.Cu" "B.Cu")
		(net "P3V3_PWR")
	)
	(via
		(at 62.611 -77.724)
		(size 0.5588)
		(drill 0.3048)
		(layers "F.Cu" "B.Cu")
		(net "P3V3_PWR")
	)
	(via
		(at 63.754 -59.055)
		(size 0.5588)
		(drill 0.3048)
		(layers "F.Cu" "B.Cu")
		(net "P3V3_PWR")
	)
	(via
		(at 30.849824 -73.445116)
		(size 0.508)
		(drill 0.254)
		(layers "F.Cu" "B.Cu")
		(net "P3V3_PWR")
	)
	(via
		(at 17.0307 -85.912706)
		(size 0.7112)
		(drill 0.3556)
		(layers "F.Cu" "B.Cu")
		(net "P3V3_PWR")
	)
	(via
		(at 62.738 -45.085)
		(size 0.5588)
		(drill 0.3048)
		(layers "F.Cu" "B.Cu")
		(net "P3V3_PWR")
	)
	(via
		(at 20.066 -88.392)
		(size 0.5588)
		(drill 0.3048)
		(layers "F.Cu" "B.Cu")
		(net "P3V3_PWR")
	)
	(via
		(at 63.754 -22.479)
		(size 0.508)
		(drill 0.254)
		(layers "F.Cu" "B.Cu")
		(net "P3V3_PWR")
	)
	(via
		(at 62.738 -63.373)
		(size 0.5588)
		(drill 0.3048)
		(layers "F.Cu" "B.Cu")
		(net "P3V3_PWR")
	)
	(via
		(at 62.738 -59.055)
		(size 0.5588)
		(drill 0.3048)
		(layers "F.Cu" "B.Cu")
		(net "P3V3_PWR")
	)
	(via
		(at 56.466994 -82.55)
		(size 0.5588)
		(drill 0.3048)
		(layers "F.Cu" "B.Cu")
		(net "P3V3_PWR")
	)
	(via
		(at 19.685 -85.852)
		(size 0.7112)
		(drill 0.3556)
		(layers "F.Cu" "B.Cu")
		(net "P3V3_PWR")
	)
	(via
		(at 62.738 -46.101)
		(size 0.5588)
		(drill 0.3048)
		(layers "F.Cu" "B.Cu")
		(net "P3V3_PWR")
	)
	(via
		(at 63.754 -35.772852)
		(size 0.5588)
		(drill 0.3048)
		(layers "F.Cu" "B.Cu")
		(net "P3V3_PWR")
	)
	(via
		(at 61.595 -77.724)
		(size 0.5588)
		(drill 0.3048)
		(layers "F.Cu" "B.Cu")
		(net "P3V3_PWR")
	)
	(via
		(at 62.611 -74.676)
		(size 0.5588)
		(drill 0.3048)
		(layers "F.Cu" "B.Cu")
		(net "P3V3_PWR")
	)
	(via
		(at 63.627 -76.708)
		(size 0.5588)
		(drill 0.3048)
		(layers "F.Cu" "B.Cu")
		(net "P3V3_PWR")
	)
	(via
		(at 63.754 -50.038)
		(size 0.508)
		(drill 0.254)
		(layers "F.Cu" "B.Cu")
		(net "P3V3_PWR")
	)
	(via
		(at 63.246 -46.99)
		(size 0.7112)
		(drill 0.3556)
		(layers "F.Cu" "B.Cu")
		(net "P3V3_PWR")
	)
	(via
		(at 62.738 -34.629852)
		(size 0.5588)
		(drill 0.3048)
		(layers "F.Cu" "B.Cu")
		(net "P3V3_PWR")
	)
	(via
		(at 63.754 -60.071)
		(size 0.5588)
		(drill 0.3048)
		(layers "F.Cu" "B.Cu")
		(net "P3V3_PWR")
	)
	(via
		(at 62.738 -35.772852)
		(size 0.5588)
		(drill 0.3048)
		(layers "F.Cu" "B.Cu")
		(net "P3V3_PWR")
	)
	(via
		(at 63.627 -77.724)
		(size 0.5588)
		(drill 0.3048)
		(layers "F.Cu" "B.Cu")
		(net "P3V3_PWR")
	)
	(via
		(at 63.754 -34.629852)
		(size 0.5588)
		(drill 0.3048)
		(layers "F.Cu" "B.Cu")
		(net "P3V3_PWR")
	)
	(via
		(at 20.066 -87.376)
		(size 0.5588)
		(drill 0.3048)
		(layers "F.Cu" "B.Cu")
		(net "P3V3_PWR")
	)
	(via
		(at 62.611 -75.692)
		(size 0.5588)
		(drill 0.3048)
		(layers "F.Cu" "B.Cu")
		(net "P3V3_PWR")
	)
	(via
		(at 61.595 -74.676)
		(size 0.5588)
		(drill 0.3048)
		(layers "F.Cu" "B.Cu")
		(net "P3V3_PWR")
	)
	(via
		(at 66.802 -80.899)
		(size 0.7112)
		(drill 0.3556)
		(layers "F.Cu" "B.Cu")
		(net "P3V3_PWR")
	)
	(via
		(at 63.754 -46.101)
		(size 0.5588)
		(drill 0.3048)
		(layers "F.Cu" "B.Cu")
		(net "P3V3_PWR")
	)
	(via
		(at 61.595 -75.692)
		(size 0.5588)
		(drill 0.3048)
		(layers "F.Cu" "B.Cu")
		(net "P3V3_PWR")
	)
	(via
		(at 62.738 -60.071)
		(size 0.5588)
		(drill 0.3048)
		(layers "F.Cu" "B.Cu")
		(net "P3V3_PWR")
	)
	(via
		(at 63.754 -62.23)
		(size 0.5588)
		(drill 0.3048)
		(layers "F.Cu" "B.Cu")
		(net "P3V3_PWR")
	)
	(via
		(at 63.246 -61.214)
		(size 0.7112)
		(drill 0.3556)
		(layers "F.Cu" "B.Cu")
		(net "P3V3_PWR")
	)
	(via
		(at 62.738 -18.500852)
		(size 0.5588)
		(drill 0.3048)
		(layers "F.Cu" "B.Cu")
		(net "P3V3_PWR")
	)
	(via
		(at 63.627 -74.676)
		(size 0.5588)
		(drill 0.3048)
		(layers "F.Cu" "B.Cu")
		(net "P3V3_PWR")
	)
	(via
		(at 63.754 -17.484852)
		(size 0.5588)
		(drill 0.3048)
		(layers "F.Cu" "B.Cu")
		(net "P3V3_PWR")
	)
	(via
		(at 55.372 -74.168)
		(size 0.5588)
		(drill 0.3048)
		(layers "F.Cu" "B.Cu")
		(net "P3V3_PWR")
	)
	(via
		(at 63.627 -75.692)
		(size 0.5588)
		(drill 0.3048)
		(layers "F.Cu" "B.Cu")
		(net "P3V3_PWR")
	)
	(via
		(at 62.611 -76.708)
		(size 0.5588)
		(drill 0.3048)
		(layers "F.Cu" "B.Cu")
		(net "P3V3_PWR")
	)
	(via
		(at 14.732 -78.915006)
		(size 0.5588)
		(drill 0.3048)
		(layers "F.Cu" "B.Cu")
		(net "P3V3_PWR")
	)
	(via
		(at 63.754 -18.500852)
		(size 0.5588)
		(drill 0.3048)
		(layers "F.Cu" "B.Cu")
		(net "P3V3_PWR")
	)
	(via
		(at 61.595 -76.708)
		(size 0.5588)
		(drill 0.3048)
		(layers "F.Cu" "B.Cu")
		(net "P3V3_PWR")
	)
	(via
		(at 63.246 -16.51)
		(size 0.7112)
		(drill 0.3556)
		(layers "F.Cu" "B.Cu")
		(net "P3V3_PWR")
	)
	(via
		(at 63.754 -45.085)
		(size 0.5588)
		(drill 0.3048)
		(layers "F.Cu" "B.Cu")
		(net "P3V3_PWR")
	)
	(via
		(at 63.754 -32.470852)
		(size 0.5588)
		(drill 0.3048)
		(layers "F.Cu" "B.Cu")
		(net "P3V3_PWR")
	)
	(via
		(at 62.738 -62.23)
		(size 0.5588)
		(drill 0.3048)
		(layers "F.Cu" "B.Cu")
		(net "P3V3_PWR")
	)
	(via
		(at 63.754 -63.373)
		(size 0.5588)
		(drill 0.3048)
		(layers "F.Cu" "B.Cu")
		(net "P3V3_PWR")
	)
	(via
		(at 63.246 -33.655)
		(size 0.7112)
		(drill 0.3556)
		(layers "F.Cu" "B.Cu")
		(net "P3V3_PWR")
	)
	(via
		(at 63.754 -31.454852)
		(size 0.5588)
		(drill 0.3048)
		(layers "F.Cu" "B.Cu")
		(net "P3V3_PWR")
	)
	(via
		(at 62.738 -17.484852)
		(size 0.5588)
		(drill 0.3048)
		(layers "F.Cu" "B.Cu")
		(net "P3V3_PWR")
	)
	(via
		(at 62.738 -32.470852)
		(size 0.5588)
		(drill 0.3048)
		(layers "F.Cu" "B.Cu")
		(net "P3V3_PWR")
	)
	(segment
		(start 28.073604 -74.422)
		(end 27.768804 -74.1172)
		(width 0.508)
		(layer "B.Cu")
		(net "P3V3_PWR")
	)
	(segment
		(start 64.7065 -22.479)
		(end 63.754 -22.479)
		(width 0.508)
		(layer "B.Cu")
		(net "P3V3_PWR")
	)
	(segment
		(start 30.4165 -74.422)
		(end 28.073604 -74.422)
		(width 0.508)
		(layer "B.Cu")
		(net "P3V3_PWR")
	)
	(segment
		(start 27.768804 -74.1172)
		(end 27.095196 -74.1172)
		(width 0.508)
		(layer "B.Cu")
		(net "P3V3_PWR")
	)
	(segment
		(start 58.039 -74.168)
		(end 61.595 -77.724)
		(width 0.254)
		(layer "B.Cu")
		(net "P3V3_PWR")
	)
	(segment
		(start 55.372 -74.168)
		(end 58.039 -74.168)
		(width 0.254)
		(layer "B.Cu")
		(net "P3V3_PWR")
	)
	(segment
		(start 30.849824 -73.445116)
		(end 30.4165 -73.87844)
		(width 0.508)
		(layer "B.Cu")
		(net "P3V3_PWR")
	)
	(segment
		(start 64.7065 -50.038)
		(end 63.754 -50.038)
		(width 0.508)
		(layer "B.Cu")
		(net "P3V3_PWR")
	)
	(segment
		(start 26.091896 -75.1205)
		(end 25.4 -75.1205)
		(width 0.508)
		(layer "B.Cu")
		(net "P3V3_PWR")
	)
	(segment
		(start 56.466994 -78.1685)
		(end 56.466994 -82.55)
		(width 0.254)
		(layer "B.Cu")
		(net "P3V3_PWR")
	)
	(segment
		(start 30.4165 -73.87844)
		(end 30.4165 -74.422)
		(width 0.508)
		(layer "B.Cu")
		(net "P3V3_PWR")
	)
	(segment
		(start 27.095196 -74.1172)
		(end 26.091896 -75.1205)
		(width 0.508)
		(layer "B.Cu")
		(net "P3V3_PWR")
	)
	(segment
		(start 25.647396 -82.042)
		(end 22.992588 -82.042)
		(width 0.508)
		(layer "In5.Cu")
		(net "P3V3_PWR")
	)
	(segment
		(start 26.625804 -82.3468)
		(end 25.952196 -82.3468)
		(width 0.508)
		(layer "In5.Cu")
		(net "P3V3_PWR")
	)
	(segment
		(start 27.8892 -79.559404)
		(end 27.8892 -81.083404)
		(width 0.508)
		(layer "In5.Cu")
		(net "P3V3_PWR")
	)
	(segment
		(start 30.849824 -73.445116)
		(end 28.2448 -76.05014)
		(width 0.508)
		(layer "In5.Cu")
		(net "P3V3_PWR")
	)
	(segment
		(start 28.2448 -76.05014)
		(end 28.2448 -79.203804)
		(width 0.508)
		(layer "In5.Cu")
		(net "P3V3_PWR")
	)
	(segment
		(start 28.2448 -79.203804)
		(end 27.8892 -79.559404)
		(width 0.508)
		(layer "In5.Cu")
		(net "P3V3_PWR")
	)
	(segment
		(start 20.066 -84.968588)
		(end 20.066 -87.376)
		(width 0.508)
		(layer "In5.Cu")
		(net "P3V3_PWR")
	)
	(segment
		(start 20.066 -87.376)
		(end 20.066 -88.392)
		(width 0.508)
		(layer "In5.Cu")
		(net "P3V3_PWR")
	)
	(segment
		(start 27.8892 -81.083404)
		(end 26.625804 -82.3468)
		(width 0.508)
		(layer "In5.Cu")
		(net "P3V3_PWR")
	)
	(segment
		(start 22.992588 -82.042)
		(end 20.066 -84.968588)
		(width 0.508)
		(layer "In5.Cu")
		(net "P3V3_PWR")
	)
	(segment
		(start 25.952196 -82.3468)
		(end 25.647396 -82.042)
		(width 0.508)
		(layer "In5.Cu")
		(net "P3V3_PWR")
	)
	(via
		(at 69.7865 -35.687)
		(size 0.7112)
		(drill 0.3556)
		(layers "F.Cu" "B.Cu")
		(net "Z50_SSD_B_ACT#")
	)
	(segment
		(start 67.345052 -42.008552)
		(end 69.09943 -42.008552)
		(width 0.12065)
		(layer "B.Cu")
		(net "Z50_SSD_B_ACT#")
	)
	(segment
		(start 69.469 -41.638982)
		(end 69.469 -41.2115)
		(width 0.12065)
		(layer "B.Cu")
		(net "Z50_SSD_B_ACT#")
	)
	(segment
		(start 67.088512 -41.8465)
		(end 66.487548 -41.245536)
		(width 0.12065)
		(layer "B.Cu")
		(net "Z50_SSD_B_ACT#")
	)
	(segment
		(start 66.487548 -41.245536)
		(end 66.487548 -38.637464)
		(width 0.12065)
		(layer "B.Cu")
		(net "Z50_SSD_B_ACT#")
	)
	(segment
		(start 66.894964 -38.230048)
		(end 67.243452 -38.230048)
		(width 0.12065)
		(layer "B.Cu")
		(net "Z50_SSD_B_ACT#")
	)
	(segment
		(start 66.487548 -38.637464)
		(end 66.894964 -38.230048)
		(width 0.12065)
		(layer "B.Cu")
		(net "Z50_SSD_B_ACT#")
	)
	(segment
		(start 67.243452 -38.230048)
		(end 69.7865 -35.687)
		(width 0.12065)
		(layer "B.Cu")
		(net "Z50_SSD_B_ACT#")
	)
	(segment
		(start 69.7865 -33.401)
		(end 69.7865 -34.417)
		(width 0.12065)
		(layer "B.Cu")
		(net "Z50_SSD_B_ACT#")
	)
	(segment
		(start 67.183 -41.8465)
		(end 67.088512 -41.8465)
		(width 0.12065)
		(layer "B.Cu")
		(net "Z50_SSD_B_ACT#")
	)
	(segment
		(start 67.183 -41.8465)
		(end 67.345052 -42.008552)
		(width 0.12065)
		(layer "B.Cu")
		(net "Z50_SSD_B_ACT#")
	)
	(segment
		(start 69.09943 -42.008552)
		(end 69.469 -41.638982)
		(width 0.12065)
		(layer "B.Cu")
		(net "Z50_SSD_B_ACT#")
	)
	(segment
		(start 69.7865 -34.417)
		(end 69.7865 -35.687)
		(width 0.12065)
		(layer "B.Cu")
		(net "Z50_SSD_B_ACT#")
	)
	(via
		(at 72.304148 -43.18)
		(size 0.7112)
		(drill 0.3556)
		(layers "F.Cu" "B.Cu")
		(net "Z50_SSD_A_ACT#")
	)
	(segment
		(start 72.042782 -41.150794)
		(end 72.450452 -41.558464)
		(width 0.12065)
		(layer "B.Cu")
		(net "Z50_SSD_A_ACT#")
	)
	(segment
		(start 69.18833 -40.414448)
		(end 71.211948 -40.414448)
		(width 0.12065)
		(layer "B.Cu")
		(net "Z50_SSD_A_ACT#")
	)
	(segment
		(start 72.304148 -42.281094)
		(end 72.304148 -43.18)
		(width 0.12065)
		(layer "B.Cu")
		(net "Z50_SSD_A_ACT#")
	)
	(segment
		(start 72.304148 -56.537352)
		(end 68.707 -60.1345)
		(width 0.12065)
		(layer "B.Cu")
		(net "Z50_SSD_A_ACT#")
	)
	(segment
		(start 72.304148 -43.18)
		(end 72.304148 -56.537352)
		(width 0.12065)
		(layer "B.Cu")
		(net "Z50_SSD_A_ACT#")
	)
	(segment
		(start 71.211948 -40.414448)
		(end 71.755 -40.9575)
		(width 0.12065)
		(layer "B.Cu")
		(net "Z50_SSD_A_ACT#")
	)
	(segment
		(start 72.450452 -42.13479)
		(end 72.304148 -42.281094)
		(width 0.12065)
		(layer "B.Cu")
		(net "Z50_SSD_A_ACT#")
	)
	(segment
		(start 68.707 -60.1345)
		(end 67.691 -60.1345)
		(width 0.12065)
		(layer "B.Cu")
		(net "Z50_SSD_A_ACT#")
	)
	(segment
		(start 71.755 -40.9575)
		(end 71.948294 -41.150794)
		(width 0.12065)
		(layer "B.Cu")
		(net "Z50_SSD_A_ACT#")
	)
	(segment
		(start 68.81876 -40.784018)
		(end 69.18833 -40.414448)
		(width 0.12065)
		(layer "B.Cu")
		(net "Z50_SSD_A_ACT#")
	)
	(segment
		(start 72.450452 -41.558464)
		(end 72.450452 -42.13479)
		(width 0.12065)
		(layer "B.Cu")
		(net "Z50_SSD_A_ACT#")
	)
	(segment
		(start 68.81876 -41.2115)
		(end 68.81876 -40.784018)
		(width 0.12065)
		(layer "B.Cu")
		(net "Z50_SSD_A_ACT#")
	)
	(segment
		(start 71.948294 -41.150794)
		(end 72.042782 -41.150794)
		(width 0.12065)
		(layer "B.Cu")
		(net "Z50_SSD_A_ACT#")
	)
	(segment
		(start 77.343 -31.45028)
		(end 77.343 -30.226)
		(width 0.12065)
		(layer "F.Cu")
		(net "Z50_DEV_RST#")
	)
	(segment
		(start 66.802 -51.04003)
		(end 68.707 -49.13503)
		(width 0.12065)
		(layer "F.Cu")
		(net "Z50_DEV_RST#")
	)
	(segment
		(start 68.615052 -35.849052)
		(end 67.952112 -35.186112)
		(width 0.12065)
		(layer "F.Cu")
		(net "Z50_DEV_RST#")
	)
	(segment
		(start 68.707 -42.533316)
		(end 67.488308 -41.314624)
		(width 0.12065)
		(layer "F.Cu")
		(net "Z50_DEV_RST#")
	)
	(segment
		(start 68.23964 -24.247094)
		(end 68.534788 -24.247094)
		(width 0.12065)
		(layer "F.Cu")
		(net "Z50_DEV_RST#")
	)
	(segment
		(start 68.534788 -24.247094)
		(end 69.342 -23.439882)
		(width 0.12065)
		(layer "F.Cu")
		(net "Z50_DEV_RST#")
	)
	(segment
		(start 77.343 -30.226)
		(end 75.057 -27.94)
		(width 0.12065)
		(layer "F.Cu")
		(net "Z50_DEV_RST#")
	)
	(segment
		(start 67.488308 -41.314624)
		(end 67.488308 -40.585644)
		(width 0.12065)
		(layer "F.Cu")
		(net "Z50_DEV_RST#")
	)
	(segment
		(start 67.952112 -35.186112)
		(end 67.952112 -24.534622)
		(width 0.12065)
		(layer "F.Cu")
		(net "Z50_DEV_RST#")
	)
	(segment
		(start 65.174876 -23.439882)
		(end 69.342 -23.439882)
		(width 0.12065)
		(layer "F.Cu")
		(net "Z50_DEV_RST#")
	)
	(segment
		(start 68.615052 -39.4589)
		(end 68.615052 -35.849052)
		(width 0.12065)
		(layer "F.Cu")
		(net "Z50_DEV_RST#")
	)
	(segment
		(start 65.174876 -51.04003)
		(end 66.802 -51.04003)
		(width 0.12065)
		(layer "F.Cu")
		(net "Z50_DEV_RST#")
	)
	(segment
		(start 67.952112 -24.534622)
		(end 68.23964 -24.247094)
		(width 0.12065)
		(layer "F.Cu")
		(net "Z50_DEV_RST#")
	)
	(segment
		(start 67.488308 -40.585644)
		(end 68.615052 -39.4589)
		(width 0.12065)
		(layer "F.Cu")
		(net "Z50_DEV_RST#")
	)
	(segment
		(start 68.707 -49.13503)
		(end 68.707 -42.533316)
		(width 0.12065)
		(layer "F.Cu")
		(net "Z50_DEV_RST#")
	)
	(via
		(at 75.057 -27.94)
		(size 0.5588)
		(drill 0.3048)
		(layers "F.Cu" "B.Cu")
		(net "Z50_DEV_RST#")
	)
	(via
		(at 69.342 -23.439882)
		(size 0.5588)
		(drill 0.3048)
		(layers "F.Cu" "B.Cu")
		(net "Z50_DEV_RST#")
	)
	(via
		(at 77.343 -31.45028)
		(size 0.5588)
		(drill 0.3048)
		(layers "F.Cu" "B.Cu")
		(net "Z50_DEV_RST#")
	)
	(via
		(at 72.136 -27.277568)
		(size 0.7112)
		(drill 0.3556)
		(layers "F.Cu" "B.Cu")
		(net "Z50_DEV_RST#")
	)
	(segment
		(start 69.342 -23.439882)
		(end 72.136 -26.233882)
		(width 0.12065)
		(layer "B.Cu")
		(net "Z50_DEV_RST#")
	)
	(segment
		(start 78.142846 -32.250126)
		(end 77.343 -31.45028)
		(width 0.12065)
		(layer "B.Cu")
		(net "Z50_DEV_RST#")
	)
	(segment
		(start 72.136 -27.277568)
		(end 74.394568 -27.277568)
		(width 0.12065)
		(layer "B.Cu")
		(net "Z50_DEV_RST#")
	)
	(segment
		(start 78.769972 -32.250126)
		(end 78.142846 -32.250126)
		(width 0.12065)
		(layer "B.Cu")
		(net "Z50_DEV_RST#")
	)
	(segment
		(start 74.394568 -27.277568)
		(end 75.057 -27.94)
		(width 0.12065)
		(layer "B.Cu")
		(net "Z50_DEV_RST#")
	)
	(segment
		(start 72.136 -26.233882)
		(end 72.136 -27.277568)
		(width 0.12065)
		(layer "B.Cu")
		(net "Z50_DEV_RST#")
	)
	(segment
		(start 77.343 -31.45028)
		(end 78.769972 -31.45028)
		(width 0.12065)
		(layer "B.Cu")
		(net "Z50_DEV_RST#")
	)
	(segment
		(start 64.008 -39.37)
		(end 63.44412 -39.93388)
		(width 0.12065)
		(layer "F.Cu")
		(net "Z50_TEMP_1_CLK")
	)
	(segment
		(start 63.44412 -39.93388)
		(end 62.63386 -39.93388)
		(width 0.12065)
		(layer "F.Cu")
		(net "Z50_TEMP_1_CLK")
	)
	(via
		(at 64.897 -38.989)
		(size 0.7112)
		(drill 0.3556)
		(layers "F.Cu" "B.Cu")
		(net "Z50_TEMP_1_CLK")
	)
	(via
		(at 64.008 -39.37)
		(size 0.508)
		(drill 0.254)
		(layers "F.Cu" "B.Cu")
		(net "Z50_TEMP_1_CLK")
	)
	(segment
		(start 63.924942 -39.453058)
		(end 64.008 -39.37)
		(width 0.12065)
		(layer "B.Cu")
		(net "Z50_TEMP_1_CLK")
	)
	(segment
		(start 63.1825 -39.751)
		(end 63.480442 -39.453058)
		(width 0.12065)
		(layer "B.Cu")
		(net "Z50_TEMP_1_CLK")
	)
	(segment
		(start 63.480442 -39.453058)
		(end 63.924942 -39.453058)
		(width 0.12065)
		(layer "B.Cu")
		(net "Z50_TEMP_1_CLK")
	)
	(segment
		(start 64.897 -38.989)
		(end 64.389 -38.989)
		(width 0.12065)
		(layer "B.Cu")
		(net "Z50_TEMP_1_CLK")
	)
	(segment
		(start 64.389 -38.989)
		(end 64.008 -39.37)
		(width 0.12065)
		(layer "B.Cu")
		(net "Z50_TEMP_1_CLK")
	)
	(segment
		(start 63.20536 -39.28364)
		(end 62.63386 -39.28364)
		(width 0.12065)
		(layer "F.Cu")
		(net "Z50_TEMP_1_DATA")
	)
	(segment
		(start 64.008 -38.481)
		(end 63.20536 -39.28364)
		(width 0.12065)
		(layer "F.Cu")
		(net "Z50_TEMP_1_DATA")
	)
	(via
		(at 64.008 -38.481)
		(size 0.508)
		(drill 0.254)
		(layers "F.Cu" "B.Cu")
		(net "Z50_TEMP_1_DATA")
	)
	(via
		(at 64.643 -37.719)
		(size 0.7112)
		(drill 0.3556)
		(layers "F.Cu" "B.Cu")
		(net "Z50_TEMP_1_DATA")
	)
	(segment
		(start 63.754 -38.735)
		(end 64.008 -38.481)
		(width 0.12065)
		(layer "B.Cu")
		(net "Z50_TEMP_1_DATA")
	)
	(segment
		(start 64.643 -37.719)
		(end 64.643 -37.846)
		(width 0.12065)
		(layer "B.Cu")
		(net "Z50_TEMP_1_DATA")
	)
	(segment
		(start 64.643 -37.846)
		(end 64.008 -38.481)
		(width 0.12065)
		(layer "B.Cu")
		(net "Z50_TEMP_1_DATA")
	)
	(segment
		(start 63.1825 -38.735)
		(end 63.754 -38.735)
		(width 0.12065)
		(layer "B.Cu")
		(net "Z50_TEMP_1_DATA")
	)
	(segment
		(start 76.327 -15.187676)
		(end 78.337918 -13.176758)
		(width 0.12065)
		(layer "F.Cu")
		(net "Z50_SMB_CLK")
	)
	(segment
		(start 78.337918 -13.176758)
		(end 82.31378 -13.176758)
		(width 0.12065)
		(layer "F.Cu")
		(net "Z50_SMB_CLK")
	)
	(segment
		(start 28.55976 -85.10524)
		(end 28.702 -84.963)
		(width 0.12065)
		(layer "F.Cu")
		(net "Z50_SMB_CLK")
	)
	(segment
		(start 82.31378 -13.176758)
		(end 82.611976 -13.474954)
		(width 0.12065)
		(layer "F.Cu")
		(net "Z50_SMB_CLK")
	)
	(segment
		(start 28.55976 -86.941406)
		(end 28.55976 -85.10524)
		(width 0.12065)
		(layer "F.Cu")
		(net "Z50_SMB_CLK")
	)
	(segment
		(start 76.327 -15.494)
		(end 76.327 -15.187676)
		(width 0.12065)
		(layer "F.Cu")
		(net "Z50_SMB_CLK")
	)
	(via
		(at 28.702 -84.963)
		(size 0.508)
		(drill 0.254)
		(layers "F.Cu" "B.Cu")
		(net "Z50_SMB_CLK")
	)
	(via
		(at 30.6705 -82.434176)
		(size 0.7112)
		(drill 0.3556)
		(layers "F.Cu" "B.Cu")
		(net "Z50_SMB_CLK")
	)
	(via
		(at 82.611976 -13.474954)
		(size 0.508)
		(drill 0.254)
		(layers "F.Cu" "B.Cu")
		(net "Z50_SMB_CLK")
	)
	(via
		(at 76.327 -15.494)
		(size 0.5588)
		(drill 0.3048)
		(layers "F.Cu" "B.Cu")
		(net "Z50_SMB_CLK")
	)
	(segment
		(start 32.50565 -80.585818)
		(end 32.50565 -80.599026)
		(width 0.12065)
		(layer "B.Cu")
		(net "Z50_SMB_CLK")
	)
	(segment
		(start 62.2935 -41.0845)
		(end 67.948302 -46.739302)
		(width 0.12065)
		(layer "B.Cu")
		(net "Z50_SMB_CLK")
	)
	(segment
		(start 28.829 -85.7885)
		(end 28.702 -85.6615)
		(width 0.12065)
		(layer "B.Cu")
		(net "Z50_SMB_CLK")
	)
	(segment
		(start 55.56504 -70.614794)
		(end 35.364674 -70.614794)
		(width 0.12065)
		(layer "B.Cu")
		(net "Z50_SMB_CLK")
	)
	(segment
		(start 65.90665 -28.896818)
		(end 67.922902 -26.880566)
		(width 0.12065)
		(layer "B.Cu")
		(net "Z50_SMB_CLK")
	)
	(segment
		(start 33.125156 -72.854312)
		(end 33.125156 -73.362312)
		(width 0.12065)
		(layer "B.Cu")
		(net "Z50_SMB_CLK")
	)
	(segment
		(start 32.37865 -79.307182)
		(end 32.616902 -79.545434)
		(width 0.12065)
		(layer "B.Cu")
		(net "Z50_SMB_CLK")
	)
	(segment
		(start 32.37865 -75.32497)
		(end 32.37865 -79.307182)
		(width 0.12065)
		(layer "B.Cu")
		(net "Z50_SMB_CLK")
	)
	(segment
		(start 28.702 -84.402676)
		(end 30.6705 -82.434176)
		(width 0.12065)
		(layer "B.Cu")
		(net "Z50_SMB_CLK")
	)
	(segment
		(start 32.559752 -73.927716)
		(end 32.559752 -75.143868)
		(width 0.12065)
		(layer "B.Cu")
		(net "Z50_SMB_CLK")
	)
	(segment
		(start 33.125156 -73.362312)
		(end 32.559752 -73.927716)
		(width 0.12065)
		(layer "B.Cu")
		(net "Z50_SMB_CLK")
	)
	(segment
		(start 32.50565 -80.599026)
		(end 30.6705 -82.434176)
		(width 0.12065)
		(layer "B.Cu")
		(net "Z50_SMB_CLK")
	)
	(segment
		(start 67.948302 -54.414166)
		(end 65.166748 -57.19572)
		(width 0.12065)
		(layer "B.Cu")
		(net "Z50_SMB_CLK")
	)
	(segment
		(start 67.922902 -26.880566)
		(end 67.922902 -23.898098)
		(width 0.12065)
		(layer "B.Cu")
		(net "Z50_SMB_CLK")
	)
	(segment
		(start 64.91605 -39.989252)
		(end 65.617852 -39.28745)
		(width 0.12065)
		(layer "B.Cu")
		(net "Z50_SMB_CLK")
	)
	(segment
		(start 32.616902 -79.545434)
		(end 32.616902 -80.474566)
		(width 0.12065)
		(layer "B.Cu")
		(net "Z50_SMB_CLK")
	)
	(segment
		(start 63.72098 -67.186302)
		(end 58.993532 -67.186302)
		(width 0.12065)
		(layer "B.Cu")
		(net "Z50_SMB_CLK")
	)
	(segment
		(start 62.79515 -40.25265)
		(end 63.646558 -40.25265)
		(width 0.12065)
		(layer "B.Cu")
		(net "Z50_SMB_CLK")
	)
	(segment
		(start 35.364674 -70.614794)
		(end 33.125156 -72.854312)
		(width 0.12065)
		(layer "B.Cu")
		(net "Z50_SMB_CLK")
	)
	(segment
		(start 63.646558 -40.25265)
		(end 63.909956 -39.989252)
		(width 0.12065)
		(layer "B.Cu")
		(net "Z50_SMB_CLK")
	)
	(segment
		(start 65.617852 -36.120324)
		(end 65.90665 -35.831526)
		(width 0.12065)
		(layer "B.Cu")
		(net "Z50_SMB_CLK")
	)
	(segment
		(start 67.948302 -46.739302)
		(end 67.948302 -54.414166)
		(width 0.12065)
		(layer "B.Cu")
		(net "Z50_SMB_CLK")
	)
	(segment
		(start 32.559752 -75.143868)
		(end 32.37865 -75.32497)
		(width 0.12065)
		(layer "B.Cu")
		(net "Z50_SMB_CLK")
	)
	(segment
		(start 63.909956 -39.989252)
		(end 64.91605 -39.989252)
		(width 0.12065)
		(layer "B.Cu")
		(net "Z50_SMB_CLK")
	)
	(segment
		(start 67.922902 -23.898098)
		(end 76.327 -15.494)
		(width 0.12065)
		(layer "B.Cu")
		(net "Z50_SMB_CLK")
	)
	(segment
		(start 62.2935 -39.751)
		(end 62.79515 -40.25265)
		(width 0.12065)
		(layer "B.Cu")
		(net "Z50_SMB_CLK")
	)
	(segment
		(start 28.702 -85.6615)
		(end 28.702 -84.963)
		(width 0.12065)
		(layer "B.Cu")
		(net "Z50_SMB_CLK")
	)
	(segment
		(start 65.90665 -35.831526)
		(end 65.90665 -28.896818)
		(width 0.12065)
		(layer "B.Cu")
		(net "Z50_SMB_CLK")
	)
	(segment
		(start 58.993532 -67.186302)
		(end 55.56504 -70.614794)
		(width 0.12065)
		(layer "B.Cu")
		(net "Z50_SMB_CLK")
	)
	(segment
		(start 65.617852 -39.28745)
		(end 65.617852 -36.120324)
		(width 0.12065)
		(layer "B.Cu")
		(net "Z50_SMB_CLK")
	)
	(segment
		(start 65.166748 -57.19572)
		(end 65.166748 -65.740534)
		(width 0.12065)
		(layer "B.Cu")
		(net "Z50_SMB_CLK")
	)
	(segment
		(start 62.2935 -39.751)
		(end 62.2935 -41.0845)
		(width 0.12065)
		(layer "B.Cu")
		(net "Z50_SMB_CLK")
	)
	(segment
		(start 65.166748 -65.740534)
		(end 63.72098 -67.186302)
		(width 0.12065)
		(layer "B.Cu")
		(net "Z50_SMB_CLK")
	)
	(segment
		(start 32.616902 -80.474566)
		(end 32.50565 -80.585818)
		(width 0.12065)
		(layer "B.Cu")
		(net "Z50_SMB_CLK")
	)
	(segment
		(start 28.702 -84.963)
		(end 28.702 -84.402676)
		(width 0.12065)
		(layer "B.Cu")
		(net "Z50_SMB_CLK")
	)
	(segment
		(start 81.380076 -13.474954)
		(end 82.611976 -13.474954)
		(width 0.12065)
		(layer "B.Cu")
		(net "Z50_SMB_CLK")
	)
	(segment
		(start 78.129892 -12.675108)
		(end 75.311 -15.494)
		(width 0.12065)
		(layer "F.Cu")
		(net "Z50_SMB_DATA")
	)
	(segment
		(start 82.611976 -12.675108)
		(end 78.129892 -12.675108)
		(width 0.12065)
		(layer "F.Cu")
		(net "Z50_SMB_DATA")
	)
	(segment
		(start 27.90952 -85.05952)
		(end 27.813 -84.963)
		(width 0.12065)
		(layer "F.Cu")
		(net "Z50_SMB_DATA")
	)
	(segment
		(start 27.90952 -86.941406)
		(end 27.90952 -85.05952)
		(width 0.12065)
		(layer "F.Cu")
		(net "Z50_SMB_DATA")
	)
	(via
		(at 82.611976 -12.675108)
		(size 0.508)
		(drill 0.254)
		(layers "F.Cu" "B.Cu")
		(net "Z50_SMB_DATA")
	)
	(via
		(at 75.311 -15.494)
		(size 0.5588)
		(drill 0.3048)
		(layers "F.Cu" "B.Cu")
		(net "Z50_SMB_DATA")
	)
	(via
		(at 27.813 -84.963)
		(size 0.508)
		(drill 0.254)
		(layers "F.Cu" "B.Cu")
		(net "Z50_SMB_DATA")
	)
	(via
		(at 27.813 -83.947)
		(size 0.7112)
		(drill 0.3556)
		(layers "F.Cu" "B.Cu")
		(net "Z50_SMB_DATA")
	)
	(segment
		(start 31.877 -79.515208)
		(end 31.877 -74.642218)
		(width 0.12065)
		(layer "B.Cu")
		(net "Z50_SMB_DATA")
	)
	(segment
		(start 67.446652 -46.947328)
		(end 61.79185 -41.292526)
		(width 0.12065)
		(layer "B.Cu")
		(net "Z50_SMB_DATA")
	)
	(segment
		(start 27.813 -84.963)
		(end 27.813 -85.6615)
		(width 0.12065)
		(layer "B.Cu")
		(net "Z50_SMB_DATA")
	)
	(segment
		(start 67.421252 -23.383748)
		(end 67.421252 -26.67254)
		(width 0.12065)
		(layer "B.Cu")
		(net "Z50_SMB_DATA")
	)
	(segment
		(start 67.446652 -54.20614)
		(end 67.446652 -46.947328)
		(width 0.12065)
		(layer "B.Cu")
		(net "Z50_SMB_DATA")
	)
	(segment
		(start 32.004 -80.377792)
		(end 32.115252 -80.26654)
		(width 0.12065)
		(layer "B.Cu")
		(net "Z50_SMB_DATA")
	)
	(segment
		(start 32.115252 -80.26654)
		(end 32.115252 -79.75346)
		(width 0.12065)
		(layer "B.Cu")
		(net "Z50_SMB_DATA")
	)
	(segment
		(start 32.623252 -72.64654)
		(end 35.156648 -70.113144)
		(width 0.12065)
		(layer "B.Cu")
		(net "Z50_SMB_DATA")
	)
	(segment
		(start 65.405 -28.688792)
		(end 65.405 -35.6235)
		(width 0.12065)
		(layer "B.Cu")
		(net "Z50_SMB_DATA")
	)
	(segment
		(start 65.405 -35.6235)
		(end 62.2935 -38.735)
		(width 0.12065)
		(layer "B.Cu")
		(net "Z50_SMB_DATA")
	)
	(segment
		(start 64.665098 -65.532508)
		(end 64.665098 -56.987694)
		(width 0.12065)
		(layer "B.Cu")
		(net "Z50_SMB_DATA")
	)
	(segment
		(start 67.421252 -26.67254)
		(end 65.405 -28.688792)
		(width 0.12065)
		(layer "B.Cu")
		(net "Z50_SMB_DATA")
	)
	(segment
		(start 58.785506 -66.684652)
		(end 63.512954 -66.684652)
		(width 0.12065)
		(layer "B.Cu")
		(net "Z50_SMB_DATA")
	)
	(segment
		(start 61.79185 -39.23665)
		(end 62.2935 -38.735)
		(width 0.12065)
		(layer "B.Cu")
		(net "Z50_SMB_DATA")
	)
	(segment
		(start 30.681676 -81.713324)
		(end 32.004 -80.391)
		(width 0.12065)
		(layer "B.Cu")
		(net "Z50_SMB_DATA")
	)
	(segment
		(start 27.813 -85.6615)
		(end 27.686 -85.7885)
		(width 0.12065)
		(layer "B.Cu")
		(net "Z50_SMB_DATA")
	)
	(segment
		(start 32.058102 -74.461116)
		(end 32.058102 -73.71969)
		(width 0.12065)
		(layer "B.Cu")
		(net "Z50_SMB_DATA")
	)
	(segment
		(start 32.623252 -73.15454)
		(end 32.623252 -72.64654)
		(width 0.12065)
		(layer "B.Cu")
		(net "Z50_SMB_DATA")
	)
	(segment
		(start 32.058102 -73.71969)
		(end 32.623252 -73.15454)
		(width 0.12065)
		(layer "B.Cu")
		(net "Z50_SMB_DATA")
	)
	(segment
		(start 27.813 -83.947)
		(end 27.813 -84.963)
		(width 0.12065)
		(layer "B.Cu")
		(net "Z50_SMB_DATA")
	)
	(segment
		(start 63.512954 -66.684652)
		(end 64.665098 -65.532508)
		(width 0.12065)
		(layer "B.Cu")
		(net "Z50_SMB_DATA")
	)
	(segment
		(start 32.004 -80.391)
		(end 32.004 -80.377792)
		(width 0.12065)
		(layer "B.Cu")
		(net "Z50_SMB_DATA")
	)
	(segment
		(start 27.813 -83.947)
		(end 30.046676 -81.713324)
		(width 0.12065)
		(layer "B.Cu")
		(net "Z50_SMB_DATA")
	)
	(segment
		(start 64.665098 -56.987694)
		(end 67.446652 -54.20614)
		(width 0.12065)
		(layer "B.Cu")
		(net "Z50_SMB_DATA")
	)
	(segment
		(start 81.380076 -12.675108)
		(end 82.611976 -12.675108)
		(width 0.12065)
		(layer "B.Cu")
		(net "Z50_SMB_DATA")
	)
	(segment
		(start 35.156648 -70.113144)
		(end 55.357014 -70.113144)
		(width 0.12065)
		(layer "B.Cu")
		(net "Z50_SMB_DATA")
	)
	(segment
		(start 55.357014 -70.113144)
		(end 58.785506 -66.684652)
		(width 0.12065)
		(layer "B.Cu")
		(net "Z50_SMB_DATA")
	)
	(segment
		(start 61.79185 -41.292526)
		(end 61.79185 -39.23665)
		(width 0.12065)
		(layer "B.Cu")
		(net "Z50_SMB_DATA")
	)
	(segment
		(start 32.115252 -79.75346)
		(end 31.877 -79.515208)
		(width 0.12065)
		(layer "B.Cu")
		(net "Z50_SMB_DATA")
	)
	(segment
		(start 31.877 -74.642218)
		(end 32.058102 -74.461116)
		(width 0.12065)
		(layer "B.Cu")
		(net "Z50_SMB_DATA")
	)
	(segment
		(start 75.311 -15.494)
		(end 67.421252 -23.383748)
		(width 0.12065)
		(layer "B.Cu")
		(net "Z50_SMB_DATA")
	)
	(segment
		(start 30.046676 -81.713324)
		(end 30.681676 -81.713324)
		(width 0.12065)
		(layer "B.Cu")
		(net "Z50_SMB_DATA")
	)
	(segment
		(start 75.184 -34.4805)
		(end 74.6125 -34.4805)
		(width 0.12065)
		(layer "F.Cu")
		(net "Z50_SSD_B_PRSNT#")
	)
	(segment
		(start 74.422 -32.997394)
		(end 75.008994 -32.4104)
		(width 0.12065)
		(layer "F.Cu")
		(net "Z50_SSD_B_PRSNT#")
	)
	(segment
		(start 75.184 -35.4965)
		(end 75.184 -34.4805)
		(width 0.12065)
		(layer "F.Cu")
		(net "Z50_SSD_B_PRSNT#")
	)
	(segment
		(start 75.692 -40.386)
		(end 75.311 -40.005)
		(width 0.12065)
		(layer "F.Cu")
		(net "Z50_SSD_B_PRSNT#")
	)
	(segment
		(start 75.692 -39.1795)
		(end 75.311 -39.5605)
		(width 0.12065)
		(layer "F.Cu")
		(net "Z50_SSD_B_PRSNT#")
	)
	(segment
		(start 75.692 -41.2115)
		(end 75.692 -40.386)
		(width 0.12065)
		(layer "F.Cu")
		(net "Z50_SSD_B_PRSNT#")
	)
	(segment
		(start 74.6125 -34.4805)
		(end 74.422 -34.29)
		(width 0.12065)
		(layer "F.Cu")
		(net "Z50_SSD_B_PRSNT#")
	)
	(segment
		(start 74.422 -34.29)
		(end 74.422 -32.997394)
		(width 0.12065)
		(layer "F.Cu")
		(net "Z50_SSD_B_PRSNT#")
	)
	(segment
		(start 75.311 -39.5605)
		(end 75.311 -40.005)
		(width 0.12065)
		(layer "F.Cu")
		(net "Z50_SSD_B_PRSNT#")
	)
	(via
		(at 75.008994 -31.369)
		(size 0.7112)
		(drill 0.3556)
		(layers "F.Cu" "B.Cu")
		(net "Z50_SSD_B_PRSNT#")
	)
	(via
		(at 75.311 -40.005)
		(size 0.508)
		(drill 0.254)
		(layers "F.Cu" "B.Cu")
		(net "Z50_SSD_B_PRSNT#")
	)
	(via
		(at 75.008994 -32.4104)
		(size 0.5588)
		(drill 0.3048)
		(layers "F.Cu" "B.Cu")
		(net "Z50_SSD_B_PRSNT#")
	)
	(segment
		(start 74.88555 -32.533844)
		(end 74.88555 -39.57955)
		(width 0.12065)
		(layer "B.Cu")
		(net "Z50_SSD_B_PRSNT#")
	)
	(segment
		(start 75.008994 -31.369)
		(end 75.008994 -32.4104)
		(width 0.12065)
		(layer "B.Cu")
		(net "Z50_SSD_B_PRSNT#")
	)
	(segment
		(start 74.88555 -39.57955)
		(end 75.311 -40.005)
		(width 0.12065)
		(layer "B.Cu")
		(net "Z50_SSD_B_PRSNT#")
	)
	(segment
		(start 75.008994 -32.4104)
		(end 74.88555 -32.533844)
		(width 0.12065)
		(layer "B.Cu")
		(net "Z50_SSD_B_PRSNT#")
	)
	(segment
		(start 74.676 -40.84574)
		(end 74.676 -39.1795)
		(width 0.12065)
		(layer "F.Cu")
		(net "Z50_SSD_A_PRSNT#")
	)
	(segment
		(start 75.7555 -63.246)
		(end 75.7555 -62.23)
		(width 0.12065)
		(layer "F.Cu")
		(net "Z50_SSD_A_PRSNT#")
	)
	(segment
		(start 75.04176 -41.2115)
		(end 74.676 -40.84574)
		(width 0.12065)
		(layer "F.Cu")
		(net "Z50_SSD_A_PRSNT#")
	)
	(segment
		(start 73.787 -39.1795)
		(end 74.676 -39.1795)
		(width 0.12065)
		(layer "F.Cu")
		(net "Z50_SSD_A_PRSNT#")
	)
	(segment
		(start 75.7555 -62.23)
		(end 76.634594 -62.23)
		(width 0.12065)
		(layer "F.Cu")
		(net "Z50_SSD_A_PRSNT#")
	)
	(via
		(at 73.787 -39.1795)
		(size 0.508)
		(drill 0.254)
		(layers "F.Cu" "B.Cu")
		(net "Z50_SSD_A_PRSNT#")
	)
	(via
		(at 73.025 -47.371)
		(size 0.7112)
		(drill 0.3556)
		(layers "F.Cu" "B.Cu")
		(net "Z50_SSD_A_PRSNT#")
	)
	(via
		(at 76.634594 -62.23)
		(size 0.5588)
		(drill 0.3048)
		(layers "F.Cu" "B.Cu")
		(net "Z50_SSD_A_PRSNT#")
	)
	(segment
		(start 73.025 -61.349382)
		(end 73.025 -47.371)
		(width 0.12065)
		(layer "B.Cu")
		(net "Z50_SSD_A_PRSNT#")
	)
	(segment
		(start 73.025 -42.394632)
		(end 73.787 -41.632632)
		(width 0.12065)
		(layer "B.Cu")
		(net "Z50_SSD_A_PRSNT#")
	)
	(segment
		(start 73.025 -47.371)
		(end 73.025 -42.394632)
		(width 0.12065)
		(layer "B.Cu")
		(net "Z50_SSD_A_PRSNT#")
	)
	(segment
		(start 76.634594 -62.23)
		(end 73.905618 -62.23)
		(width 0.12065)
		(layer "B.Cu")
		(net "Z50_SSD_A_PRSNT#")
	)
	(segment
		(start 73.905618 -62.23)
		(end 73.025 -61.349382)
		(width 0.12065)
		(layer "B.Cu")
		(net "Z50_SSD_A_PRSNT#")
	)
	(segment
		(start 73.787 -41.632632)
		(end 73.787 -39.1795)
		(width 0.12065)
		(layer "B.Cu")
		(net "Z50_SSD_A_PRSNT#")
	)
	(zone
		(layer "F.Cu")
		(hatch none 0.5)
		(connect_pads
			(clearance 0)
		)
		(min_thickness 0.25)
		(keepout
			(tracks allowed)
			(vias allowed)
			(pads allowed)
			(copperpour allowed)
			(footprints not_allowed)
		)
		(placement
			(enabled no)
			(sheetname "")
		)
		(fill
			(thermal_gap 0.5)
			(thermal_bridge_width 0.5)
			(island_removal_mode 0)
		)
		(polygon
			(pts
				(arc
					(start 73.000108 -86.03488)
					(mid 74.775314 -87.810086)
					(end 73.000108 -89.585038)
				)
				(arc
					(start 73.000108 -89.585038)
					(mid 71.225156 -87.810086)
					(end 73.000108 -86.03488)
				)
			)
		)
	)
	(zone
		(layer "F.Cu")
		(hatch none 0.5)
		(connect_pads
			(clearance 0)
		)
		(min_thickness 0.25)
		(keepout
			(tracks not_allowed)
			(vias allowed)
			(pads allowed)
			(copperpour not_allowed)
			(footprints allowed)
		)
		(placement
			(enabled no)
			(sheetname "")
		)
		(fill
			(thermal_gap 0.5)
			(thermal_bridge_width 0.5)
			(island_removal_mode 0)
		)
		(polygon
			(pts
				(arc
					(start 69.97954 -24.8666)
					(mid 69.367527 -24.254206)
					(end 68.75526 -24.866346)
				)
				(arc
					(start 68.75526 -25.983946)
					(mid 69.3674 -26.596086)
					(end 69.97954 -25.983946)
				)
				(xy 69.97954 -25.66797)
				(arc
					(start 69.977 -25.66797)
					(mid 69.811646 -25.700843)
					(end 69.671438 -25.794462)
				)
				(arc
					(start 69.604382 -25.861518)
					(mid 69.178788 -26.172558)
					(end 69.489828 -25.746964)
				)
				(xy 69.55663 -25.679908) (xy 69.556884 -25.679908) (xy 69.580506 -25.656286)
				(arc
					(start 69.581776 -25.656286)
					(mid 69.749497 -25.551121)
					(end 69.942456 -25.506934)
				)
				(xy 69.943472 -25.505918) (xy 69.97954 -25.505918) (xy 69.97954 -25.373838) (xy 69.943472 -25.373838)
				(arc
					(start 69.942202 -25.372568)
					(mid 69.776699 -25.333948)
					(end 69.632322 -25.244298)
				)
				(xy 69.630798 -25.244298) (xy 69.607176 -25.220676) (xy 69.606922 -25.220676)
				(arc
					(start 69.489828 -25.103328)
					(mid 69.178788 -24.677734)
					(end 69.604382 -24.988774)
				)
				(arc
					(start 69.72173 -25.106122)
					(mid 69.838863 -25.184325)
					(end 69.977 -25.211786)
				)
				(xy 69.97954 -25.211786)
			)
		)
	)
	(zone
		(net "P1V8_PWR")
		(layer "F.Cu")
		(hatch none 0.5)
		(connect_pads
			(clearance 0.5)
		)
		(min_thickness 0.25)
		(fill yes
			(thermal_gap 0.5)
			(thermal_bridge_width 0.5)
			(island_removal_mode 0)
		)
		(polygon
			(pts
				(xy 17.78 -71.803006) (xy 17.653 -71.930006) (xy 17.653 -77.216) (xy 18.415 -77.978) (xy 18.415 -78.915006)
				(xy 18.416524 -78.916276) (xy 18.416524 -79.020924) (xy 18.4912 -79.0956) (xy 20.012406 -79.0956)
				(xy 20.193 -78.915006) (xy 20.193 -71.930006) (xy 20.066 -71.803006)
			)
		)
		(polygon
			(pts
				(xy 18.415 -77.060806) (xy 18.161 -77.060806) (xy 18.161 -77.314806) (xy 18.415 -77.314806)
			)
		)
		(polygon
			(pts
				(xy 18.415 -76.451206) (xy 18.161 -76.451206) (xy 18.161 -76.705206) (xy 18.415 -76.705206)
			)
		)
		(polygon
			(pts
				(xy 18.3642 -76.019406) (xy 18.1102 -76.019406) (xy 18.1102 -76.273406) (xy 18.3642 -76.273406)
			)
		)
		(polygon
			(pts
				(xy 18.3642 -75.460606) (xy 18.1102 -75.460606) (xy 18.1102 -75.714606) (xy 18.3642 -75.714606)
			)
		)
	)
	(zone
		(layer "F.Cu")
		(hatch none 0.5)
		(connect_pads
			(clearance 0)
		)
		(min_thickness 0.25)
		(keepout
			(tracks allowed)
			(vias allowed)
			(pads allowed)
			(copperpour allowed)
			(footprints not_allowed)
		)
		(placement
			(enabled no)
			(sheetname "")
		)
		(fill
			(thermal_gap 0.5)
			(thermal_bridge_width 0.5)
			(island_removal_mode 0)
		)
		(polygon
			(pts
				(xy 54.85003 -42.29989) (xy 54.85003 -65.79997) (xy 67.69989 -65.79997) (xy 67.69989 -42.29989)
			)
		)
	)
	(zone
		(layer "F.Cu")
		(hatch none 0.5)
		(connect_pads
			(clearance 0)
		)
		(min_thickness 0.25)
		(keepout
			(tracks allowed)
			(vias allowed)
			(pads allowed)
			(copperpour allowed)
			(footprints allowed)
		)
		(placement
			(enabled no)
			(sheetname "")
		)
		(fill
			(thermal_gap 0.5)
			(thermal_bridge_width 0.5)
			(island_removal_mode 0)
		)
		(polygon
			(pts
				(xy 64.262 -19.177) (xy 64.262 -18.161) (xy 66.04 -18.161) (xy 66.04 -19.177)
			)
		)
	)
	(zone
		(layer "F.Cu")
		(hatch none 0.5)
		(connect_pads
			(clearance 0)
		)
		(min_thickness 0.25)
		(keepout
			(tracks not_allowed)
			(vias allowed)
			(pads allowed)
			(copperpour not_allowed)
			(footprints allowed)
		)
		(placement
			(enabled no)
			(sheetname "")
		)
		(fill
			(thermal_gap 0.5)
			(thermal_bridge_width 0.5)
			(island_removal_mode 0)
		)
		(polygon
			(pts
				(arc
					(start 69.97954 -24.87676)
					(mid 69.367527 -24.264366)
					(end 68.75526 -24.876506)
				)
				(arc
					(start 68.75526 -25.994106)
					(mid 69.3674 -26.606246)
					(end 69.97954 -25.994106)
				)
				(xy 69.97954 -25.67813)
				(arc
					(start 69.977 -25.67813)
					(mid 69.811646 -25.711003)
					(end 69.671438 -25.804622)
				)
				(arc
					(start 69.604382 -25.871678)
					(mid 69.178788 -26.182718)
					(end 69.489828 -25.757124)
				)
				(xy 69.55663 -25.690068) (xy 69.556884 -25.690068) (xy 69.580506 -25.666446)
				(arc
					(start 69.581776 -25.666446)
					(mid 69.749497 -25.561281)
					(end 69.942456 -25.517094)
				)
				(xy 69.943472 -25.516078) (xy 69.97954 -25.516078) (xy 69.97954 -25.383998) (xy 69.943472 -25.383998)
				(arc
					(start 69.942202 -25.382728)
					(mid 69.776699 -25.344108)
					(end 69.632322 -25.254458)
				)
				(xy 69.630798 -25.254458) (xy 69.607176 -25.230836) (xy 69.606922 -25.230836)
				(arc
					(start 69.489828 -25.113488)
					(mid 69.178788 -24.687894)
					(end 69.604382 -24.998934)
				)
				(arc
					(start 69.72173 -25.116282)
					(mid 69.838863 -25.194485)
					(end 69.977 -25.221946)
				)
				(xy 69.97954 -25.221946)
			)
		)
	)
	(zone
		(layer "F.Cu")
		(hatch none 0.5)
		(connect_pads
			(clearance 0)
		)
		(min_thickness 0.25)
		(keepout
			(tracks allowed)
			(vias allowed)
			(pads allowed)
			(copperpour allowed)
			(footprints allowed)
		)
		(placement
			(enabled no)
			(sheetname "")
		)
		(fill
			(thermal_gap 0.5)
			(thermal_bridge_width 0.5)
			(island_removal_mode 0)
		)
		(polygon
			(pts
				(xy 16.764 -82.55) (xy 17.78 -82.55) (xy 17.78 -84.074) (xy 18.542 -84.074) (xy 18.542 -82.55) (xy 19.431 -82.55)
				(xy 20.066 -82.55) (xy 20.447 -82.55) (xy 20.701 -82.55) (xy 20.701 -78.105) (xy 20.32 -78.105)
				(xy 20.066 -78.105) (xy 19.431 -78.105) (xy 18.415 -78.105) (xy 18.415 -76.581) (xy 16.764 -76.581)
			)
		)
	)
	(zone
		(layer "F.Cu")
		(hatch none 0.5)
		(connect_pads
			(clearance 0)
		)
		(min_thickness 0.25)
		(keepout
			(tracks allowed)
			(vias allowed)
			(pads allowed)
			(copperpour allowed)
			(footprints allowed)
		)
		(placement
			(enabled no)
			(sheetname "")
		)
		(fill
			(thermal_gap 0.5)
			(thermal_bridge_width 0.5)
			(island_removal_mode 0)
		)
		(polygon
			(pts
				(xy 52.910994 -75.819) (xy 57.355994 -75.819) (xy 57.355994 -77.597) (xy 52.910994 -77.597) (xy 52.783994 -77.597)
				(xy 52.783994 -75.819)
			)
		)
	)
	(zone
		(layer "F.Cu")
		(hatch none 0.5)
		(connect_pads
			(clearance 0)
		)
		(min_thickness 0.25)
		(keepout
			(tracks allowed)
			(vias allowed)
			(pads allowed)
			(copperpour allowed)
			(footprints allowed)
		)
		(placement
			(enabled no)
			(sheetname "")
		)
		(fill
			(thermal_gap 0.5)
			(thermal_bridge_width 0.5)
			(island_removal_mode 0)
		)
		(polygon
			(pts
				(xy 72.009 -63.5) (xy 73.533 -63.5) (xy 73.533 -62.484) (xy 72.009 -62.484) (xy 71.882 -62.484)
				(xy 71.882 -63.5)
			)
		)
	)
	(zone
		(layer "F.Cu")
		(hatch none 0.5)
		(connect_pads
			(clearance 0)
		)
		(min_thickness 0.25)
		(keepout
			(tracks not_allowed)
			(vias allowed)
			(pads allowed)
			(copperpour not_allowed)
			(footprints allowed)
		)
		(placement
			(enabled no)
			(sheetname "")
		)
		(fill
			(thermal_gap 0.5)
			(thermal_bridge_width 0.5)
			(island_removal_mode 0)
		)
		(polygon
			(pts
				(arc
					(start 82.995516 -22.275292)
					(mid 82.612103 -21.891498)
					(end 82.228436 -22.275038)
				)
				(arc
					(start 82.228436 -22.44217)
					(mid 82.302289 -22.422622)
					(end 82.370676 -22.388576)
				)
				(arc
					(start 82.370676 -22.388576)
					(mid 82.806589 -22.092713)
					(end 82.482944 -22.508464)
				)
				(arc
					(start 82.482944 -22.508464)
					(mid 82.361929 -22.573426)
					(end 82.228436 -22.605746)
				)
				(arc
					(start 82.228436 -22.74443)
					(mid 82.361933 -22.776741)
					(end 82.482944 -22.841712)
				)
				(arc
					(start 82.482944 -22.841712)
					(mid 82.806617 -23.257489)
					(end 82.370676 -22.9616)
				)
				(arc
					(start 82.370676 -22.9616)
					(mid 82.302277 -22.927587)
					(end 82.228436 -22.908006)
				)
				(arc
					(start 82.228436 -23.075138)
					(mid 82.611976 -23.458678)
					(end 82.995516 -23.075138)
				)
			)
		)
	)
	(zone
		(net "P3V3_PWR")
		(layer "F.Cu")
		(hatch none 0.5)
		(connect_pads
			(clearance 0.5)
		)
		(min_thickness 0.25)
		(fill yes
			(thermal_gap 0.5)
			(thermal_bridge_width 0.5)
			(island_removal_mode 0)
		)
		(polygon
			(pts
				(xy 60.071 -44.196) (xy 59.944 -44.323) (xy 59.944 -64.389) (xy 60.071 -64.516) (xy 65.786 -64.516)
				(xy 65.913 -64.389) (xy 65.913 -44.323) (xy 65.786 -44.196)
			)
		)
		(polygon
			(pts
				(xy 63.6778 -63.754) (xy 63.4238 -63.754) (xy 63.4238 -64.008) (xy 63.6778 -64.008)
			)
		)
		(polygon
			(pts
				(xy 63.0682 -63.754) (xy 62.8142 -63.754) (xy 62.8142 -64.008) (xy 63.0682 -64.008)
			)
		)
		(polygon
			(pts
				(xy 60.706 -62.9158) (xy 60.452 -62.9158) (xy 60.452 -63.1698) (xy 60.706 -63.1698)
			)
		)
		(polygon
			(pts
				(xy 60.706 -62.3062) (xy 60.452 -62.3062) (xy 60.452 -62.5602) (xy 60.706 -62.5602)
			)
		)
		(polygon
			(pts
				(xy 60.706 -61.8998) (xy 60.452 -61.8998) (xy 60.452 -62.1538) (xy 60.706 -62.1538)
			)
		)
		(polygon
			(pts
				(xy 60.706 -61.2902) (xy 60.452 -61.2902) (xy 60.452 -61.5442) (xy 60.706 -61.5442)
			)
		)
		(polygon
			(pts
				(xy 60.706 -60.7568) (xy 60.452 -60.7568) (xy 60.452 -61.0108) (xy 60.706 -61.0108)
			)
		)
		(polygon
			(pts
				(xy 60.706 -60.1472) (xy 60.452 -60.1472) (xy 60.452 -60.4012) (xy 60.706 -60.4012)
			)
		)
		(polygon
			(pts
				(xy 60.706 -59.7408) (xy 60.452 -59.7408) (xy 60.452 -59.9948) (xy 60.706 -59.9948)
			)
		)
		(polygon
			(pts
				(xy 60.706 -59.1312) (xy 60.452 -59.1312) (xy 60.452 -59.3852) (xy 60.706 -59.3852)
			)
		)
		(polygon
			(pts
				(xy 60.706 -58.7248) (xy 60.452 -58.7248) (xy 60.452 -58.9788) (xy 60.706 -58.9788)
			)
		)
		(polygon
			(pts
				(xy 60.706 -58.1152) (xy 60.452 -58.1152) (xy 60.452 -58.3692) (xy 60.706 -58.3692)
			)
		)
		(polygon
			(pts
				(xy 60.706 -46.7868) (xy 60.452 -46.7868) (xy 60.452 -47.0408) (xy 60.706 -47.0408)
			)
		)
		(polygon
			(pts
				(xy 60.706 -46.1772) (xy 60.452 -46.1772) (xy 60.452 -46.4312) (xy 60.706 -46.4312)
			)
		)
		(polygon
			(pts
				(xy 60.706 -45.7708) (xy 60.452 -45.7708) (xy 60.452 -46.0248) (xy 60.706 -46.0248)
			)
		)
		(polygon
			(pts
				(xy 60.706 -45.1612) (xy 60.452 -45.1612) (xy 60.452 -45.4152) (xy 60.706 -45.4152)
			)
		)
		(polygon
			(pts
				(xy 60.706 -44.7548) (xy 60.452 -44.7548) (xy 60.452 -45.0088) (xy 60.706 -45.0088)
			)
		)
	)
	(zone
		(layer "F.Cu")
		(hatch none 0.5)
		(connect_pads
			(clearance 0)
		)
		(min_thickness 0.25)
		(keepout
			(tracks allowed)
			(vias allowed)
			(pads allowed)
			(copperpour allowed)
			(footprints allowed)
		)
		(placement
			(enabled no)
			(sheetname "")
		)
		(fill
			(thermal_gap 0.5)
			(thermal_bridge_width 0.5)
			(island_removal_mode 0)
		)
		(polygon
			(pts
				(xy 24.257 -78.359) (xy 24.257 -73.279) (xy 27.559 -73.279) (xy 27.559 -78.359)
			)
		)
	)
	(zone
		(layer "F.Cu")
		(hatch none 0.5)
		(connect_pads
			(clearance 0)
		)
		(min_thickness 0.25)
		(keepout
			(tracks allowed)
			(vias allowed)
			(pads allowed)
			(copperpour allowed)
			(footprints not_allowed)
		)
		(placement
			(enabled no)
			(sheetname "")
		)
		(fill
			(thermal_gap 0.5)
			(thermal_bridge_width 0.5)
			(island_removal_mode 0)
		)
		(polygon
			(pts
				(arc
					(start 52.850034 -67.55003)
					(mid 54.264245 -66.964245)
					(end 54.85003 -65.550034)
				)
				(xy 54.85003 -65.79997) (xy 67.69989 -65.79997) (xy 67.69989 -65.300098) (xy 73.200006 -65.300098)
				(xy 73.200006 -67.55003)
			)
		)
	)
	(zone
		(layer "F.Cu")
		(hatch none 0.5)
		(connect_pads
			(clearance 0)
		)
		(min_thickness 0.25)
		(keepout
			(tracks allowed)
			(vias allowed)
			(pads allowed)
			(copperpour allowed)
			(footprints allowed)
		)
		(placement
			(enabled no)
			(sheetname "")
		)
		(fill
			(thermal_gap 0.5)
			(thermal_bridge_width 0.5)
			(island_removal_mode 0)
		)
		(polygon
			(pts
				(xy 64.262 -63.286894) (xy 64.262 -62.270894) (xy 64.262 -58.841894) (xy 64.262 -58.333894) (xy 66.04 -58.333894)
				(xy 66.04 -58.841894) (xy 66.04 -62.270894) (xy 66.04 -63.286894)
			)
		)
	)
	(zone
		(net "GND")
		(layer "F.Cu")
		(hatch none 0.5)
		(connect_pads
			(clearance 0.5)
		)
		(min_thickness 0.25)
		(fill yes
			(thermal_gap 0.5)
			(thermal_bridge_width 0.5)
			(island_removal_mode 0)
		)
		(polygon
			(pts
				(xy 20.828 -71.628) (xy 20.701 -71.755) (xy 20.701 -77.343) (xy 20.828 -77.47) (xy 20.828 -84.836)
				(xy 20.955 -84.963) (xy 22.86 -84.963) (xy 22.987 -84.836) (xy 22.987 -71.755) (xy 22.86 -71.628)
			)
		)
	)
	(zone
		(layer "F.Cu")
		(hatch none 0.5)
		(connect_pads
			(clearance 0)
		)
		(min_thickness 0.25)
		(keepout
			(tracks not_allowed)
			(vias allowed)
			(pads allowed)
			(copperpour not_allowed)
			(footprints allowed)
		)
		(placement
			(enabled no)
			(sheetname "")
		)
		(fill
			(thermal_gap 0.5)
			(thermal_bridge_width 0.5)
			(island_removal_mode 0)
		)
		(polygon
			(pts
				(arc
					(start 69.97954 -52.4764)
					(mid 69.3674 -51.86426)
					(end 68.75526 -52.4764)
				)
				(arc
					(start 68.75526 -53.593746)
					(mid 69.367273 -54.20614)
					(end 69.97954 -53.594)
				)
				(xy 69.97954 -53.278024)
				(arc
					(start 69.977 -53.278024)
					(mid 69.811646 -53.310897)
					(end 69.671438 -53.404516)
				)
				(xy 69.671438 -53.40477)
				(arc
					(start 69.604382 -53.471572)
					(mid 69.178788 -53.782612)
					(end 69.489828 -53.357018)
				)
				(xy 69.55663 -53.289962) (xy 69.556884 -53.289962) (xy 69.580506 -53.26634)
				(arc
					(start 69.581776 -53.26634)
					(mid 69.749497 -53.161175)
					(end 69.942456 -53.116988)
				)
				(xy 69.943472 -53.115972) (xy 69.97954 -53.115972) (xy 69.97954 -52.983892) (xy 69.943472 -52.983892)
				(arc
					(start 69.942202 -52.982622)
					(mid 69.776699 -52.944002)
					(end 69.632322 -52.854352)
				)
				(xy 69.630798 -52.854352) (xy 69.607176 -52.83073) (xy 69.606922 -52.83073)
				(arc
					(start 69.489828 -52.713382)
					(mid 69.178788 -52.287788)
					(end 69.604382 -52.598828)
				)
				(xy 69.72173 -52.715922)
				(arc
					(start 69.72173 -52.716176)
					(mid 69.838863 -52.794379)
					(end 69.977 -52.82184)
				)
				(xy 69.97954 -52.82184)
			)
		)
	)
	(zone
		(net "GND")
		(layer "F.Cu")
		(hatch none 0.5)
		(connect_pads
			(clearance 0.5)
		)
		(min_thickness 0.25)
		(fill yes
			(thermal_gap 0.5)
			(thermal_bridge_width 0.5)
			(island_removal_mode 0)
		)
		(polygon
			(pts
				(xy 56.642 -0.508) (xy 55.372 -1.778) (xy 55.372 -66.548) (xy 53.848 -68.072) (xy 1.778 -68.072)
				(xy 0.508 -69.342) (xy 0.508 -90.424) (xy 1.905 -91.821) (xy 86.741 -91.821) (xy 88.265 -90.297)
				(xy 88.265 -70.993) (xy 88.138 -70.866) (xy 85.852 -70.866) (xy 85.217 -70.231) (xy 85.217 -55.372)
				(xy 85.852 -54.737) (xy 88.138 -54.737) (xy 88.265 -54.61) (xy 88.265 -49.911) (xy 88.138 -49.784)
				(xy 81.153 -49.784) (xy 80.518 -49.149) (xy 80.518 -45.339) (xy 80.391 -45.212) (xy 78.74 -45.212)
				(xy 78.359 -45.593) (xy 78.359 -48.895) (xy 80.391 -50.927) (xy 80.391 -54.991) (xy 79.502 -55.88)
				(xy 78.486 -55.88) (xy 78.359 -56.007) (xy 78.359 -60.579) (xy 76.962 -61.976) (xy 76.962 -63.5)
				(xy 76.708 -63.754) (xy 70.231 -63.754) (xy 68.199 -65.786) (xy 59.69 -65.786) (xy 59.563 -65.659)
				(xy 59.563 -44.069) (xy 57.404 -41.91) (xy 57.404 -38.354) (xy 57.531 -38.227) (xy 59.309 -38.227)
				(xy 59.563 -37.973) (xy 59.563 -16.129) (xy 60.833 -14.859) (xy 67.056 -14.859) (xy 70.612 -18.415)
				(xy 73.914 -18.415) (xy 74.041 -18.288) (xy 74.041 -14.986) (xy 74.168 -14.859) (xy 76.708 -14.859)
				(xy 80.518 -11.049) (xy 80.518 -5.842) (xy 81.026 -5.334) (xy 88.011 -5.334) (xy 88.138 -5.207)
				(xy 88.138 -0.635) (xy 88.011 -0.508)
			)
		)
		(polygon
			(pts
				(xy 43.6118 -85.725) (xy 43.3578 -85.725) (xy 43.3578 -85.979) (xy 43.6118 -85.979)
			)
		)
		(polygon
			(pts
				(xy 42.7482 -85.725) (xy 42.4942 -85.725) (xy 42.4942 -85.979) (xy 42.7482 -85.979)
			)
		)
		(polygon
			(pts
				(xy 33.4518 -73.66) (xy 33.1978 -73.66) (xy 33.1978 -73.914) (xy 33.4518 -73.914)
			)
		)
		(polygon
			(pts
				(xy 29.845 -68.834) (xy 19.812 -68.834) (xy 12.7 -75.946) (xy 12.7 -87.122) (xy 14.859 -89.281)
				(xy 33.274 -89.281) (xy 34.544 -88.011) (xy 34.544 -84.963) (xy 34.671 -84.836) (xy 45.339 -84.836)
				(xy 45.72 -84.455) (xy 45.72 -77.978) (xy 45.847 -77.851) (xy 48.641 -77.851) (xy 48.768 -77.978)
				(xy 48.768 -85.979) (xy 48.641 -86.106) (xy 47.117 -86.106) (xy 46.99 -86.233) (xy 46.99 -88.138)
				(xy 47.244 -88.392) (xy 49.657 -88.392) (xy 49.911 -88.138) (xy 59.817 -88.138) (xy 59.944 -88.011)
				(xy 59.944 -85.09) (xy 60.071 -84.963) (xy 65.659 -84.963) (xy 66.04 -84.582) (xy 66.04 -73.66)
				(xy 65.786 -73.406) (xy 52.324 -73.406) (xy 51.816 -73.914) (xy 41.148 -73.914) (xy 38.735 -76.327)
				(xy 38.735 -77.089) (xy 40.132 -78.486) (xy 40.132 -79.883) (xy 40.005 -80.01) (xy 36.703 -80.01)
				(xy 36.576 -79.883) (xy 36.576 -78.74) (xy 36.83 -78.486) (xy 36.83 -75.819) (xy 35.433 -74.422)
				(xy 32.766 -74.422) (xy 32.639 -74.295) (xy 32.639 -73.66) (xy 30.734 -71.755) (xy 30.734 -69.723)
			)
		)
		(polygon
			(pts
				(xy 59.182 -62.9158) (xy 58.928 -62.9158) (xy 58.928 -63.1698) (xy 59.182 -63.1698)
			)
		)
		(polygon
			(pts
				(xy 59.182 -62.3062) (xy 58.928 -62.3062) (xy 58.928 -62.5602) (xy 59.182 -62.5602)
			)
		)
		(polygon
			(pts
				(xy 59.182 -61.8998) (xy 58.928 -61.8998) (xy 58.928 -62.1538) (xy 59.182 -62.1538)
			)
		)
		(polygon
			(pts
				(xy 59.182 -61.2902) (xy 58.928 -61.2902) (xy 58.928 -61.5442) (xy 59.182 -61.5442)
			)
		)
		(polygon
			(pts
				(xy 59.182 -60.7568) (xy 58.928 -60.7568) (xy 58.928 -61.0108) (xy 59.182 -61.0108)
			)
		)
		(polygon
			(pts
				(xy 59.182 -60.1472) (xy 58.928 -60.1472) (xy 58.928 -60.4012) (xy 59.182 -60.4012)
			)
		)
		(polygon
			(pts
				(xy 59.182 -59.7408) (xy 58.928 -59.7408) (xy 58.928 -59.9948) (xy 59.182 -59.9948)
			)
		)
		(polygon
			(pts
				(xy 59.182 -59.1312) (xy 58.928 -59.1312) (xy 58.928 -59.3852) (xy 59.182 -59.3852)
			)
		)
		(polygon
			(pts
				(xy 59.182 -58.7248) (xy 58.928 -58.7248) (xy 58.928 -58.9788) (xy 59.182 -58.9788)
			)
		)
		(polygon
			(pts
				(xy 59.182 -58.1152) (xy 58.928 -58.1152) (xy 58.928 -58.3692) (xy 59.182 -58.3692)
			)
		)
		(polygon
			(pts
				(xy 59.182 -46.7868) (xy 58.928 -46.7868) (xy 58.928 -47.0408) (xy 59.182 -47.0408)
			)
		)
		(polygon
			(pts
				(xy 59.182 -46.1772) (xy 58.928 -46.1772) (xy 58.928 -46.4312) (xy 59.182 -46.4312)
			)
		)
		(polygon
			(pts
				(xy 59.182 -45.7708) (xy 58.928 -45.7708) (xy 58.928 -46.0248) (xy 59.182 -46.0248)
			)
		)
		(polygon
			(pts
				(xy 59.182 -45.1612) (xy 58.928 -45.1612) (xy 58.928 -45.4152) (xy 59.182 -45.4152)
			)
		)
		(polygon
			(pts
				(xy 59.182 -44.7548) (xy 58.928 -44.7548) (xy 58.928 -45.0088) (xy 59.182 -45.0088)
			)
		)
		(polygon
			(pts
				(xy 59.182 -44.1452) (xy 58.928 -44.1452) (xy 58.928 -44.3992) (xy 59.182 -44.3992)
			)
		)
		(polygon
			(pts
				(xy 59.182 -35.3568) (xy 58.928 -35.3568) (xy 58.928 -35.6108) (xy 59.182 -35.6108)
			)
		)
		(polygon
			(pts
				(xy 59.182 -34.7472) (xy 58.928 -34.7472) (xy 58.928 -35.0012) (xy 59.182 -35.0012)
			)
		)
		(polygon
			(pts
				(xy 59.182 -34.3408) (xy 58.928 -34.3408) (xy 58.928 -34.5948) (xy 59.182 -34.5948)
			)
		)
		(polygon
			(pts
				(xy 59.182 -33.7312) (xy 58.928 -33.7312) (xy 58.928 -33.9852) (xy 59.182 -33.9852)
			)
		)
		(polygon
			(pts
				(xy 59.182 -33.1978) (xy 58.928 -33.1978) (xy 58.928 -33.4518) (xy 59.182 -33.4518)
			)
		)
		(polygon
			(pts
				(xy 59.182 -32.5882) (xy 58.928 -32.5882) (xy 58.928 -32.8422) (xy 59.182 -32.8422)
			)
		)
		(polygon
			(pts
				(xy 59.182 -32.1818) (xy 58.928 -32.1818) (xy 58.928 -32.4358) (xy 59.182 -32.4358)
			)
		)
		(polygon
			(pts
				(xy 59.182 -31.5722) (xy 58.928 -31.5722) (xy 58.928 -31.8262) (xy 59.182 -31.8262)
			)
		)
		(polygon
			(pts
				(xy 59.182 -31.1658) (xy 58.928 -31.1658) (xy 58.928 -31.4198) (xy 59.182 -31.4198)
			)
		)
		(polygon
			(pts
				(xy 59.182 -30.5562) (xy 58.928 -30.5562) (xy 58.928 -30.8102) (xy 59.182 -30.8102)
			)
		)
		(polygon
			(pts
				(xy 59.182 -19.2278) (xy 58.928 -19.2278) (xy 58.928 -19.4818) (xy 59.182 -19.4818)
			)
		)
		(polygon
			(pts
				(xy 59.182 -18.6182) (xy 58.928 -18.6182) (xy 58.928 -18.8722) (xy 59.182 -18.8722)
			)
		)
		(polygon
			(pts
				(xy 59.182 -18.2118) (xy 58.928 -18.2118) (xy 58.928 -18.4658) (xy 59.182 -18.4658)
			)
		)
		(polygon
			(pts
				(xy 59.182 -17.6022) (xy 58.928 -17.6022) (xy 58.928 -17.8562) (xy 59.182 -17.8562)
			)
		)
		(polygon
			(pts
				(xy 59.182 -17.1958) (xy 58.928 -17.1958) (xy 58.928 -17.4498) (xy 59.182 -17.4498)
			)
		)
		(polygon
			(pts
				(xy 59.182 -16.5862) (xy 58.928 -16.5862) (xy 58.928 -16.8402) (xy 59.182 -16.8402)
			)
		)
	)
	(zone
		(net "GND")
		(layer "F.Cu")
		(hatch none 0.5)
		(connect_pads
			(clearance 0.5)
		)
		(min_thickness 0.25)
		(fill yes
			(thermal_gap 0.5)
			(thermal_bridge_width 0.5)
			(island_removal_mode 0)
		)
		(polygon
			(pts
				(xy 17.907 -84.249006) (xy 17.78 -84.376006) (xy 17.78 -85.773006) (xy 17.907 -85.900006) (xy 18.542 -85.900006)
				(xy 18.669 -85.773006) (xy 18.669 -84.376006) (xy 18.542 -84.249006)
			)
		)
	)
	(zone
		(layer "F.Cu")
		(hatch none 0.5)
		(connect_pads
			(clearance 0)
		)
		(min_thickness 0.25)
		(keepout
			(tracks allowed)
			(vias allowed)
			(pads allowed)
			(copperpour allowed)
			(footprints not_allowed)
		)
		(placement
			(enabled no)
			(sheetname "")
		)
		(fill
			(thermal_gap 0.5)
			(thermal_bridge_width 0.5)
			(island_removal_mode 0)
		)
		(polygon
			(pts
				(arc
					(start 77.0001 -87.810086)
					(mid 73.000108 -91.810078)
					(end 69.000116 -87.810086)
				)
				(arc
					(start 69.000116 -87.810086)
					(mid 73.000108 -83.810094)
					(end 77.0001 -87.810086)
				)
			)
		)
	)
	(zone
		(layer "F.Cu")
		(hatch none 0.5)
		(connect_pads
			(clearance 0)
		)
		(min_thickness 0.25)
		(keepout
			(tracks allowed)
			(vias allowed)
			(pads allowed)
			(copperpour allowed)
			(footprints not_allowed)
		)
		(placement
			(enabled no)
			(sheetname "")
		)
		(fill
			(thermal_gap 0.5)
			(thermal_bridge_width 0.5)
			(island_removal_mode 0)
		)
		(polygon
			(pts
				(arc
					(start 60.200032 -2.724912)
					(mid 61.975238 -4.500118)
					(end 60.200032 -6.27507)
				)
				(arc
					(start 60.200032 -6.27507)
					(mid 58.42508 -4.500118)
					(end 60.200032 -2.724912)
				)
			)
		)
	)
	(zone
		(layer "F.Cu")
		(hatch none 0.5)
		(connect_pads
			(clearance 0)
		)
		(min_thickness 0.25)
		(keepout
			(tracks allowed)
			(vias allowed)
			(pads allowed)
			(copperpour allowed)
			(footprints not_allowed)
		)
		(placement
			(enabled no)
			(sheetname "")
		)
		(fill
			(thermal_gap 0.5)
			(thermal_bridge_width 0.5)
			(island_removal_mode 0)
		)
		(polygon
			(pts
				(arc
					(start 6.500114 -82.084926)
					(mid 4.725162 -80.309974)
					(end 6.500114 -78.535022)
				)
				(arc
					(start 6.500114 -78.535022)
					(mid 8.275066 -80.309974)
					(end 6.500114 -82.084926)
				)
			)
		)
	)
	(zone
		(layer "F.Cu")
		(hatch none 0.5)
		(connect_pads
			(clearance 0)
		)
		(min_thickness 0.25)
		(keepout
			(tracks allowed)
			(vias allowed)
			(pads allowed)
			(copperpour allowed)
			(footprints allowed)
		)
		(placement
			(enabled no)
			(sheetname "")
		)
		(fill
			(thermal_gap 0.5)
			(thermal_bridge_width 0.5)
			(island_removal_mode 0)
		)
		(polygon
			(pts
				(xy 64.262 -46.776894) (xy 64.262 -45.760894) (xy 66.04 -45.760894) (xy 66.04 -46.776894)
			)
		)
	)
	(zone
		(net "P3V3_PWR")
		(layer "F.Cu")
		(hatch none 0.5)
		(connect_pads
			(clearance 0.5)
		)
		(min_thickness 0.25)
		(fill yes
			(thermal_gap 0.5)
			(thermal_bridge_width 0.5)
			(island_removal_mode 0)
		)
		(polygon
			(pts
				(xy 61.468 -74.295) (xy 57.531 -78.232) (xy 57.531 -82.931) (xy 57.658 -83.058) (xy 65.405 -83.058)
				(xy 65.532 -82.931) (xy 65.532 -74.422) (xy 65.405 -74.295)
			)
		)
	)
	(zone
		(layer "F.Cu")
		(hatch none 0.5)
		(connect_pads
			(clearance 0)
		)
		(min_thickness 0.25)
		(keepout
			(tracks not_allowed)
			(vias allowed)
			(pads allowed)
			(copperpour not_allowed)
			(footprints allowed)
		)
		(placement
			(enabled no)
			(sheetname "")
		)
		(fill
			(thermal_gap 0.5)
			(thermal_bridge_width 0.5)
			(island_removal_mode 0)
		)
		(polygon
			(pts
				(arc
					(start 70.48754 -27.876754)
					(mid 69.875527 -27.26436)
					(end 69.26326 -27.8765)
				)
				(arc
					(start 69.26326 -28.9941)
					(mid 69.8754 -29.60624)
					(end 70.48754 -28.9941)
				)
				(xy 70.48754 -28.678124)
				(arc
					(start 70.485 -28.678124)
					(mid 70.319646 -28.710997)
					(end 70.179438 -28.804616)
				)
				(arc
					(start 70.112382 -28.871672)
					(mid 69.686788 -29.182712)
					(end 69.997828 -28.757118)
				)
				(xy 70.06463 -28.690062) (xy 70.064884 -28.690062) (xy 70.088506 -28.66644)
				(arc
					(start 70.089776 -28.66644)
					(mid 70.257497 -28.561275)
					(end 70.450456 -28.517088)
				)
				(xy 70.451472 -28.516072) (xy 70.48754 -28.516072) (xy 70.48754 -28.383992) (xy 70.451472 -28.383992)
				(arc
					(start 70.450202 -28.382722)
					(mid 70.284699 -28.344102)
					(end 70.140322 -28.254452)
				)
				(xy 70.138798 -28.254452) (xy 70.115176 -28.23083) (xy 70.114922 -28.23083)
				(arc
					(start 69.997828 -28.113482)
					(mid 69.686788 -27.687888)
					(end 70.112382 -27.998928)
				)
				(arc
					(start 70.22973 -28.116276)
					(mid 70.346863 -28.194479)
					(end 70.485 -28.22194)
				)
				(xy 70.48754 -28.22194)
			)
		)
	)
	(zone
		(layer "F.Cu")
		(hatch none 0.5)
		(connect_pads
			(clearance 0)
		)
		(min_thickness 0.25)
		(keepout
			(tracks not_allowed)
			(vias allowed)
			(pads allowed)
			(copperpour not_allowed)
			(footprints allowed)
		)
		(placement
			(enabled no)
			(sheetname "")
		)
		(fill
			(thermal_gap 0.5)
			(thermal_bridge_width 0.5)
			(island_removal_mode 0)
		)
		(polygon
			(pts
				(arc
					(start 82.995516 -39.875206)
					(mid 82.612103 -39.491412)
					(end 82.228436 -39.874952)
				)
				(arc
					(start 82.228436 -40.013128)
					(mid 82.295033 -39.989664)
					(end 82.359246 -39.960296)
				)
				(arc
					(start 82.359246 -39.960296)
					(mid 82.826299 -39.716138)
					(end 82.456782 -40.091868)
				)
				(arc
					(start 82.456782 -40.091868)
					(mid 82.345517 -40.143997)
					(end 82.228436 -40.181276)
				)
				(arc
					(start 82.228436 -40.368728)
					(mid 82.345528 -40.40598)
					(end 82.456782 -40.458136)
				)
				(arc
					(start 82.456782 -40.458136)
					(mid 82.826271 -40.833845)
					(end 82.359246 -40.589708)
				)
				(arc
					(start 82.359246 -40.589708)
					(mid 82.295034 -40.560338)
					(end 82.228436 -40.536876)
				)
				(arc
					(start 82.228436 -40.675052)
					(mid 82.611976 -41.058592)
					(end 82.995516 -40.675052)
				)
			)
		)
	)
	(zone
		(net "P3V3_PWR")
		(layer "F.Cu")
		(hatch none 0.5)
		(connect_pads
			(clearance 0.5)
		)
		(min_thickness 0.25)
		(fill yes
			(thermal_gap 0.5)
			(thermal_bridge_width 0.5)
			(island_removal_mode 0)
		)
		(polygon
			(pts
				(xy 60.112148 -16.595852) (xy 59.944 -16.764) (xy 59.944 -36.83) (xy 60.071 -36.957) (xy 65.786 -36.957)
				(xy 65.913 -36.83) (xy 65.913 -16.722852) (xy 65.786 -16.595852)
			)
		)
		(polygon
			(pts
				(xy 63.6778 -36.195) (xy 63.4238 -36.195) (xy 63.4238 -36.449) (xy 63.6778 -36.449)
			)
		)
		(polygon
			(pts
				(xy 63.0682 -36.195) (xy 62.8142 -36.195) (xy 62.8142 -36.449) (xy 63.0682 -36.449)
			)
		)
		(polygon
			(pts
				(xy 60.706 -35.3568) (xy 60.452 -35.3568) (xy 60.452 -35.6108) (xy 60.706 -35.6108)
			)
		)
		(polygon
			(pts
				(xy 60.706 -34.7472) (xy 60.452 -34.7472) (xy 60.452 -35.0012) (xy 60.706 -35.0012)
			)
		)
		(polygon
			(pts
				(xy 60.706 -34.3408) (xy 60.452 -34.3408) (xy 60.452 -34.5948) (xy 60.706 -34.5948)
			)
		)
		(polygon
			(pts
				(xy 60.706 -33.7312) (xy 60.452 -33.7312) (xy 60.452 -33.9852) (xy 60.706 -33.9852)
			)
		)
		(polygon
			(pts
				(xy 60.706 -33.1978) (xy 60.452 -33.1978) (xy 60.452 -33.4518) (xy 60.706 -33.4518)
			)
		)
		(polygon
			(pts
				(xy 60.706 -32.5882) (xy 60.452 -32.5882) (xy 60.452 -32.8422) (xy 60.706 -32.8422)
			)
		)
		(polygon
			(pts
				(xy 60.706 -32.1818) (xy 60.452 -32.1818) (xy 60.452 -32.4358) (xy 60.706 -32.4358)
			)
		)
		(polygon
			(pts
				(xy 60.706 -31.5722) (xy 60.452 -31.5722) (xy 60.452 -31.8262) (xy 60.706 -31.8262)
			)
		)
		(polygon
			(pts
				(xy 60.706 -31.1658) (xy 60.452 -31.1658) (xy 60.452 -31.4198) (xy 60.706 -31.4198)
			)
		)
		(polygon
			(pts
				(xy 60.706 -30.5562) (xy 60.452 -30.5562) (xy 60.452 -30.8102) (xy 60.706 -30.8102)
			)
		)
		(polygon
			(pts
				(xy 60.706 -19.2278) (xy 60.452 -19.2278) (xy 60.452 -19.4818) (xy 60.706 -19.4818)
			)
		)
		(polygon
			(pts
				(xy 60.706 -18.6182) (xy 60.452 -18.6182) (xy 60.452 -18.8722) (xy 60.706 -18.8722)
			)
		)
		(polygon
			(pts
				(xy 60.706 -18.2118) (xy 60.452 -18.2118) (xy 60.452 -18.4658) (xy 60.706 -18.4658)
			)
		)
		(polygon
			(pts
				(xy 60.706 -17.6022) (xy 60.452 -17.6022) (xy 60.452 -17.8562) (xy 60.706 -17.8562)
			)
		)
		(polygon
			(pts
				(xy 60.706 -17.1958) (xy 60.452 -17.1958) (xy 60.452 -17.4498) (xy 60.706 -17.4498)
			)
		)
	)
	(zone
		(layer "F.Cu")
		(hatch none 0.5)
		(connect_pads
			(clearance 0)
		)
		(min_thickness 0.25)
		(keepout
			(tracks not_allowed)
			(vias allowed)
			(pads allowed)
			(copperpour not_allowed)
			(footprints allowed)
		)
		(placement
			(enabled no)
			(sheetname "")
		)
		(fill
			(thermal_gap 0.5)
			(thermal_bridge_width 0.5)
			(island_removal_mode 0)
		)
		(polygon
			(pts
				(arc
					(start 70.48754 -55.466742)
					(mid 69.875527 -54.854348)
					(end 69.26326 -55.466488)
				)
				(arc
					(start 69.26326 -56.584088)
					(mid 69.8754 -57.196228)
					(end 70.48754 -56.584088)
				)
				(xy 70.48754 -56.268112)
				(arc
					(start 70.485 -56.268112)
					(mid 70.319646 -56.300985)
					(end 70.179438 -56.394604)
				)
				(xy 70.179438 -56.394858)
				(arc
					(start 70.112382 -56.46166)
					(mid 69.686788 -56.7727)
					(end 69.997828 -56.347106)
				)
				(xy 70.06463 -56.28005) (xy 70.064884 -56.28005) (xy 70.088506 -56.256428)
				(arc
					(start 70.089776 -56.256428)
					(mid 70.257497 -56.151263)
					(end 70.450456 -56.107076)
				)
				(xy 70.451472 -56.10606) (xy 70.48754 -56.10606) (xy 70.48754 -55.97398) (xy 70.451472 -55.97398)
				(arc
					(start 70.450202 -55.97271)
					(mid 70.284699 -55.93409)
					(end 70.140322 -55.84444)
				)
				(xy 70.138798 -55.84444) (xy 70.115176 -55.820818) (xy 70.114922 -55.820818)
				(arc
					(start 69.997828 -55.70347)
					(mid 69.686788 -55.277876)
					(end 70.112382 -55.588916)
				)
				(xy 70.22973 -55.70601)
				(arc
					(start 70.22973 -55.706264)
					(mid 70.346863 -55.784467)
					(end 70.485 -55.811928)
				)
				(xy 70.48754 -55.811928)
			)
		)
	)
	(zone
		(layer "F.Cu")
		(hatch none 0.5)
		(connect_pads
			(clearance 0)
		)
		(min_thickness 0.25)
		(keepout
			(tracks allowed)
			(vias allowed)
			(pads allowed)
			(copperpour allowed)
			(footprints allowed)
		)
		(placement
			(enabled no)
			(sheetname "")
		)
		(fill
			(thermal_gap 0.5)
			(thermal_bridge_width 0.5)
			(island_removal_mode 0)
		)
		(polygon
			(pts
				(xy 66.802 -24.765) (xy 65.278 -24.765) (xy 65.024 -24.765) (xy 65.024 -26.162) (xy 65.278 -26.162)
				(xy 66.802 -26.162)
			)
		)
	)
	(zone
		(layer "F.Cu")
		(hatch none 0.5)
		(connect_pads
			(clearance 0)
		)
		(min_thickness 0.25)
		(keepout
			(tracks allowed)
			(vias allowed)
			(pads allowed)
			(copperpour allowed)
			(footprints not_allowed)
		)
		(placement
			(enabled no)
			(sheetname "")
		)
		(fill
			(thermal_gap 0.5)
			(thermal_bridge_width 0.5)
			(island_removal_mode 0)
		)
		(polygon
			(pts
				(xy 54.85003 -14.699996) (xy 54.85003 -38.200076) (xy 67.69989 -38.200076) (xy 67.69989 -14.699996)
			)
		)
	)
	(zone
		(layer "F.Cu")
		(hatch none 0.5)
		(connect_pads
			(clearance 0)
		)
		(min_thickness 0.25)
		(keepout
			(tracks not_allowed)
			(vias allowed)
			(pads allowed)
			(copperpour not_allowed)
			(footprints allowed)
		)
		(placement
			(enabled no)
			(sheetname "")
		)
		(fill
			(thermal_gap 0.5)
			(thermal_bridge_width 0.5)
			(island_removal_mode 0)
		)
		(polygon
			(pts
				(arc
					(start 70.48754 -55.476394)
					(mid 69.8754 -54.864254)
					(end 69.26326 -55.476394)
				)
				(arc
					(start 69.26326 -56.59374)
					(mid 69.875273 -57.206134)
					(end 70.48754 -56.593994)
				)
				(xy 70.48754 -56.278018)
				(arc
					(start 70.485 -56.278018)
					(mid 70.319646 -56.310891)
					(end 70.179438 -56.40451)
				)
				(xy 70.179438 -56.404764)
				(arc
					(start 70.112382 -56.471566)
					(mid 69.686788 -56.782606)
					(end 69.997828 -56.357012)
				)
				(xy 70.06463 -56.289956) (xy 70.064884 -56.289956) (xy 70.088506 -56.266334)
				(arc
					(start 70.089776 -56.266334)
					(mid 70.257497 -56.161169)
					(end 70.450456 -56.116982)
				)
				(xy 70.451472 -56.115966) (xy 70.48754 -56.115966) (xy 70.48754 -55.983886) (xy 70.451472 -55.983886)
				(arc
					(start 70.450202 -55.982616)
					(mid 70.284699 -55.943996)
					(end 70.140322 -55.854346)
				)
				(xy 70.138798 -55.854346) (xy 70.115176 -55.830724) (xy 70.114922 -55.830724)
				(arc
					(start 69.997828 -55.713376)
					(mid 69.686788 -55.287782)
					(end 70.112382 -55.598822)
				)
				(xy 70.22973 -55.715916)
				(arc
					(start 70.22973 -55.71617)
					(mid 70.346863 -55.794373)
					(end 70.485 -55.821834)
				)
				(xy 70.48754 -55.821834)
			)
		)
	)
	(zone
		(net "P3V3_DEV_LL")
		(layer "F.Cu")
		(hatch none 0.5)
		(connect_pads
			(clearance 0.5)
		)
		(min_thickness 0.25)
		(fill yes
			(thermal_gap 0.5)
			(thermal_bridge_width 0.5)
			(island_removal_mode 0)
		)
		(polygon
			(pts
				(xy 54.483 -80.01) (xy 53.848 -80.645) (xy 49.149 -80.645) (xy 49.022 -80.772) (xy 49.022 -84.328)
				(xy 49.149 -84.455) (xy 54.61 -84.455) (xy 54.737 -84.328) (xy 54.737 -80.645) (xy 54.864 -80.518)
				(xy 54.864 -80.137) (xy 54.737 -80.01)
			)
		)
	)
	(zone
		(layer "F.Cu")
		(hatch none 0.5)
		(connect_pads
			(clearance 0)
		)
		(min_thickness 0.25)
		(keepout
			(tracks not_allowed)
			(vias allowed)
			(pads allowed)
			(copperpour not_allowed)
			(footprints allowed)
		)
		(placement
			(enabled no)
			(sheetname "")
		)
		(fill
			(thermal_gap 0.5)
			(thermal_bridge_width 0.5)
			(island_removal_mode 0)
		)
		(polygon
			(pts
				(arc
					(start 75.44054 -22.0218)
					(mid 74.930127 -21.511006)
					(end 74.41946 -22.021546)
				)
				(arc
					(start 74.41946 -22.159722)
					(mid 74.545601 -22.121179)
					(end 74.668126 -22.072346)
				)
				(arc
					(start 74.668126 -22.072346)
					(mid 75.163978 -21.893432)
					(end 74.746104 -22.21484)
				)
				(arc
					(start 74.746104 -22.21484)
					(mid 74.585539 -22.278888)
					(end 74.41946 -22.326854)
				)
				(arc
					(start 74.41946 -22.571456)
					(mid 74.574509 -22.611839)
					(end 74.7268 -22.661626)
				)
				(arc
					(start 74.7268 -22.661626)
					(mid 75.176135 -22.93701)
					(end 74.664316 -22.811486)
				)
				(arc
					(start 74.664316 -22.811486)
					(mid 74.542848 -22.771465)
					(end 74.41946 -22.737826)
				)
				(arc
					(start 74.41946 -22.834346)
					(mid 74.93 -23.344886)
					(end 75.44054 -22.834346)
				)
			)
		)
	)
	(zone
		(layer "F.Cu")
		(hatch none 0.5)
		(connect_pads
			(clearance 0)
		)
		(min_thickness 0.25)
		(keepout
			(tracks allowed)
			(vias allowed)
			(pads allowed)
			(copperpour allowed)
			(footprints allowed)
		)
		(placement
			(enabled no)
			(sheetname "")
		)
		(fill
			(thermal_gap 0.5)
			(thermal_bridge_width 0.5)
			(island_removal_mode 0)
		)
		(polygon
			(pts
				(xy 71.882 -49.022) (xy 74.295 -49.022) (xy 74.295 -57.023) (xy 71.882 -57.023) (xy 70.739 -57.023)
				(xy 70.739 -49.022)
			)
		)
	)
	(zone
		(layer "F.Cu")
		(hatch none 0.5)
		(connect_pads
			(clearance 0)
		)
		(min_thickness 0.25)
		(keepout
			(tracks allowed)
			(vias allowed)
			(pads allowed)
			(copperpour allowed)
			(footprints not_allowed)
		)
		(placement
			(enabled no)
			(sheetname "")
		)
		(fill
			(thermal_gap 0.5)
			(thermal_bridge_width 0.5)
			(island_removal_mode 0)
		)
		(polygon
			(pts
				(arc
					(start 54.85003 -1.999996)
					(mid 55.435815 -0.585785)
					(end 56.850026 0)
				)
				(arc
					(start 88.250014 0)
					(mid 88.603567 -0.146499)
					(end 88.749886 -0.500126)
				)
				(arc
					(start 88.749886 -5.435092)
					(mid 88.603477 -5.788555)
					(end 88.250014 -5.934964)
				)
				(arc
					(start 81.550002 -5.934964)
					(mid 81.19636 -6.081448)
					(end 81.049876 -6.43509)
				)
				(xy 81.049876 -14.699996) (xy 54.85003 -14.699996)
			)
		)
	)
	(zone
		(layer "F.Cu")
		(hatch none 0.5)
		(connect_pads
			(clearance 0)
		)
		(min_thickness 0.25)
		(keepout
			(tracks not_allowed)
			(vias allowed)
			(pads allowed)
			(copperpour not_allowed)
			(footprints allowed)
		)
		(placement
			(enabled no)
			(sheetname "")
		)
		(fill
			(thermal_gap 0.5)
			(thermal_bridge_width 0.5)
			(island_removal_mode 0)
		)
		(polygon
			(pts
				(arc
					(start 69.97954 -52.466748)
					(mid 69.367527 -51.854354)
					(end 68.75526 -52.466494)
				)
				(arc
					(start 68.75526 -53.584094)
					(mid 69.3674 -54.196234)
					(end 69.97954 -53.584094)
				)
				(xy 69.97954 -53.268118)
				(arc
					(start 69.977 -53.268118)
					(mid 69.811646 -53.300991)
					(end 69.671438 -53.39461)
				)
				(xy 69.671438 -53.394864)
				(arc
					(start 69.604382 -53.461666)
					(mid 69.178788 -53.772706)
					(end 69.489828 -53.347112)
				)
				(xy 69.55663 -53.280056) (xy 69.556884 -53.280056) (xy 69.580506 -53.256434)
				(arc
					(start 69.581776 -53.256434)
					(mid 69.749497 -53.151269)
					(end 69.942456 -53.107082)
				)
				(xy 69.943472 -53.106066) (xy 69.97954 -53.106066) (xy 69.97954 -52.973986) (xy 69.943472 -52.973986)
				(arc
					(start 69.942202 -52.972716)
					(mid 69.776699 -52.934096)
					(end 69.632322 -52.844446)
				)
				(xy 69.630798 -52.844446) (xy 69.607176 -52.820824) (xy 69.606922 -52.820824)
				(arc
					(start 69.489828 -52.703476)
					(mid 69.178788 -52.277882)
					(end 69.604382 -52.588922)
				)
				(xy 69.72173 -52.706016)
				(arc
					(start 69.72173 -52.70627)
					(mid 69.838863 -52.784473)
					(end 69.977 -52.811934)
				)
				(xy 69.97954 -52.811934)
			)
		)
	)
	(zone
		(layer "F.Cu")
		(hatch none 0.5)
		(connect_pads
			(clearance 0)
		)
		(min_thickness 0.25)
		(keepout
			(tracks allowed)
			(vias allowed)
			(pads allowed)
			(copperpour allowed)
			(footprints not_allowed)
		)
		(placement
			(enabled no)
			(sheetname "")
		)
		(fill
			(thermal_gap 0.5)
			(thermal_bridge_width 0.5)
			(island_removal_mode 0)
		)
		(polygon
			(pts
				(arc
					(start 56.20004 -4.500118)
					(mid 60.200032 -0.500126)
					(end 64.200024 -4.500118)
				)
				(arc
					(start 64.200024 -4.500118)
					(mid 60.200032 -8.50011)
					(end 56.20004 -4.500118)
				)
			)
		)
	)
	(zone
		(layer "F.Cu")
		(hatch none 0.5)
		(connect_pads
			(clearance 0)
		)
		(min_thickness 0.25)
		(keepout
			(tracks allowed)
			(vias allowed)
			(pads allowed)
			(copperpour allowed)
			(footprints allowed)
		)
		(placement
			(enabled no)
			(sheetname "")
		)
		(fill
			(thermal_gap 0.5)
			(thermal_bridge_width 0.5)
			(island_removal_mode 0)
		)
		(polygon
			(pts
				(xy 66.802 -52.324) (xy 65.278 -52.324) (xy 65.024 -52.324) (xy 65.024 -53.721) (xy 65.278 -53.721)
				(xy 66.802 -53.721)
			)
		)
	)
	(zone
		(net "P12V")
		(layer "F.Cu")
		(hatch none 0.5)
		(connect_pads
			(clearance 0.5)
		)
		(min_thickness 0.25)
		(fill yes
			(thermal_gap 0.5)
			(thermal_bridge_width 0.5)
			(island_removal_mode 0)
		)
		(polygon
			(pts
				(xy 33.909 -75.819) (xy 33.782 -75.946) (xy 33.782 -79.883) (xy 33.909 -80.01) (xy 35.941 -80.01)
				(xy 36.068 -79.883) (xy 36.068 -78.74) (xy 36.449 -78.359) (xy 36.449 -75.946) (xy 36.322 -75.819)
			)
		)
		(polygon
			(pts
				(xy 34.7345 -78.6003) (xy 34.4805 -78.6003) (xy 34.4805 -78.8543) (xy 34.7345 -78.8543)
			)
		)
	)
	(zone
		(layer "F.Cu")
		(hatch none 0.5)
		(connect_pads
			(clearance 0)
		)
		(min_thickness 0.25)
		(keepout
			(tracks allowed)
			(vias allowed)
			(pads allowed)
			(copperpour allowed)
			(footprints allowed)
		)
		(placement
			(enabled no)
			(sheetname "")
		)
		(fill
			(thermal_gap 0.5)
			(thermal_bridge_width 0.5)
			(island_removal_mode 0)
		)
		(polygon
			(pts
				(xy 72.898 -44.577) (xy 71.071994 -44.577) (xy 70.817994 -44.577) (xy 70.817994 -45.974) (xy 71.071994 -45.974)
				(xy 72.898 -45.974)
			)
		)
	)
	(zone
		(layer "F.Cu")
		(hatch none 0.5)
		(connect_pads
			(clearance 0)
		)
		(min_thickness 0.25)
		(keepout
			(tracks not_allowed)
			(vias allowed)
			(pads allowed)
			(copperpour not_allowed)
			(footprints allowed)
		)
		(placement
			(enabled no)
			(sheetname "")
		)
		(fill
			(thermal_gap 0.5)
			(thermal_bridge_width 0.5)
			(island_removal_mode 0)
		)
		(polygon
			(pts
				(arc
					(start 74.50074 -49.621948)
					(mid 73.990327 -49.111154)
					(end 73.47966 -49.621694)
				)
				(xy 73.47966 -49.70907)
				(arc
					(start 73.583546 -49.70907)
					(mid 73.658318 -49.703382)
					(end 73.731374 -49.686464)
				)
				(arc
					(start 73.731374 -49.686464)
					(mid 74.215403 -49.479114)
					(end 73.82002 -49.826926)
				)
				(arc
					(start 73.82002 -49.826926)
					(mid 73.720764 -49.856508)
					(end 73.61809 -49.870106)
				)
				(xy 73.617074 -49.871122) (xy 73.47966 -49.871122) (xy 73.47966 -50.208942) (xy 73.566528 -50.208942)
				(arc
					(start 73.56729 -50.209704)
					(mid 73.683827 -50.222039)
					(end 73.797668 -50.249836)
				)
				(arc
					(start 73.797668 -50.249836)
					(mid 74.230236 -50.550897)
					(end 73.72604 -50.397664)
				)
				(arc
					(start 73.72604 -50.397664)
					(mid 73.630433 -50.377723)
					(end 73.533 -50.370994)
				)
				(xy 73.47966 -50.370994)
				(arc
					(start 73.47966 -50.434494)
					(mid 73.9902 -50.945034)
					(end 74.50074 -50.434494)
				)
			)
		)
	)
	(zone
		(net "GND")
		(layer "F.Cu")
		(hatch none 0.5)
		(connect_pads
			(clearance 0.5)
		)
		(min_thickness 0.25)
		(fill yes
			(thermal_gap 0.5)
			(thermal_bridge_width 0.5)
			(island_removal_mode 0)
		)
		(polygon
			(pts
				(xy 70.8406 -44.592494) (xy 70.739 -44.694094) (xy 70.739 -45.964094) (xy 70.866 -46.091094) (xy 71.374 -46.091094)
				(xy 71.501 -45.964094) (xy 71.501 -44.694094) (xy 71.3994 -44.592494)
			)
		)
	)
	(zone
		(layer "F.Cu")
		(hatch none 0.5)
		(connect_pads
			(clearance 0)
		)
		(min_thickness 0.25)
		(keepout
			(tracks allowed)
			(vias allowed)
			(pads allowed)
			(copperpour allowed)
			(footprints allowed)
		)
		(placement
			(enabled no)
			(sheetname "")
		)
		(fill
			(thermal_gap 0.5)
			(thermal_bridge_width 0.5)
			(island_removal_mode 0)
		)
		(polygon
			(pts
				(xy 71.882 -29.464) (xy 74.168 -29.464) (xy 74.295 -29.464) (xy 74.295 -29.337) (xy 74.295 -21.463)
				(xy 71.882 -21.463) (xy 70.739 -21.463) (xy 70.739 -29.464)
			)
		)
	)
	(zone
		(layer "F.Cu")
		(hatch none 0.5)
		(connect_pads
			(clearance 0)
		)
		(min_thickness 0.25)
		(keepout
			(tracks not_allowed)
			(vias allowed)
			(pads allowed)
			(copperpour not_allowed)
			(footprints allowed)
		)
		(placement
			(enabled no)
			(sheetname "")
		)
		(fill
			(thermal_gap 0.5)
			(thermal_bridge_width 0.5)
			(island_removal_mode 0)
		)
		(polygon
			(pts
				(arc
					(start 70.48754 -27.86634)
					(mid 69.8754 -27.2542)
					(end 69.26326 -27.86634)
				)
				(arc
					(start 69.26326 -28.983686)
					(mid 69.875273 -29.59608)
					(end 70.48754 -28.98394)
				)
				(xy 70.48754 -28.667964)
				(arc
					(start 70.485 -28.667964)
					(mid 70.319646 -28.700837)
					(end 70.179438 -28.794456)
				)
				(arc
					(start 70.112382 -28.861512)
					(mid 69.686788 -29.172552)
					(end 69.997828 -28.746958)
				)
				(xy 70.06463 -28.679902) (xy 70.064884 -28.679902) (xy 70.088506 -28.65628)
				(arc
					(start 70.089776 -28.65628)
					(mid 70.257497 -28.551115)
					(end 70.450456 -28.506928)
				)
				(xy 70.451472 -28.505912) (xy 70.48754 -28.505912) (xy 70.48754 -28.373832) (xy 70.451472 -28.373832)
				(arc
					(start 70.450202 -28.372562)
					(mid 70.284699 -28.333942)
					(end 70.140322 -28.244292)
				)
				(xy 70.138798 -28.244292) (xy 70.115176 -28.22067) (xy 70.114922 -28.22067)
				(arc
					(start 69.997828 -28.103322)
					(mid 69.686788 -27.677728)
					(end 70.112382 -27.988768)
				)
				(arc
					(start 70.22973 -28.106116)
					(mid 70.346863 -28.184319)
					(end 70.485 -28.21178)
				)
				(xy 70.48754 -28.21178)
			)
		)
	)
	(zone
		(layer "F.Cu")
		(hatch none 0.5)
		(connect_pads
			(clearance 0)
		)
		(min_thickness 0.25)
		(keepout
			(tracks allowed)
			(vias allowed)
			(pads allowed)
			(copperpour allowed)
			(footprints allowed)
		)
		(placement
			(enabled no)
			(sheetname "")
		)
		(fill
			(thermal_gap 0.5)
			(thermal_bridge_width 0.5)
			(island_removal_mode 0)
		)
		(polygon
			(pts
				(xy 64.262 -35.687) (xy 64.262 -34.671) (xy 64.262 -31.242) (xy 64.262 -30.734) (xy 66.04 -30.734)
				(xy 66.04 -31.242) (xy 66.04 -34.671) (xy 66.04 -35.687)
			)
		)
	)
	(zone
		(layer "F.Cu")
		(hatch none 0.5)
		(connect_pads
			(clearance 0)
		)
		(min_thickness 0.25)
		(keepout
			(tracks allowed)
			(vias allowed)
			(pads allowed)
			(copperpour allowed)
			(footprints allowed)
		)
		(placement
			(enabled no)
			(sheetname "")
		)
		(fill
			(thermal_gap 0.5)
			(thermal_bridge_width 0.5)
			(island_removal_mode 0)
		)
		(polygon
			(pts
				(xy 72.898 -17.018) (xy 71.071994 -17.018) (xy 70.817994 -17.018) (xy 70.817994 -18.415) (xy 71.071994 -18.415)
				(xy 72.898 -18.415)
			)
		)
	)
	(zone
		(layer "F.Cu")
		(hatch none 0.5)
		(connect_pads
			(clearance 0)
		)
		(min_thickness 0.25)
		(keepout
			(tracks allowed)
			(vias allowed)
			(pads allowed)
			(copperpour allowed)
			(footprints allowed)
		)
		(placement
			(enabled no)
			(sheetname "")
		)
		(fill
			(thermal_gap 0.5)
			(thermal_bridge_width 0.5)
			(island_removal_mode 0)
		)
		(polygon
			(pts
				(xy 43.942 -83.693) (xy 43.942 -80.645) (xy 42.799 -80.645) (xy 42.672 -80.645) (xy 41.529 -79.502)
				(xy 41.529 -78.867) (xy 41.529 -78.613) (xy 42.799 -78.613) (xy 43.942 -78.613) (xy 45.847 -78.613)
				(xy 48.768 -78.613) (xy 48.895 -78.74) (xy 48.895 -80.264) (xy 51.054 -80.264) (xy 51.308 -80.264)
				(xy 51.308 -80.518) (xy 51.308 -83.185) (xy 50.419 -84.074) (xy 43.942 -84.074)
			)
		)
	)
	(zone
		(net "P3V3_PWR")
		(layer "F.Cu")
		(hatch none 0.5)
		(connect_pads
			(clearance 0.5)
		)
		(min_thickness 0.25)
		(fill yes
			(thermal_gap 0.5)
			(thermal_bridge_width 0.5)
			(island_removal_mode 0)
		)
		(polygon
			(pts
				(xy 18.415 -81.2546) (xy 18.415 -82.852006) (xy 18.923 -83.360006) (xy 18.923 -86.106) (xy 18.542 -86.487)
				(xy 18.542 -88.646) (xy 18.669 -88.773) (xy 20.447 -88.773) (xy 20.574 -88.646) (xy 20.574 -81.455006)
				(xy 20.373594 -81.2546)
			)
		)
		(polygon
			(pts
				(xy 19.2532 -87.7824) (xy 18.9992 -87.7824) (xy 18.9992 -88.0364) (xy 19.2532 -88.0364)
			)
		)
		(polygon
			(pts
				(xy 19.2532 -87.2236) (xy 18.9992 -87.2236) (xy 18.9992 -87.4776) (xy 19.2532 -87.4776)
			)
		)
	)
	(zone
		(layer "F.Cu")
		(hatch none 0.5)
		(connect_pads
			(clearance 0)
		)
		(min_thickness 0.25)
		(keepout
			(tracks allowed)
			(vias allowed)
			(pads allowed)
			(copperpour allowed)
			(footprints not_allowed)
		)
		(placement
			(enabled no)
			(sheetname "")
		)
		(fill
			(thermal_gap 0.5)
			(thermal_bridge_width 0.5)
			(island_removal_mode 0)
		)
		(polygon
			(pts
				(xy 81.049876 -14.699996) (xy 81.049876 -65.300098) (xy 67.69989 -65.300098) (xy 67.69989 -42.29989)
				(xy 54.85003 -42.29989) (xy 54.85003 -38.200076) (xy 67.69989 -38.200076) (xy 67.69989 -14.699996)
			)
		)
	)
	(zone
		(layer "F.Cu")
		(hatch none 0.5)
		(connect_pads
			(clearance 0)
		)
		(min_thickness 0.25)
		(keepout
			(tracks allowed)
			(vias allowed)
			(pads allowed)
			(copperpour allowed)
			(footprints not_allowed)
		)
		(placement
			(enabled no)
			(sheetname "")
		)
		(fill
			(thermal_gap 0.5)
			(thermal_bridge_width 0.5)
			(island_removal_mode 0)
		)
		(polygon
			(pts
				(arc
					(start 10.500106 -80.309974)
					(mid 6.500114 -84.309966)
					(end 2.500122 -80.309974)
				)
				(arc
					(start 2.500122 -80.309974)
					(mid 6.500114 -76.309982)
					(end 10.500106 -80.309974)
				)
			)
		)
	)
	(zone
		(net "P3V3_DEV_VIN")
		(layer "F.Cu")
		(hatch none 0.5)
		(connect_pads
			(clearance 0.5)
		)
		(min_thickness 0.25)
		(fill yes
			(thermal_gap 0.5)
			(thermal_bridge_width 0.5)
			(island_removal_mode 0)
		)
		(polygon
			(pts
				(xy 34.671 -80.645) (xy 34.544 -80.772) (xy 34.544 -84.328) (xy 34.671 -84.455) (xy 45.212 -84.455)
				(xy 45.339 -84.328) (xy 45.339 -80.772) (xy 45.212 -80.645)
			)
		)
		(polygon
			(pts
				(xy 43.6118 -83.439) (xy 43.3578 -83.439) (xy 43.3578 -83.693) (xy 43.6118 -83.693)
			)
		)
		(polygon
			(pts
				(xy 42.7482 -83.439) (xy 42.4942 -83.439) (xy 42.4942 -83.693) (xy 42.7482 -83.693)
			)
		)
		(polygon
			(pts
				(xy 36.1315 -81.6737) (xy 35.8775 -81.6737) (xy 35.8775 -81.9277) (xy 36.1315 -81.9277)
			)
		)
	)
	(zone
		(layer "F.Cu")
		(hatch none 0.5)
		(connect_pads
			(clearance 0)
		)
		(min_thickness 0.25)
		(keepout
			(tracks allowed)
			(vias allowed)
			(pads allowed)
			(copperpour allowed)
			(footprints not_allowed)
		)
		(placement
			(enabled no)
			(sheetname "")
		)
		(fill
			(thermal_gap 0.5)
			(thermal_bridge_width 0.5)
			(island_removal_mode 0)
		)
		(polygon
			(pts
				(arc
					(start 81.549748 -11.18489)
					(mid 81.196359 -11.038407)
					(end 81.049876 -10.685018)
				)
				(arc
					(start 81.049876 -44.515024)
					(mid 81.19636 -44.161382)
					(end 81.550002 -44.014898)
				)
				(arc
					(start 82.850228 -44.014898)
					(mid 83.203691 -43.868489)
					(end 83.3501 -43.515026)
				)
				(arc
					(start 83.3501 -11.685016)
					(mid 83.203616 -11.331374)
					(end 82.849974 -11.18489)
				)
			)
		)
	)
	(zone
		(layer "F.Cu")
		(hatch none 0.5)
		(connect_pads
			(clearance 0)
		)
		(min_thickness 0.25)
		(keepout
			(tracks not_allowed)
			(vias allowed)
			(pads allowed)
			(copperpour not_allowed)
			(footprints allowed)
		)
		(placement
			(enabled no)
			(sheetname "")
		)
		(fill
			(thermal_gap 0.5)
			(thermal_bridge_width 0.5)
			(island_removal_mode 0)
		)
		(polygon
			(pts
				(arc
					(start 82.995516 -17.4752)
					(mid 82.612103 -17.091406)
					(end 82.228436 -17.474946)
				)
				(arc
					(start 82.228436 -17.61617)
					(mid 82.295617 -17.592775)
					(end 82.360262 -17.563084)
				)
				(arc
					(start 82.360262 -17.563084)
					(mid 82.824435 -17.313734)
					(end 82.459322 -17.69364)
				)
				(arc
					(start 82.459322 -17.69364)
					(mid 82.346969 -17.746634)
					(end 82.228436 -17.78381)
				)
				(arc
					(start 82.228436 -17.966182)
					(mid 82.346976 -18.003339)
					(end 82.459322 -18.056352)
				)
				(arc
					(start 82.459322 -18.056352)
					(mid 82.824438 -18.43626)
					(end 82.360262 -18.186908)
				)
				(arc
					(start 82.360262 -18.186908)
					(mid 82.295617 -18.157217)
					(end 82.228436 -18.133822)
				)
				(arc
					(start 82.228436 -18.275046)
					(mid 82.611976 -18.658586)
					(end 82.995516 -18.275046)
				)
			)
		)
	)
	(zone
		(layer "F.Cu")
		(hatch none 0.5)
		(connect_pads
			(clearance 0)
		)
		(min_thickness 0.25)
		(keepout
			(tracks allowed)
			(vias allowed)
			(pads allowed)
			(copperpour allowed)
			(footprints not_allowed)
		)
		(placement
			(enabled no)
			(sheetname "")
		)
		(fill
			(thermal_gap 0.5)
			(thermal_bridge_width 0.5)
			(island_removal_mode 0)
		)
		(polygon
			(pts
				(arc
					(start 0 -69.550026)
					(mid 0.585785 -68.135815)
					(end 1.999996 -67.55003)
				)
				(xy 73.200006 -67.55003) (xy 73.200006 -65.300098) (xy 81.049876 -65.300098) (xy 81.049876 -92.30995)
				(arc
					(start 1.999996 -92.30995)
					(mid 0.585785 -91.724165)
					(end 0 -90.309954)
				)
			)
		)
	)
	(zone
		(layer "F.Cu")
		(hatch none 0.5)
		(connect_pads
			(clearance 0)
		)
		(min_thickness 0.25)
		(keepout
			(tracks allowed)
			(vias allowed)
			(pads allowed)
			(copperpour allowed)
			(footprints not_allowed)
		)
		(placement
			(enabled no)
			(sheetname "")
		)
		(fill
			(thermal_gap 0.5)
			(thermal_bridge_width 0.5)
			(island_removal_mode 0)
		)
		(polygon
			(pts
				(arc
					(start 88.749886 -70.809866)
					(mid 88.603477 -70.456403)
					(end 88.250014 -70.309994)
				)
				(arc
					(start 86.249764 -70.309994)
					(mid 85.896375 -70.163511)
					(end 85.749892 -69.810122)
				)
				(arc
					(start 85.749892 -55.770018)
					(mid 85.896376 -55.416376)
					(end 86.250018 -55.269892)
				)
				(arc
					(start 88.250014 -55.269892)
					(mid 88.603477 -55.123483)
					(end 88.749886 -54.77002)
				)
				(arc
					(start 88.749886 -49.76495)
					(mid 88.603477 -49.411487)
					(end 88.250014 -49.265078)
				)
				(arc
					(start 81.550002 -49.265078)
					(mid 81.19636 -49.118594)
					(end 81.049876 -48.764952)
				)
				(xy 81.049876 -92.30995)
				(arc
					(start 86.750144 -92.30995)
					(mid 88.164101 -91.724165)
					(end 88.749886 -90.310208)
				)
			)
		)
	)
	(zone
		(layer "F.Cu")
		(hatch none 0.5)
		(connect_pads
			(clearance 0)
		)
		(min_thickness 0.25)
		(keepout
			(tracks allowed)
			(vias allowed)
			(pads allowed)
			(copperpour allowed)
			(footprints allowed)
		)
		(placement
			(enabled no)
			(sheetname "")
		)
		(fill
			(thermal_gap 0.5)
			(thermal_bridge_width 0.5)
			(island_removal_mode 0)
		)
		(polygon
			(pts
				(xy 27.559 -76.581) (xy 27.559 -73.279) (xy 32.639 -73.279) (xy 32.639 -76.581)
			)
		)
	)
	(zone
		(layer "F.Cu")
		(hatch none 0.5)
		(connect_pads
			(clearance 0)
		)
		(min_thickness 0.25)
		(keepout
			(tracks allowed)
			(vias allowed)
			(pads allowed)
			(copperpour allowed)
			(footprints allowed)
		)
		(placement
			(enabled no)
			(sheetname "")
		)
		(fill
			(thermal_gap 0.5)
			(thermal_bridge_width 0.5)
			(island_removal_mode 0)
		)
		(polygon
			(pts
				(xy 71.882 -34.925) (xy 73.611994 -34.925) (xy 73.611994 -35.941) (xy 71.882 -35.941)
			)
		)
	)
	(zone
		(layer "F.Cu")
		(hatch none 0.5)
		(connect_pads
			(clearance 0)
		)
		(min_thickness 0.25)
		(keepout
			(tracks not_allowed)
			(vias allowed)
			(pads allowed)
			(copperpour not_allowed)
			(footprints allowed)
		)
		(placement
			(enabled no)
			(sheetname "")
		)
		(fill
			(thermal_gap 0.5)
			(thermal_bridge_width 0.5)
			(island_removal_mode 0)
		)
		(polygon
			(pts
				(arc
					(start 82.995516 -27.075384)
					(mid 82.612103 -26.69159)
					(end 82.228436 -27.07513)
				)
				(arc
					(start 82.228436 -27.242262)
					(mid 82.302289 -27.222714)
					(end 82.370676 -27.188668)
				)
				(arc
					(start 82.370676 -27.188668)
					(mid 82.806589 -26.892805)
					(end 82.482944 -27.308556)
				)
				(arc
					(start 82.482944 -27.308556)
					(mid 82.361929 -27.373518)
					(end 82.228436 -27.405838)
				)
				(arc
					(start 82.228436 -27.544522)
					(mid 82.361793 -27.576882)
					(end 82.48269 -27.641804)
				)
				(arc
					(start 82.48269 -27.641804)
					(mid 82.806741 -28.057049)
					(end 82.370676 -27.761692)
				)
				(arc
					(start 82.370676 -27.761692)
					(mid 82.302276 -27.727679)
					(end 82.228436 -27.708098)
				)
				(arc
					(start 82.228436 -27.874976)
					(mid 82.611976 -28.258516)
					(end 82.995516 -27.874976)
				)
			)
		)
	)
	(zone
		(layers "F.Cu" "B.Cu" "In1.Cu" "In2.Cu" "In3.Cu" "In4.Cu" "In5.Cu" "In6.Cu")
		(name "Route Keepin")
		(hatch none 0.5)
		(connect_pads
			(clearance 0)
		)
		(min_thickness 0.25)
		(keepout
			(tracks allowed)
			(vias allowed)
			(pads allowed)
			(copperpour allowed)
			(footprints allowed)
		)
		(placement
			(enabled no)
			(sheetname "")
		)
		(fill
			(thermal_gap 0.5)
			(thermal_bridge_width 0.5)
			(island_removal_mode 0)
		)
		(polygon
			(pts
				(arc
					(start 86.249764 -70.792594)
					(mid 85.555126 -70.50476)
					(end 85.267292 -69.810122)
				)
				(arc
					(start 85.267292 -55.770018)
					(mid 85.555126 -55.075126)
					(end 86.250018 -54.787292)
				)
				(arc
					(start 88.250014 -54.787292)
					(mid 88.262227 -54.782233)
					(end 88.267286 -54.77002)
				)
				(arc
					(start 88.267286 -49.76495)
					(mid 88.262227 -49.752737)
					(end 88.250014 -49.747678)
				)
				(arc
					(start 81.549748 -49.747678)
					(mid 80.85511 -49.459844)
					(end 80.567276 -48.765206)
				)
				(arc
					(start 80.567276 -44.515024)
					(mid 80.85511 -43.820132)
					(end 81.550002 -43.532298)
				)
				(arc
					(start 82.850228 -43.532298)
					(mid 82.862368 -43.527166)
					(end 82.8675 -43.515026)
				)
				(arc
					(start 82.8675 -11.685016)
					(mid 82.862367 -11.672623)
					(end 82.849974 -11.66749)
				)
				(arc
					(start 81.549748 -11.66749)
					(mid 80.85511 -11.379656)
					(end 80.567276 -10.685018)
				)
				(arc
					(start 80.567276 -6.434836)
					(mid 80.85511 -5.740198)
					(end 81.549748 -5.452364)
				)
				(arc
					(start 88.250014 -5.452364)
					(mid 88.262227 -5.447305)
					(end 88.267286 -5.435092)
				)
				(arc
					(start 88.267286 -0.499872)
					(mid 88.262227 -0.487659)
					(end 88.250014 -0.4826)
				)
				(arc
					(start 56.850026 -0.4826)
					(mid 55.777065 -0.927035)
					(end 55.33263 -1.999996)
				)
				(arc
					(start 55.33263 -65.550034)
					(mid 54.605494 -67.305494)
					(end 52.850034 -68.03263)
				)
				(arc
					(start 1.999996 -68.03263)
					(mid 0.927035 -68.477065)
					(end 0.4826 -69.550026)
				)
				(arc
					(start 0.4826 -90.309954)
					(mid 0.927035 -91.382915)
					(end 1.999996 -91.82735)
				)
				(arc
					(start 86.74989 -91.82735)
					(mid 87.822851 -91.382915)
					(end 88.267286 -90.309954)
				)
				(arc
					(start 88.267286 -70.809866)
					(mid 88.262227 -70.797653)
					(end 88.250014 -70.792594)
				)
			)
		)
	)
	(zone
		(layers "F.Cu" "B.Cu" "In1.Cu" "In2.Cu" "In3.Cu" "In4.Cu" "In5.Cu" "In6.Cu")
		(name "Package Keepin")
		(hatch none 0.5)
		(connect_pads
			(clearance 0)
		)
		(min_thickness 0.25)
		(keepout
			(tracks allowed)
			(vias allowed)
			(pads allowed)
			(copperpour allowed)
			(footprints allowed)
		)
		(placement
			(enabled no)
			(sheetname "")
		)
		(fill
			(thermal_gap 0.5)
			(thermal_bridge_width 0.5)
			(island_removal_mode 0)
		)
		(polygon
			(pts
				(xy 58.91403 -4.064)
				(arc
					(start 58.91403 -65.550034)
					(mid 57.137927 -69.837927)
					(end 52.850034 -71.61403)
				)
				(xy 4.064 -71.61403) (xy 4.064 -88.24595) (xy 84.685886 -88.24595)
				(arc
					(start 84.685886 -74.097642)
					(mid 82.510481 -72.426617)
					(end 81.685892 -69.810376)
				)
				(arc
					(start 81.685892 -55.769764)
					(mid 81.866392 -54.499164)
					(end 82.393536 -53.329078)
				)
				(arc
					(start 81.549748 -53.329078)
					(mid 78.322678 -51.992276)
					(end 76.985876 -48.765206)
				)
				(arc
					(start 76.985876 -44.51477)
					(mid 77.602673 -42.223771)
					(end 79.2861 -40.551862)
				)
				(arc
					(start 79.2861 -14.647926)
					(mid 77.60277 -12.976142)
					(end 76.985876 -10.685272)
				)
				(arc
					(start 76.985876 -6.434836)
					(mid 77.155103 -5.203788)
					(end 77.650086 -4.064)
				)
			)
		)
	)
	(zone
		(layers "F.Cu" "In2.Cu")
		(hatch none 0.5)
		(connect_pads
			(clearance 0)
		)
		(min_thickness 0.25)
		(keepout
			(tracks not_allowed)
			(vias allowed)
			(pads allowed)
			(copperpour not_allowed)
			(footprints allowed)
		)
		(placement
			(enabled no)
			(sheetname "")
		)
		(fill yes
			(thermal_gap 0.5)
			(thermal_bridge_width 0.5)
			(island_removal_mode 0)
		)
		(polygon
			(pts
				(arc
					(start 82.995516 -42.274998)
					(mid 82.611976 -41.891458)
					(end 82.228436 -42.274998)
				)
				(arc
					(start 82.228436 -43.075098)
					(mid 82.610706 -43.458636)
					(end 82.995516 -43.077638)
				)
				(arc
					(start 82.878676 -43.077638)
					(mid 82.611976 -43.34181)
					(end 82.345276 -43.077638)
				)
				(arc
					(start 82.345276 -43.075098)
					(mid 82.611976 -42.808398)
					(end 82.878676 -43.075098)
				)
				(xy 82.995516 -43.075098) (xy 82.995516 -42.277538)
				(arc
					(start 82.878676 -42.277538)
					(mid 82.611976 -42.54171)
					(end 82.345276 -42.277538)
				)
				(arc
					(start 82.345276 -42.274998)
					(mid 82.611976 -42.008298)
					(end 82.878676 -42.274998)
				)
			)
		)
	)
	(zone
		(layers "F.Cu" "In2.Cu")
		(hatch none 0.5)
		(connect_pads
			(clearance 0)
		)
		(min_thickness 0.25)
		(keepout
			(tracks not_allowed)
			(vias allowed)
			(pads allowed)
			(copperpour not_allowed)
			(footprints allowed)
		)
		(placement
			(enabled no)
			(sheetname "")
		)
		(fill yes
			(thermal_gap 0.5)
			(thermal_bridge_width 0.5)
			(island_removal_mode 0)
		)
		(polygon
			(pts
				(arc
					(start 77.52334 -33.691322)
					(mid 76.9112 -33.079182)
					(end 76.29906 -33.691322)
				)
				(arc
					(start 76.29906 -34.808922)
					(mid 76.90993 -35.421061)
					(end 77.52334 -34.811462)
				)
				(arc
					(start 77.1779 -34.811462)
					(mid 76.9112 -35.075634)
					(end 76.6445 -34.811462)
				)
				(arc
					(start 76.6445 -34.808922)
					(mid 76.9112 -34.542222)
					(end 77.1779 -34.808922)
				)
				(xy 77.52334 -34.808922) (xy 77.52334 -33.693862)
				(arc
					(start 77.1779 -33.693862)
					(mid 76.9112 -33.958034)
					(end 76.6445 -33.693862)
				)
				(arc
					(start 76.6445 -33.691322)
					(mid 76.9112 -33.424622)
					(end 77.1779 -33.691322)
				)
			)
		)
	)
	(zone
		(layers "F.Cu" "In5.Cu")
		(hatch none 0.5)
		(connect_pads
			(clearance 0)
		)
		(min_thickness 0.25)
		(keepout
			(tracks not_allowed)
			(vias allowed)
			(pads allowed)
			(copperpour not_allowed)
			(footprints allowed)
		)
		(placement
			(enabled no)
			(sheetname "")
		)
		(fill yes
			(thermal_gap 0.5)
			(thermal_bridge_width 0.5)
			(island_removal_mode 0)
		)
		(polygon
			(pts
				(arc
					(start 82.995516 -24.675084)
					(mid 82.611976 -24.291544)
					(end 82.228436 -24.675084)
				)
				(arc
					(start 82.228436 -25.475184)
					(mid 82.610706 -25.858722)
					(end 82.995516 -25.477724)
				)
				(arc
					(start 82.878676 -25.477724)
					(mid 82.611976 -25.741896)
					(end 82.345276 -25.477724)
				)
				(arc
					(start 82.345276 -25.475184)
					(mid 82.611976 -25.208484)
					(end 82.878676 -25.475184)
				)
				(xy 82.995516 -25.475184) (xy 82.995516 -24.677624)
				(arc
					(start 82.878676 -24.677624)
					(mid 82.611976 -24.941796)
					(end 82.345276 -24.677624)
				)
				(arc
					(start 82.345276 -24.675084)
					(mid 82.611976 -24.408384)
					(end 82.878676 -24.675084)
				)
			)
		)
	)
	(zone
		(layers "F.Cu" "In5.Cu")
		(hatch none 0.5)
		(connect_pads
			(clearance 0)
		)
		(min_thickness 0.25)
		(keepout
			(tracks not_allowed)
			(vias allowed)
			(pads allowed)
			(copperpour not_allowed)
			(footprints allowed)
		)
		(placement
			(enabled no)
			(sheetname "")
		)
		(fill yes
			(thermal_gap 0.5)
			(thermal_bridge_width 0.5)
			(island_removal_mode 0)
		)
		(polygon
			(pts
				(arc
					(start 82.995516 -15.075154)
					(mid 82.611976 -14.691614)
					(end 82.228436 -15.075154)
				)
				(arc
					(start 82.228436 -15.874746)
					(mid 82.610579 -16.258538)
					(end 82.995516 -15.87754)
				)
				(arc
					(start 82.878676 -15.87754)
					(mid 82.611976 -16.141712)
					(end 82.345276 -15.87754)
				)
				(arc
					(start 82.345276 -15.875)
					(mid 82.611976 -15.6083)
					(end 82.878676 -15.875)
				)
				(xy 82.995516 -15.875) (xy 82.995516 -15.077694)
				(arc
					(start 82.878676 -15.077694)
					(mid 82.611976 -15.341866)
					(end 82.345276 -15.077694)
				)
				(arc
					(start 82.345276 -15.075154)
					(mid 82.611976 -14.808454)
					(end 82.878676 -15.075154)
				)
			)
		)
	)
	(zone
		(layers "F.Cu" "In5.Cu")
		(hatch none 0.5)
		(connect_pads
			(clearance 0)
		)
		(min_thickness 0.25)
		(keepout
			(tracks not_allowed)
			(vias allowed)
			(pads allowed)
			(copperpour not_allowed)
			(footprints allowed)
		)
		(placement
			(enabled no)
			(sheetname "")
		)
		(fill yes
			(thermal_gap 0.5)
			(thermal_bridge_width 0.5)
			(island_removal_mode 0)
		)
		(polygon
			(pts
				(arc
					(start 82.995516 -19.874992)
					(mid 82.611976 -19.491452)
					(end 82.228436 -19.874992)
				)
				(arc
					(start 82.228436 -20.674838)
					(mid 82.610579 -21.05863)
					(end 82.995516 -20.677632)
				)
				(arc
					(start 82.878676 -20.677632)
					(mid 82.611976 -20.941804)
					(end 82.345276 -20.677632)
				)
				(arc
					(start 82.345276 -20.675092)
					(mid 82.611976 -20.408392)
					(end 82.878676 -20.675092)
				)
				(xy 82.995516 -20.675092) (xy 82.995516 -19.877532)
				(arc
					(start 82.878676 -19.877532)
					(mid 82.611976 -20.141704)
					(end 82.345276 -19.877532)
				)
				(arc
					(start 82.345276 -19.874992)
					(mid 82.611976 -19.608292)
					(end 82.878676 -19.874992)
				)
			)
		)
	)
	(zone
		(net "P3V3_PWR")
		(layer "B.Cu")
		(hatch none 0.5)
		(connect_pads
			(clearance 0.5)
		)
		(min_thickness 0.25)
		(fill yes
			(thermal_gap 0.5)
			(thermal_bridge_width 0.5)
			(island_removal_mode 0)
		)
		(polygon
			(pts
				(xy 60.96 -44.196) (xy 60.833 -44.323) (xy 60.833 -47.244) (xy 60.96 -47.371) (xy 64.008 -47.371)
				(xy 64.135 -47.244) (xy 64.135 -44.323) (xy 64.008 -44.196)
			)
		)
	)
	(zone
		(net "GND")
		(layer "B.Cu")
		(hatch none 0.5)
		(connect_pads
			(clearance 0.5)
		)
		(min_thickness 0.25)
		(fill yes
			(thermal_gap 0.5)
			(thermal_bridge_width 0.5)
			(island_removal_mode 0)
		)
		(polygon
			(pts
				(xy 56.642 -0.508) (xy 55.372 -1.778) (xy 55.372 -31.496) (xy 55.499 -31.623) (xy 55.88 -31.623)
				(xy 57.785 -29.718) (xy 57.785 -24.257) (xy 58.166 -23.876) (xy 60.452 -23.876) (xy 64.135 -20.193)
				(xy 69.596 -20.193) (xy 73.914 -15.875) (xy 73.914 -10.922) (xy 74.422 -10.414) (xy 80.391 -10.414)
				(xy 80.518 -10.287) (xy 80.518 -5.969) (xy 81.153 -5.334) (xy 88.011 -5.334) (xy 88.138 -5.207)
				(xy 88.138 -0.635) (xy 88.011254 -0.508254) (xy 64.135 -0.508254) (xy 64.134746 -0.508)
			)
		)
		(polygon
			(pts
				(xy 64.389 -15.748) (xy 60.452 -15.748) (xy 60.325 -15.875) (xy 60.325 -19.558) (xy 60.452 -19.685)
				(xy 64.389 -19.685) (xy 64.516 -19.558) (xy 64.516 -15.875)
			)
		)
	)
	(zone
		(layer "B.Cu")
		(hatch none 0.5)
		(connect_pads
			(clearance 0)
		)
		(min_thickness 0.25)
		(keepout
			(tracks not_allowed)
			(vias allowed)
			(pads allowed)
			(copperpour not_allowed)
			(footprints allowed)
		)
		(placement
			(enabled no)
			(sheetname "")
		)
		(fill
			(thermal_gap 0.5)
			(thermal_bridge_width 0.5)
			(island_removal_mode 0)
		)
		(polygon
			(pts
				(arc
					(start 82.995516 -27.075384)
					(mid 82.652844 -26.693773)
					(end 82.237072 -26.994104)
				)
				(arc
					(start 82.357976 -26.994104)
					(mid 82.878587 -27.07513)
					(end 82.357976 -27.156156)
				)
				(xy 82.228436 -27.156156) (xy 82.228436 -27.79395)
				(arc
					(start 82.357976 -27.79395)
					(mid 82.878587 -27.874976)
					(end 82.357976 -27.956002)
				)
				(arc
					(start 82.237072 -27.956002)
					(mid 82.65272 -28.256366)
					(end 82.995516 -27.874976)
				)
			)
		)
	)
	(zone
		(layer "B.Cu")
		(hatch none 0.5)
		(connect_pads
			(clearance 0)
		)
		(min_thickness 0.25)
		(keepout
			(tracks allowed)
			(vias allowed)
			(pads allowed)
			(copperpour allowed)
			(footprints not_allowed)
		)
		(placement
			(enabled no)
			(sheetname "")
		)
		(fill
			(thermal_gap 0.5)
			(thermal_bridge_width 0.5)
			(island_removal_mode 0)
		)
		(polygon
			(pts
				(arc
					(start 69.000116 -87.810086)
					(mid 73.000108 -91.810078)
					(end 77.0001 -87.810086)
				)
				(arc
					(start 77.0001 -87.810086)
					(mid 73.000108 -83.810094)
					(end 69.000116 -87.810086)
				)
			)
		)
	)
	(zone
		(layer "B.Cu")
		(hatch none 0.5)
		(connect_pads
			(clearance 0)
		)
		(min_thickness 0.25)
		(keepout
			(tracks not_allowed)
			(vias allowed)
			(pads allowed)
			(copperpour not_allowed)
			(footprints allowed)
		)
		(placement
			(enabled no)
			(sheetname "")
		)
		(fill
			(thermal_gap 0.5)
			(thermal_bridge_width 0.5)
			(island_removal_mode 0)
		)
		(polygon
			(pts
				(arc
					(start 82.995516 -42.275252)
					(mid 82.652844 -41.893641)
					(end 82.237072 -42.193972)
				)
				(arc
					(start 82.357976 -42.193972)
					(mid 82.878587 -42.274998)
					(end 82.357976 -42.356024)
				)
				(xy 82.228436 -42.356024) (xy 82.228436 -42.994072)
				(arc
					(start 82.357976 -42.994072)
					(mid 82.878587 -43.075098)
					(end 82.357976 -43.156124)
				)
				(arc
					(start 82.237072 -43.156124)
					(mid 82.65272 -43.456488)
					(end 82.995516 -43.075098)
				)
			)
		)
	)
	(zone
		(net "GND")
		(layer "B.Cu")
		(hatch none 0.5)
		(connect_pads
			(clearance 0.5)
		)
		(min_thickness 0.25)
		(fill yes
			(thermal_gap 0.5)
			(thermal_bridge_width 0.5)
			(island_removal_mode 0)
		)
		(polygon
			(pts
				(xy 58.166 -44.196) (xy 58.039 -44.323) (xy 58.039 -46.863) (xy 58.166 -46.99) (xy 60.198 -46.99)
				(xy 60.325 -46.863) (xy 60.325 -44.323) (xy 60.198 -44.196)
			)
		)
	)
	(zone
		(layer "B.Cu")
		(hatch none 0.5)
		(connect_pads
			(clearance 0)
		)
		(min_thickness 0.25)
		(keepout
			(tracks allowed)
			(vias allowed)
			(pads allowed)
			(copperpour allowed)
			(footprints not_allowed)
		)
		(placement
			(enabled no)
			(sheetname "")
		)
		(fill
			(thermal_gap 0.5)
			(thermal_bridge_width 0.5)
			(island_removal_mode 0)
		)
		(polygon
			(pts
				(arc
					(start 73.000108 -8.800084)
					(mid 75.539786 -7.969951)
					(end 77.098906 -5.80009)
				)
				(xy 79.2988 -5.80009) (xy 79.2988 0)
				(arc
					(start 56.850026 0)
					(mid 55.435815 -0.585785)
					(end 54.85003 -1.999996)
				)
				(xy 54.85003 -10.299954) (xy 73.000108 -10.299954)
			)
		)
	)
	(zone
		(layer "B.Cu")
		(hatch none 0.5)
		(connect_pads
			(clearance 0)
		)
		(min_thickness 0.25)
		(keepout
			(tracks allowed)
			(vias allowed)
			(pads allowed)
			(copperpour allowed)
			(footprints not_allowed)
		)
		(placement
			(enabled no)
			(sheetname "")
		)
		(fill
			(thermal_gap 0.5)
			(thermal_bridge_width 0.5)
			(island_removal_mode 0)
		)
		(polygon
			(pts
				(arc
					(start 60.200032 -2.724912)
					(mid 58.424826 -4.500118)
					(end 60.200032 -6.27507)
				)
				(arc
					(start 60.200032 -6.27507)
					(mid 61.974984 -4.500118)
					(end 60.200032 -2.724912)
				)
			)
		)
	)
	(zone
		(net "GND")
		(layer "B.Cu")
		(hatch none 0.5)
		(connect_pads
			(clearance 0.5)
		)
		(min_thickness 0.25)
		(fill yes
			(thermal_gap 0.5)
			(thermal_bridge_width 0.5)
			(island_removal_mode 0)
		)
		(polygon
			(pts
				(xy 58.166 -33.782) (xy 58.039 -33.909) (xy 58.039 -36.449) (xy 58.166 -36.576) (xy 60.198 -36.576)
				(xy 60.325 -36.449) (xy 60.325 -33.909) (xy 60.198 -33.782)
			)
		)
	)
	(zone
		(net "P3V3_PWR")
		(layer "B.Cu")
		(hatch none 0.5)
		(connect_pads
			(clearance 0.5)
		)
		(min_thickness 0.25)
		(fill yes
			(thermal_gap 0.5)
			(thermal_bridge_width 0.5)
			(island_removal_mode 0)
		)
		(polygon
			(pts
				(xy 60.96 -31.115) (xy 60.833 -31.242) (xy 60.833 -36.449) (xy 60.96 -36.576) (xy 64.008 -36.576)
				(xy 64.135 -36.449) (xy 64.135 -31.242) (xy 64.008 -31.115)
			)
		)
	)
	(zone
		(net "GND")
		(layer "B.Cu")
		(hatch none 0.5)
		(connect_pads
			(clearance 0.5)
		)
		(min_thickness 0.25)
		(fill yes
			(thermal_gap 0.5)
			(thermal_bridge_width 0.5)
			(island_removal_mode 0)
		)
		(polygon
			(pts
				(xy 37.084 -76.708) (xy 36.957 -76.835) (xy 36.957 -78.359) (xy 37.084 -78.486) (xy 38.354 -78.486)
				(xy 38.481 -78.359) (xy 38.481 -76.835) (xy 38.354 -76.708)
			)
		)
	)
	(zone
		(net "P3V3_PWR")
		(layer "B.Cu")
		(hatch none 0.5)
		(connect_pads
			(clearance 0.5)
		)
		(min_thickness 0.25)
		(fill yes
			(thermal_gap 0.5)
			(thermal_bridge_width 0.5)
			(island_removal_mode 0)
		)
		(polygon
			(pts
				(xy 63.373 -76.327) (xy 63.246 -76.454) (xy 63.246 -78.105) (xy 67.056 -81.915) (xy 67.056 -88.265)
				(xy 66.421 -88.9) (xy 22.098 -88.9) (xy 20.193 -86.995) (xy 19.05 -86.995) (xy 15.494 -83.439) (xy 15.494 -78.486)
				(xy 15.367 -78.359) (xy 14.097 -78.359) (xy 13.97 -78.486) (xy 13.97 -84.201) (xy 19.939 -90.17)
				(xy 66.802 -90.17) (xy 68.199 -88.773) (xy 68.199 -80.772) (xy 63.754 -76.327)
			)
		)
	)
	(zone
		(net "GND")
		(layer "B.Cu")
		(hatch none 0.5)
		(connect_pads
			(clearance 0.5)
		)
		(min_thickness 0.25)
		(fill yes
			(thermal_gap 0.5)
			(thermal_bridge_width 0.5)
			(island_removal_mode 0)
		)
		(polygon
			(pts
				(xy 68.326 -43.053) (xy 68.072 -43.307) (xy 68.072 -54.737) (xy 65.405 -57.404) (xy 65.405 -65.659)
				(xy 63.627 -67.437) (xy 58.42 -67.437) (xy 54.864 -70.993) (xy 33.655 -70.993) (xy 33.528 -71.12)
				(xy 33.528 -75.057) (xy 33.655 -75.184) (xy 38.354 -75.184) (xy 41.148 -72.39) (xy 50.927 -72.39)
				(xy 51.943 -73.406) (xy 70.485 -73.406) (xy 70.739 -73.66) (xy 70.739 -79.883) (xy 68.58 -82.042)
				(xy 68.58 -88.9) (xy 67.056 -90.424) (xy 31.623 -90.424) (xy 31.496 -90.297) (xy 15.875 -90.297)
				(xy 12.7 -87.122) (xy 12.7 -75.946) (xy 19.812 -68.834) (xy 28.448 -68.834) (xy 28.956 -68.326)
				(xy 28.956 -68.199) (xy 28.829 -68.072) (xy 1.778 -68.072) (xy 0.508 -69.342) (xy 0.508 -90.424)
				(xy 1.905 -91.821) (xy 86.741 -91.821) (xy 88.265 -90.297) (xy 88.265 -70.993) (xy 88.138 -70.866)
				(xy 85.852 -70.866) (xy 85.217 -70.231) (xy 85.217 -55.372) (xy 85.852 -54.737) (xy 88.138 -54.737)
				(xy 88.265 -54.61) (xy 88.265 -49.911) (xy 88.138 -49.784) (xy 81.153 -49.784) (xy 80.518 -49.149)
				(xy 80.518 -43.688) (xy 79.883 -43.053)
			)
		)
		(polygon
			(pts
				(xy 69.1134 -61.1632) (xy 68.8594 -61.1632) (xy 68.8594 -61.4172) (xy 69.1134 -61.4172)
			)
		)
	)
	(zone
		(net "P3V3_PWR")
		(layer "B.Cu")
		(hatch none 0.5)
		(connect_pads
			(clearance 0.5)
		)
		(min_thickness 0.25)
		(fill yes
			(thermal_gap 0.5)
			(thermal_bridge_width 0.5)
			(island_removal_mode 0)
		)
		(polygon
			(pts
				(xy 60.96 -58.674) (xy 60.833 -58.801) (xy 60.833 -64.008) (xy 60.96 -64.135) (xy 64.008 -64.135)
				(xy 64.135 -64.008) (xy 64.135 -58.801) (xy 64.008 -58.674)
			)
		)
	)
	(zone
		(layer "B.Cu")
		(hatch none 0.5)
		(connect_pads
			(clearance 0)
		)
		(min_thickness 0.25)
		(keepout
			(tracks not_allowed)
			(vias allowed)
			(pads allowed)
			(copperpour not_allowed)
			(footprints allowed)
		)
		(placement
			(enabled no)
			(sheetname "")
		)
		(fill
			(thermal_gap 0.5)
			(thermal_bridge_width 0.5)
			(island_removal_mode 0)
		)
		(polygon
			(pts
				(arc
					(start 82.995516 -22.275292)
					(mid 82.652844 -21.893681)
					(end 82.237072 -22.194012)
				)
				(arc
					(start 82.357976 -22.194012)
					(mid 82.878587 -22.275038)
					(end 82.357976 -22.356064)
				)
				(xy 82.228436 -22.356064) (xy 82.228436 -22.994112)
				(arc
					(start 82.357976 -22.994112)
					(mid 82.878587 -23.075138)
					(end 82.357976 -23.156164)
				)
				(arc
					(start 82.237072 -23.156164)
					(mid 82.65272 -23.456528)
					(end 82.995516 -23.075138)
				)
			)
		)
	)
	(zone
		(layer "B.Cu")
		(hatch none 0.5)
		(connect_pads
			(clearance 0)
		)
		(min_thickness 0.25)
		(keepout
			(tracks allowed)
			(vias allowed)
			(pads allowed)
			(copperpour allowed)
			(footprints allowed)
		)
		(placement
			(enabled no)
			(sheetname "")
		)
		(fill
			(thermal_gap 0.5)
			(thermal_bridge_width 0.5)
			(island_removal_mode 0)
		)
		(polygon
			(pts
				(xy 57.355994 -82.931) (xy 57.355994 -75.819) (xy 51.132994 -75.819) (xy 51.132994 -82.931)
			)
		)
	)
	(zone
		(layer "B.Cu")
		(hatch none 0.5)
		(connect_pads
			(clearance 0)
		)
		(min_thickness 0.25)
		(keepout
			(tracks not_allowed)
			(vias allowed)
			(pads allowed)
			(copperpour not_allowed)
			(footprints allowed)
		)
		(placement
			(enabled no)
			(sheetname "")
		)
		(fill
			(thermal_gap 0.5)
			(thermal_bridge_width 0.5)
			(island_removal_mode 0)
		)
		(polygon
			(pts
				(arc
					(start 77.52334 -33.691576)
					(mid 76.911327 -33.079182)
					(end 76.29906 -33.691322)
				)
				(arc
					(start 76.29906 -34.808922)
					(mid 76.9112 -35.421062)
					(end 77.52334 -34.808922)
				)
				(arc
					(start 77.52334 -34.501328)
					(mid 77.461913 -34.484052)
					(end 77.398372 -34.478214)
				)
				(arc
					(start 77.373988 -34.478214)
					(mid 77.216252 -34.512028)
					(end 77.086206 -34.6075)
				)
				(arc
					(start 77.086206 -34.6075)
					(mid 76.809316 -35.055249)
					(end 76.930504 -34.542984)
				)
				(arc
					(start 76.930504 -34.542984)
					(mid 77.109658 -34.384241)
					(end 77.339444 -34.317178)
				)
				(xy 77.34046 -34.316162) (xy 77.4319 -34.316162)
				(arc
					(start 77.43317 -34.317432)
					(mid 77.478571 -34.322538)
					(end 77.52334 -34.331656)
				)
				(arc
					(start 77.52334 -34.162492)
					(mid 77.4679 -34.175781)
					(end 77.411326 -34.182812)
				)
				(xy 77.410056 -34.184082) (xy 77.34046 -34.184082)
				(arc
					(start 77.339444 -34.183066)
					(mid 77.109641 -34.116033)
					(end 76.930504 -33.95726)
				)
				(arc
					(start 76.930504 -33.95726)
					(mid 76.809333 -33.445035)
					(end 77.086206 -33.892744)
				)
				(arc
					(start 77.086206 -33.892744)
					(mid 77.216235 -33.988254)
					(end 77.373988 -34.02203)
				)
				(arc
					(start 77.376528 -34.02203)
					(mid 77.451691 -34.013883)
					(end 77.52334 -33.989772)
				)
			)
		)
	)
	(zone
		(layer "B.Cu")
		(hatch none 0.5)
		(connect_pads
			(clearance 0)
		)
		(min_thickness 0.25)
		(keepout
			(tracks not_allowed)
			(vias allowed)
			(pads allowed)
			(copperpour not_allowed)
			(footprints allowed)
		)
		(placement
			(enabled no)
			(sheetname "")
		)
		(fill
			(thermal_gap 0.5)
			(thermal_bridge_width 0.5)
			(island_removal_mode 0)
		)
		(polygon
			(pts
				(arc
					(start 82.995516 -24.675338)
					(mid 82.652844 -24.293727)
					(end 82.237072 -24.594058)
				)
				(arc
					(start 82.357976 -24.594058)
					(mid 82.878587 -24.675084)
					(end 82.357976 -24.75611)
				)
				(xy 82.228436 -24.75611) (xy 82.228436 -25.394158)
				(arc
					(start 82.357976 -25.394158)
					(mid 82.878587 -25.475184)
					(end 82.357976 -25.55621)
				)
				(arc
					(start 82.237072 -25.55621)
					(mid 82.65272 -25.856574)
					(end 82.995516 -25.475184)
				)
			)
		)
	)
	(zone
		(layer "B.Cu")
		(hatch none 0.5)
		(connect_pads
			(clearance 0)
		)
		(min_thickness 0.25)
		(keepout
			(tracks not_allowed)
			(vias allowed)
			(pads allowed)
			(copperpour not_allowed)
			(footprints allowed)
		)
		(placement
			(enabled no)
			(sheetname "")
		)
		(fill
			(thermal_gap 0.5)
			(thermal_bridge_width 0.5)
			(island_removal_mode 0)
		)
		(polygon
			(pts
				(arc
					(start 82.995516 -39.875206)
					(mid 82.652844 -39.493595)
					(end 82.237072 -39.793926)
				)
				(arc
					(start 82.357976 -39.793926)
					(mid 82.878587 -39.874952)
					(end 82.357976 -39.955978)
				)
				(xy 82.228436 -39.955978) (xy 82.228436 -40.594026)
				(arc
					(start 82.357976 -40.594026)
					(mid 82.878587 -40.675052)
					(end 82.357976 -40.756078)
				)
				(arc
					(start 82.237072 -40.756078)
					(mid 82.65272 -41.056442)
					(end 82.995516 -40.675052)
				)
			)
		)
	)
	(zone
		(layer "B.Cu")
		(hatch none 0.5)
		(connect_pads
			(clearance 0)
		)
		(min_thickness 0.25)
		(keepout
			(tracks allowed)
			(vias allowed)
			(pads allowed)
			(copperpour allowed)
			(footprints not_allowed)
		)
		(placement
			(enabled no)
			(sheetname "")
		)
		(fill
			(thermal_gap 0.5)
			(thermal_bridge_width 0.5)
			(island_removal_mode 0)
		)
		(polygon
			(pts
				(arc
					(start 81.550002 -5.934964)
					(mid 81.19636 -6.081448)
					(end 81.049876 -6.43509)
				)
				(arc
					(start 81.049876 -10.48512)
					(mid 81.089919 -10.958974)
					(end 81.508346 -11.18489)
				)
				(arc
					(start 82.849974 -11.18489)
					(mid 83.203616 -11.331374)
					(end 83.3501 -11.685016)
				)
				(arc
					(start 83.3501 -43.515026)
					(mid 83.203527 -43.868504)
					(end 82.849974 -44.014898)
				)
				(arc
					(start 81.488026 -44.014898)
					(mid 81.233506 -44.084506)
					(end 81.049876 -44.273978)
				)
				(arc
					(start 81.049876 -48.764952)
					(mid 81.19636 -49.118594)
					(end 81.550002 -49.265078)
				)
				(arc
					(start 88.250014 -49.265078)
					(mid 88.603477 -49.411487)
					(end 88.749886 -49.76495)
				)
				(arc
					(start 88.749886 -54.77002)
					(mid 88.603477 -55.123483)
					(end 88.250014 -55.269892)
				)
				(arc
					(start 86.250018 -55.269892)
					(mid 85.896376 -55.416376)
					(end 85.749892 -55.770018)
				)
				(arc
					(start 85.749892 -69.810122)
					(mid 85.896465 -70.1636)
					(end 86.250018 -70.309994)
				)
				(arc
					(start 88.250014 -70.309994)
					(mid 88.603567 -70.456493)
					(end 88.749886 -70.81012)
				)
				(arc
					(start 88.749886 -90.309954)
					(mid 88.164101 -91.724165)
					(end 86.74989 -92.30995)
				)
				(xy 79.149956 -92.30995) (xy 79.149956 -81.309972) (xy 67.14998 -81.309972) (xy 67.14998 -92.30995)
				(xy 13.999972 -92.30995) (xy 13.999972 -67.55003)
				(arc
					(start 52.850034 -67.55003)
					(mid 54.264245 -66.964245)
					(end 54.85003 -65.550034)
				)
				(xy 54.85003 -10.299954) (xy 73.000108 -10.299954)
				(arc
					(start 73.000108 -8.800084)
					(mid 75.539786 -7.969951)
					(end 77.098906 -5.80009)
				)
				(xy 79.2988 -5.80009) (xy 79.2988 0)
				(arc
					(start 88.250014 0)
					(mid 88.603567 -0.146499)
					(end 88.749886 -0.500126)
				)
				(arc
					(start 88.749886 -5.435092)
					(mid 88.603477 -5.788555)
					(end 88.250014 -5.934964)
				)
			)
		)
	)
	(zone
		(layer "B.Cu")
		(hatch none 0.5)
		(connect_pads
			(clearance 0)
		)
		(min_thickness 0.25)
		(keepout
			(tracks allowed)
			(vias allowed)
			(pads allowed)
			(copperpour allowed)
			(footprints not_allowed)
		)
		(placement
			(enabled no)
			(sheetname "")
		)
		(fill
			(thermal_gap 0.5)
			(thermal_bridge_width 0.5)
			(island_removal_mode 0)
		)
		(polygon
			(pts
				(arc
					(start 2.500122 -80.309974)
					(mid 6.500114 -84.309966)
					(end 10.500106 -80.309974)
				)
				(arc
					(start 10.500106 -80.309974)
					(mid 6.500114 -76.309982)
					(end 2.500122 -80.309974)
				)
			)
		)
	)
	(zone
		(layer "B.Cu")
		(hatch none 0.5)
		(connect_pads
			(clearance 0)
		)
		(min_thickness 0.25)
		(keepout
			(tracks allowed)
			(vias allowed)
			(pads allowed)
			(copperpour allowed)
			(footprints not_allowed)
		)
		(placement
			(enabled no)
			(sheetname "")
		)
		(fill
			(thermal_gap 0.5)
			(thermal_bridge_width 0.5)
			(island_removal_mode 0)
		)
		(polygon
			(pts
				(xy 13.999972 -92.30995) (xy 13.999972 -67.55003)
				(arc
					(start 1.999996 -67.55003)
					(mid 0.585785 -68.135815)
					(end 0 -69.550026)
				)
				(arc
					(start 0 -90.309954)
					(mid 0.585785 -91.724165)
					(end 1.999996 -92.30995)
				)
			)
		)
	)
	(zone
		(layer "B.Cu")
		(hatch none 0.5)
		(connect_pads
			(clearance 0)
		)
		(min_thickness 0.25)
		(keepout
			(tracks allowed)
			(vias allowed)
			(pads allowed)
			(copperpour allowed)
			(footprints not_allowed)
		)
		(placement
			(enabled no)
			(sheetname "")
		)
		(fill
			(thermal_gap 0.5)
			(thermal_bridge_width 0.5)
			(island_removal_mode 0)
		)
		(polygon
			(pts
				(xy 79.149956 -92.30995) (xy 79.149956 -81.309972) (xy 67.14998 -81.309972) (xy 67.14998 -92.30995)
			)
		)
	)
	(zone
		(layer "B.Cu")
		(hatch none 0.5)
		(connect_pads
			(clearance 0)
		)
		(min_thickness 0.25)
		(keepout
			(tracks not_allowed)
			(vias allowed)
			(pads allowed)
			(copperpour not_allowed)
			(footprints allowed)
		)
		(placement
			(enabled no)
			(sheetname "")
		)
		(fill
			(thermal_gap 0.5)
			(thermal_bridge_width 0.5)
			(island_removal_mode 0)
		)
		(polygon
			(pts
				(arc
					(start 82.995516 -15.075154)
					(mid 82.652717 -14.693784)
					(end 82.237072 -14.994128)
				)
				(arc
					(start 82.357976 -14.994128)
					(mid 82.878587 -15.075154)
					(end 82.357976 -15.15618)
				)
				(xy 82.228436 -15.15618) (xy 82.228436 -15.793974)
				(arc
					(start 82.357976 -15.793974)
					(mid 82.878587 -15.875)
					(end 82.357976 -15.956026)
				)
				(arc
					(start 82.237072 -15.956026)
					(mid 82.65272 -16.25639)
					(end 82.995516 -15.875)
				)
			)
		)
	)
	(zone
		(layer "B.Cu")
		(hatch none 0.5)
		(connect_pads
			(clearance 0)
		)
		(min_thickness 0.25)
		(keepout
			(tracks allowed)
			(vias allowed)
			(pads allowed)
			(copperpour allowed)
			(footprints not_allowed)
		)
		(placement
			(enabled no)
			(sheetname "")
		)
		(fill
			(thermal_gap 0.5)
			(thermal_bridge_width 0.5)
			(island_removal_mode 0)
		)
		(polygon
			(pts
				(arc
					(start 56.20004 -4.500118)
					(mid 60.200032 -8.50011)
					(end 64.200024 -4.500118)
				)
				(arc
					(start 64.200024 -4.500118)
					(mid 60.200032 -0.500126)
					(end 56.20004 -4.500118)
				)
			)
		)
	)
	(zone
		(net "P3V3_PWR")
		(layer "B.Cu")
		(hatch none 0.5)
		(connect_pads
			(clearance 0.5)
		)
		(min_thickness 0.25)
		(fill yes
			(thermal_gap 0.5)
			(thermal_bridge_width 0.5)
			(island_removal_mode 0)
		)
		(polygon
			(pts
				(xy 60.96 -16.129) (xy 60.833 -16.256) (xy 60.833 -19.304) (xy 60.96 -19.431) (xy 64.008 -19.431)
				(xy 64.135 -19.304) (xy 64.135 -16.256) (xy 64.008 -16.129)
			)
		)
	)
	(zone
		(layer "B.Cu")
		(hatch none 0.5)
		(connect_pads
			(clearance 0)
		)
		(min_thickness 0.25)
		(keepout
			(tracks not_allowed)
			(vias allowed)
			(pads allowed)
			(copperpour not_allowed)
			(footprints allowed)
		)
		(placement
			(enabled no)
			(sheetname "")
		)
		(fill
			(thermal_gap 0.5)
			(thermal_bridge_width 0.5)
			(island_removal_mode 0)
		)
		(polygon
			(pts
				(arc
					(start 82.995516 -19.874992)
					(mid 82.652717 -19.493622)
					(end 82.237072 -19.793966)
				)
				(arc
					(start 82.357976 -19.793966)
					(mid 82.878587 -19.874992)
					(end 82.357976 -19.956018)
				)
				(xy 82.228436 -19.956018) (xy 82.228436 -20.594066)
				(arc
					(start 82.357976 -20.594066)
					(mid 82.878587 -20.675092)
					(end 82.357976 -20.756118)
				)
				(arc
					(start 82.237072 -20.756118)
					(mid 82.65272 -21.056482)
					(end 82.995516 -20.675092)
				)
			)
		)
	)
	(zone
		(layer "B.Cu")
		(hatch none 0.5)
		(connect_pads
			(clearance 0)
		)
		(min_thickness 0.25)
		(keepout
			(tracks allowed)
			(vias allowed)
			(pads allowed)
			(copperpour allowed)
			(footprints allowed)
		)
		(placement
			(enabled no)
			(sheetname "")
		)
		(fill
			(thermal_gap 0.5)
			(thermal_bridge_width 0.5)
			(island_removal_mode 0)
		)
		(polygon
			(pts
				(xy 79.121 -32.766) (xy 76.581 -32.766) (xy 76.581 -35.052) (xy 77.089 -35.052) (xy 79.121 -35.052)
			)
		)
	)
	(zone
		(layer "B.Cu")
		(hatch none 0.5)
		(connect_pads
			(clearance 0)
		)
		(min_thickness 0.25)
		(keepout
			(tracks not_allowed)
			(vias allowed)
			(pads allowed)
			(copperpour not_allowed)
			(footprints allowed)
		)
		(placement
			(enabled no)
			(sheetname "")
		)
		(fill
			(thermal_gap 0.5)
			(thermal_bridge_width 0.5)
			(island_removal_mode 0)
		)
		(polygon
			(pts
				(arc
					(start 82.995516 -17.4752)
					(mid 82.652844 -17.093589)
					(end 82.237072 -17.39392)
				)
				(arc
					(start 82.357976 -17.39392)
					(mid 82.878587 -17.474946)
					(end 82.357976 -17.555972)
				)
				(xy 82.228436 -17.555972) (xy 82.228436 -18.19402)
				(arc
					(start 82.357976 -18.19402)
					(mid 82.878587 -18.275046)
					(end 82.357976 -18.356072)
				)
				(arc
					(start 82.237072 -18.356072)
					(mid 82.65272 -18.656436)
					(end 82.995516 -18.275046)
				)
			)
		)
	)
	(zone
		(net "P3V3_DEV_VIN")
		(layer "B.Cu")
		(hatch none 0.5)
		(connect_pads
			(clearance 0.5)
		)
		(min_thickness 0.25)
		(fill yes
			(thermal_gap 0.5)
			(thermal_bridge_width 0.5)
			(island_removal_mode 0)
		)
		(polygon
			(pts
				(xy 34.671 -80.645) (xy 34.544 -80.772) (xy 34.544 -84.328) (xy 34.671 -84.455) (xy 45.290994 -84.455)
				(xy 45.417994 -84.328) (xy 45.417994 -80.772) (xy 45.290994 -80.645)
			)
		)
	)
	(zone
		(net "P12V")
		(layer "B.Cu")
		(hatch none 0.5)
		(connect_pads
			(clearance 0.5)
		)
		(min_thickness 0.25)
		(fill yes
			(thermal_gap 0.5)
			(thermal_bridge_width 0.5)
			(island_removal_mode 0)
		)
		(polygon
			(pts
				(xy 74.803 -11.176) (xy 74.676 -11.303) (xy 74.676 -14.732) (xy 74.803 -14.859) (xy 79.756 -14.859)
				(xy 79.883 -14.732) (xy 79.883 -11.303) (xy 79.756 -11.176)
			)
		)
	)
	(zone
		(net "P12V")
		(layer "B.Cu")
		(hatch none 0.5)
		(connect_pads
			(clearance 0.5)
		)
		(min_thickness 0.25)
		(fill yes
			(thermal_gap 0.5)
			(thermal_bridge_width 0.5)
			(island_removal_mode 0)
		)
		(polygon
			(pts
				(xy 33.909 -75.692) (xy 33.782 -75.819) (xy 33.782 -80.01) (xy 33.909 -80.137) (xy 36.83 -80.137)
				(xy 36.957 -80.01) (xy 36.957 -79.248) (xy 36.576 -78.867) (xy 36.576 -75.819) (xy 36.449 -75.692)
			)
		)
		(polygon
			(pts
				(xy 36.146994 -79.0702) (xy 35.892994 -79.0702) (xy 35.892994 -79.3242) (xy 36.146994 -79.3242)
			)
		)
	)
	(zone
		(layer "B.Cu")
		(hatch none 0.5)
		(connect_pads
			(clearance 0)
		)
		(min_thickness 0.25)
		(keepout
			(tracks allowed)
			(vias allowed)
			(pads allowed)
			(copperpour allowed)
			(footprints not_allowed)
		)
		(placement
			(enabled no)
			(sheetname "")
		)
		(fill
			(thermal_gap 0.5)
			(thermal_bridge_width 0.5)
			(island_removal_mode 0)
		)
		(polygon
			(pts
				(arc
					(start 6.500114 -82.084926)
					(mid 8.275066 -80.309974)
					(end 6.500114 -78.535022)
				)
				(arc
					(start 6.500114 -78.535022)
					(mid 4.725162 -80.309974)
					(end 6.500114 -82.084926)
				)
			)
		)
	)
	(zone
		(net "GND")
		(layer "B.Cu")
		(hatch none 0.5)
		(connect_pads
			(clearance 0.5)
		)
		(min_thickness 0.25)
		(fill yes
			(thermal_gap 0.5)
			(thermal_bridge_width 0.5)
			(island_removal_mode 0)
		)
		(polygon
			(pts
				(xy 58.166 -61.341) (xy 58.039 -61.468) (xy 58.039 -64.008) (xy 58.166 -64.135) (xy 60.198 -64.135)
				(xy 60.325 -64.008) (xy 60.325 -61.468) (xy 60.198 -61.341)
			)
		)
	)
	(zone
		(layer "B.Cu")
		(hatch none 0.5)
		(connect_pads
			(clearance 0)
		)
		(min_thickness 0.25)
		(keepout
			(tracks allowed)
			(vias allowed)
			(pads allowed)
			(copperpour allowed)
			(footprints not_allowed)
		)
		(placement
			(enabled no)
			(sheetname "")
		)
		(fill
			(thermal_gap 0.5)
			(thermal_bridge_width 0.5)
			(island_removal_mode 0)
		)
		(polygon
			(pts
				(arc
					(start 74.77506 -87.810086)
					(mid 73.000108 -86.035134)
					(end 71.224902 -87.810086)
				)
				(arc
					(start 71.224902 -87.810086)
					(mid 73.000108 -89.585292)
					(end 74.77506 -87.810086)
				)
			)
		)
	)
	(zone
		(layers "B.Cu" "In2.Cu")
		(hatch none 0.5)
		(connect_pads
			(clearance 0)
		)
		(min_thickness 0.25)
		(keepout
			(tracks not_allowed)
			(vias allowed)
			(pads allowed)
			(copperpour not_allowed)
			(footprints allowed)
		)
		(placement
			(enabled no)
			(sheetname "")
		)
		(fill yes
			(thermal_gap 0.5)
			(thermal_bridge_width 0.5)
			(island_removal_mode 0)
		)
		(polygon
			(pts
				(arc
					(start 74.50074 -49.621694)
					(mid 73.9902 -49.111154)
					(end 73.47966 -49.621694)
				)
				(arc
					(start 73.47966 -50.434494)
					(mid 73.98893 -50.945032)
					(end 74.50074 -50.437034)
				)
				(arc
					(start 74.2569 -50.437034)
					(mid 73.9902 -50.701206)
					(end 73.7235 -50.437034)
				)
				(arc
					(start 73.7235 -50.434494)
					(mid 73.9902 -50.167794)
					(end 74.2569 -50.434494)
				)
				(xy 74.50074 -50.434494) (xy 74.50074 -49.624234)
				(arc
					(start 74.2569 -49.624234)
					(mid 73.9902 -49.888406)
					(end 73.7235 -49.624234)
				)
				(arc
					(start 73.7235 -49.621694)
					(mid 73.9902 -49.354994)
					(end 74.2569 -49.621694)
				)
			)
		)
	)
	(zone
		(layers "B.Cu" "In2.Cu")
		(hatch none 0.5)
		(connect_pads
			(clearance 0)
		)
		(min_thickness 0.25)
		(keepout
			(tracks not_allowed)
			(vias allowed)
			(pads allowed)
			(copperpour not_allowed)
			(footprints allowed)
		)
		(placement
			(enabled no)
			(sheetname "")
		)
		(fill yes
			(thermal_gap 0.5)
			(thermal_bridge_width 0.5)
			(island_removal_mode 0)
		)
		(polygon
			(pts
				(arc
					(start 75.44054 -22.021546)
					(mid 74.93 -21.511006)
					(end 74.41946 -22.021546)
				)
				(arc
					(start 74.41946 -22.834346)
					(mid 74.92873 -23.344884)
					(end 75.44054 -22.836886)
				)
				(arc
					(start 75.1967 -22.836886)
					(mid 74.93 -23.101058)
					(end 74.6633 -22.836886)
				)
				(arc
					(start 74.6633 -22.834346)
					(mid 74.93 -22.567646)
					(end 75.1967 -22.834346)
				)
				(xy 75.44054 -22.834346) (xy 75.44054 -22.024086)
				(arc
					(start 75.1967 -22.024086)
					(mid 74.93 -22.288258)
					(end 74.6633 -22.024086)
				)
				(arc
					(start 74.6633 -22.021546)
					(mid 74.93 -21.754846)
					(end 75.1967 -22.021546)
				)
			)
		)
	)
	(zone
		(layers "B.Cu" "In5.Cu")
		(hatch none 0.5)
		(connect_pads
			(clearance 0)
		)
		(min_thickness 0.25)
		(keepout
			(tracks not_allowed)
			(vias allowed)
			(pads allowed)
			(copperpour not_allowed)
			(footprints allowed)
		)
		(placement
			(enabled no)
			(sheetname "")
		)
		(fill yes
			(thermal_gap 0.5)
			(thermal_bridge_width 0.5)
			(island_removal_mode 0)
		)
		(polygon
			(pts
				(arc
					(start 69.97954 -24.866346)
					(mid 69.3674 -24.254206)
					(end 68.75526 -24.866346)
				)
				(arc
					(start 68.75526 -25.983946)
					(mid 69.36613 -26.596085)
					(end 69.97954 -25.986486)
				)
				(arc
					(start 69.6341 -25.986486)
					(mid 69.3674 -26.250658)
					(end 69.1007 -25.986486)
				)
				(arc
					(start 69.1007 -25.983946)
					(mid 69.3674 -25.717246)
					(end 69.6341 -25.983946)
				)
				(xy 69.97954 -25.983946) (xy 69.97954 -24.868886)
				(arc
					(start 69.6341 -24.868886)
					(mid 69.3674 -25.133058)
					(end 69.1007 -24.868886)
				)
				(arc
					(start 69.1007 -24.866346)
					(mid 69.3674 -24.599646)
					(end 69.6341 -24.866346)
				)
			)
		)
	)
	(zone
		(layers "B.Cu" "In5.Cu")
		(hatch none 0.5)
		(connect_pads
			(clearance 0)
		)
		(min_thickness 0.25)
		(keepout
			(tracks not_allowed)
			(vias allowed)
			(pads allowed)
			(copperpour not_allowed)
			(footprints allowed)
		)
		(placement
			(enabled no)
			(sheetname "")
		)
		(fill yes
			(thermal_gap 0.5)
			(thermal_bridge_width 0.5)
			(island_removal_mode 0)
		)
		(polygon
			(pts
				(arc
					(start 70.48754 -27.8765)
					(mid 69.8754 -27.26436)
					(end 69.26326 -27.8765)
				)
				(arc
					(start 69.26326 -28.9941)
					(mid 69.87413 -29.606239)
					(end 70.48754 -28.99664)
				)
				(arc
					(start 70.1421 -28.99664)
					(mid 69.8754 -29.260812)
					(end 69.6087 -28.99664)
				)
				(arc
					(start 69.6087 -28.9941)
					(mid 69.8754 -28.7274)
					(end 70.1421 -28.9941)
				)
				(xy 70.48754 -28.9941) (xy 70.48754 -27.87904)
				(arc
					(start 70.1421 -27.87904)
					(mid 69.8754 -28.143212)
					(end 69.6087 -27.87904)
				)
				(arc
					(start 69.6087 -27.8765)
					(mid 69.8754 -27.6098)
					(end 70.1421 -27.8765)
				)
			)
		)
	)
	(zone
		(layers "B.Cu" "In5.Cu")
		(hatch none 0.5)
		(connect_pads
			(clearance 0)
		)
		(min_thickness 0.25)
		(keepout
			(tracks not_allowed)
			(vias allowed)
			(pads allowed)
			(copperpour not_allowed)
			(footprints allowed)
		)
		(placement
			(enabled no)
			(sheetname "")
		)
		(fill yes
			(thermal_gap 0.5)
			(thermal_bridge_width 0.5)
			(island_removal_mode 0)
		)
		(polygon
			(pts
				(arc
					(start 69.97954 -52.466494)
					(mid 69.3674 -51.854354)
					(end 68.75526 -52.466494)
				)
				(arc
					(start 68.75526 -53.584094)
					(mid 69.36613 -54.196233)
					(end 69.97954 -53.586634)
				)
				(arc
					(start 69.6341 -53.586634)
					(mid 69.3674 -53.850806)
					(end 69.1007 -53.586634)
				)
				(arc
					(start 69.1007 -53.584094)
					(mid 69.3674 -53.317394)
					(end 69.6341 -53.584094)
				)
				(xy 69.97954 -53.584094) (xy 69.97954 -52.469034)
				(arc
					(start 69.6341 -52.469034)
					(mid 69.3674 -52.733206)
					(end 69.1007 -52.469034)
				)
				(arc
					(start 69.1007 -52.466494)
					(mid 69.3674 -52.199794)
					(end 69.6341 -52.466494)
				)
			)
		)
	)
	(zone
		(layers "B.Cu" "In5.Cu")
		(hatch none 0.5)
		(connect_pads
			(clearance 0)
		)
		(min_thickness 0.25)
		(keepout
			(tracks not_allowed)
			(vias allowed)
			(pads allowed)
			(copperpour not_allowed)
			(footprints allowed)
		)
		(placement
			(enabled no)
			(sheetname "")
		)
		(fill yes
			(thermal_gap 0.5)
			(thermal_bridge_width 0.5)
			(island_removal_mode 0)
		)
		(polygon
			(pts
				(arc
					(start 69.97954 -52.4764)
					(mid 69.3674 -51.86426)
					(end 68.75526 -52.4764)
				)
				(arc
					(start 68.75526 -53.593746)
					(mid 69.366003 -54.206138)
					(end 69.97954 -53.59654)
				)
				(arc
					(start 69.6341 -53.59654)
					(mid 69.3674 -53.860712)
					(end 69.1007 -53.59654)
				)
				(arc
					(start 69.1007 -53.594)
					(mid 69.3674 -53.3273)
					(end 69.6341 -53.594)
				)
				(xy 69.97954 -53.594) (xy 69.97954 -52.47894)
				(arc
					(start 69.6341 -52.47894)
					(mid 69.3674 -52.743112)
					(end 69.1007 -52.47894)
				)
				(arc
					(start 69.1007 -52.4764)
					(mid 69.3674 -52.2097)
					(end 69.6341 -52.4764)
				)
			)
		)
	)
	(zone
		(layers "B.Cu" "In5.Cu")
		(hatch none 0.5)
		(connect_pads
			(clearance 0)
		)
		(min_thickness 0.25)
		(keepout
			(tracks not_allowed)
			(vias allowed)
			(pads allowed)
			(copperpour not_allowed)
			(footprints allowed)
		)
		(placement
			(enabled no)
			(sheetname "")
		)
		(fill yes
			(thermal_gap 0.5)
			(thermal_bridge_width 0.5)
			(island_removal_mode 0)
		)
		(polygon
			(pts
				(arc
					(start 69.97954 -24.876506)
					(mid 69.3674 -24.264366)
					(end 68.75526 -24.876506)
				)
				(arc
					(start 68.75526 -25.994106)
					(mid 69.36613 -26.606245)
					(end 69.97954 -25.996646)
				)
				(arc
					(start 69.6341 -25.996646)
					(mid 69.3674 -26.260818)
					(end 69.1007 -25.996646)
				)
				(arc
					(start 69.1007 -25.994106)
					(mid 69.3674 -25.727406)
					(end 69.6341 -25.994106)
				)
				(xy 69.97954 -25.994106) (xy 69.97954 -24.879046)
				(arc
					(start 69.6341 -24.879046)
					(mid 69.3674 -25.143218)
					(end 69.1007 -24.879046)
				)
				(arc
					(start 69.1007 -24.876506)
					(mid 69.3674 -24.609806)
					(end 69.6341 -24.876506)
				)
			)
		)
	)
	(zone
		(layers "B.Cu" "In5.Cu")
		(hatch none 0.5)
		(connect_pads
			(clearance 0)
		)
		(min_thickness 0.25)
		(keepout
			(tracks not_allowed)
			(vias allowed)
			(pads allowed)
			(copperpour not_allowed)
			(footprints allowed)
		)
		(placement
			(enabled no)
			(sheetname "")
		)
		(fill yes
			(thermal_gap 0.5)
			(thermal_bridge_width 0.5)
			(island_removal_mode 0)
		)
		(polygon
			(pts
				(arc
					(start 70.48754 -55.466488)
					(mid 69.8754 -54.854348)
					(end 69.26326 -55.466488)
				)
				(arc
					(start 69.26326 -56.584088)
					(mid 69.87413 -57.196227)
					(end 70.48754 -56.586628)
				)
				(arc
					(start 70.1421 -56.586628)
					(mid 69.8754 -56.8508)
					(end 69.6087 -56.586628)
				)
				(arc
					(start 69.6087 -56.584088)
					(mid 69.8754 -56.317388)
					(end 70.1421 -56.584088)
				)
				(xy 70.48754 -56.584088) (xy 70.48754 -55.469028)
				(arc
					(start 70.1421 -55.469028)
					(mid 69.8754 -55.7332)
					(end 69.6087 -55.469028)
				)
				(arc
					(start 69.6087 -55.466488)
					(mid 69.8754 -55.199788)
					(end 70.1421 -55.466488)
				)
			)
		)
	)
	(zone
		(layers "B.Cu" "In5.Cu")
		(hatch none 0.5)
		(connect_pads
			(clearance 0)
		)
		(min_thickness 0.25)
		(keepout
			(tracks not_allowed)
			(vias allowed)
			(pads allowed)
			(copperpour not_allowed)
			(footprints allowed)
		)
		(placement
			(enabled no)
			(sheetname "")
		)
		(fill yes
			(thermal_gap 0.5)
			(thermal_bridge_width 0.5)
			(island_removal_mode 0)
		)
		(polygon
			(pts
				(arc
					(start 70.48754 -55.476394)
					(mid 69.8754 -54.864254)
					(end 69.26326 -55.476394)
				)
				(arc
					(start 69.26326 -56.59374)
					(mid 69.874003 -57.206132)
					(end 70.48754 -56.596534)
				)
				(arc
					(start 70.1421 -56.596534)
					(mid 69.8754 -56.860706)
					(end 69.6087 -56.596534)
				)
				(arc
					(start 69.6087 -56.593994)
					(mid 69.8754 -56.327294)
					(end 70.1421 -56.593994)
				)
				(xy 70.48754 -56.593994) (xy 70.48754 -55.478934)
				(arc
					(start 70.1421 -55.478934)
					(mid 69.8754 -55.743106)
					(end 69.6087 -55.478934)
				)
				(arc
					(start 69.6087 -55.476394)
					(mid 69.8754 -55.209694)
					(end 70.1421 -55.476394)
				)
			)
		)
	)
	(zone
		(layers "B.Cu" "In5.Cu")
		(hatch none 0.5)
		(connect_pads
			(clearance 0)
		)
		(min_thickness 0.25)
		(keepout
			(tracks not_allowed)
			(vias allowed)
			(pads allowed)
			(copperpour not_allowed)
			(footprints allowed)
		)
		(placement
			(enabled no)
			(sheetname "")
		)
		(fill yes
			(thermal_gap 0.5)
			(thermal_bridge_width 0.5)
			(island_removal_mode 0)
		)
		(polygon
			(pts
				(arc
					(start 70.48754 -27.86634)
					(mid 69.8754 -27.2542)
					(end 69.26326 -27.86634)
				)
				(arc
					(start 69.26326 -28.983686)
					(mid 69.874003 -29.596078)
					(end 70.48754 -28.98648)
				)
				(arc
					(start 70.1421 -28.98648)
					(mid 69.8754 -29.250652)
					(end 69.6087 -28.98648)
				)
				(arc
					(start 69.6087 -28.98394)
					(mid 69.8754 -28.71724)
					(end 70.1421 -28.98394)
				)
				(xy 70.48754 -28.98394) (xy 70.48754 -27.86888)
				(arc
					(start 70.1421 -27.86888)
					(mid 69.8754 -28.133052)
					(end 69.6087 -27.86888)
				)
				(arc
					(start 69.6087 -27.86634)
					(mid 69.8754 -27.59964)
					(end 70.1421 -27.86634)
				)
			)
		)
	)
	(zone
		(layer "In1.Cu")
		(hatch none 0.5)
		(connect_pads
			(clearance 0)
		)
		(min_thickness 0.25)
		(keepout
			(tracks not_allowed)
			(vias allowed)
			(pads allowed)
			(copperpour not_allowed)
			(footprints allowed)
		)
		(placement
			(enabled no)
			(sheetname "")
		)
		(fill
			(thermal_gap 0.5)
			(thermal_bridge_width 0.5)
			(island_removal_mode 0)
		)
		(polygon
			(pts
				(xy 71.950326 -21.842222) (xy 73.499726 -21.842222) (xy 73.499726 -23.037546) (xy 71.950326 -23.037546)
			)
		)
	)
	(zone
		(layer "In1.Cu")
		(hatch none 0.5)
		(connect_pads
			(clearance 0)
		)
		(min_thickness 0.25)
		(keepout
			(tracks not_allowed)
			(vias allowed)
			(pads allowed)
			(copperpour not_allowed)
			(footprints allowed)
		)
		(placement
			(enabled no)
			(sheetname "")
		)
		(fill
			(thermal_gap 0.5)
			(thermal_bridge_width 0.5)
			(island_removal_mode 0)
		)
		(polygon
			(pts
				(xy 71.950326 -24.852376) (xy 73.499726 -24.852376) (xy 73.499726 -26.0477) (xy 71.950326 -26.0477)
			)
		)
	)
	(zone
		(layer "In1.Cu")
		(hatch none 0.5)
		(connect_pads
			(clearance 0)
		)
		(min_thickness 0.25)
		(keepout
			(tracks not_allowed)
			(vias allowed)
			(pads allowed)
			(copperpour not_allowed)
			(footprints allowed)
		)
		(placement
			(enabled no)
			(sheetname "")
		)
		(fill
			(thermal_gap 0.5)
			(thermal_bridge_width 0.5)
			(island_removal_mode 0)
		)
		(polygon
			(pts
				(xy 71.950326 -50.942494) (xy 73.499726 -50.942494) (xy 73.499726 -52.137564) (xy 71.950326 -52.137564)
			)
		)
	)
	(zone
		(net "GND")
		(layer "In1.Cu")
		(hatch none 0.5)
		(connect_pads
			(clearance 0.5)
		)
		(min_thickness 0.25)
		(fill yes
			(thermal_gap 0.5)
			(thermal_bridge_width 0.5)
			(island_removal_mode 0)
		)
		(polygon
			(pts
				(arc
					(start 56.850026 -0.483616)
					(mid 55.777783 -0.927753)
					(end 55.333646 -1.999996)
				)
				(arc
					(start 55.333646 -65.550034)
					(mid 54.606213 -67.306213)
					(end 52.850034 -68.033646)
				)
				(arc
					(start 1.999996 -68.033646)
					(mid 0.927753 -68.477783)
					(end 0.483616 -69.550026)
				)
				(arc
					(start 0.483616 -90.309954)
					(mid 0.927753 -91.382197)
					(end 1.999996 -91.826334)
				)
				(arc
					(start 86.74989 -91.826334)
					(mid 87.822133 -91.382197)
					(end 88.26627 -90.309954)
				)
				(arc
					(start 88.26627 -70.809866)
					(mid 88.261509 -70.798371)
					(end 88.250014 -70.79361)
				)
				(arc
					(start 86.249764 -70.79361)
					(mid 85.554407 -70.505479)
					(end 85.266276 -69.810122)
				)
				(arc
					(start 85.266276 -55.770018)
					(mid 85.554407 -55.074407)
					(end 86.250018 -54.786276)
				)
				(arc
					(start 88.250014 -54.786276)
					(mid 88.261509 -54.781515)
					(end 88.26627 -54.77002)
				)
				(arc
					(start 88.26627 -49.76495)
					(mid 88.261509 -49.753455)
					(end 88.250014 -49.748694)
				)
				(arc
					(start 81.549748 -49.748694)
					(mid 80.854391 -49.460563)
					(end 80.56626 -48.765206)
				)
				(arc
					(start 80.56626 -44.515024)
					(mid 80.854391 -43.819413)
					(end 81.550002 -43.531282)
				)
				(arc
					(start 82.850228 -43.531282)
					(mid 82.86165 -43.526448)
					(end 82.866484 -43.515026)
				)
				(arc
					(start 82.866484 -43.362118)
					(mid 82.454617 -43.424945)
					(end 82.228436 -43.075098)
				)
				(arc
					(start 82.228436 -42.274998)
					(mid 82.454645 -41.925213)
					(end 82.866484 -41.987978)
				)
				(arc
					(start 82.866484 -40.962072)
					(mid 82.454617 -41.024899)
					(end 82.228436 -40.675052)
				)
				(arc
					(start 82.228436 -39.874952)
					(mid 82.454645 -39.525167)
					(end 82.866484 -39.587932)
				)
				(arc
					(start 82.866484 -38.562026)
					(mid 82.454617 -38.624853)
					(end 82.228436 -38.275006)
				)
				(arc
					(start 82.228436 -37.47516)
					(mid 82.454645 -37.125375)
					(end 82.866484 -37.18814)
				)
				(arc
					(start 82.866484 -28.161996)
					(mid 82.454617 -28.224823)
					(end 82.228436 -27.874976)
				)
				(arc
					(start 82.228436 -27.07513)
					(mid 82.454645 -26.725345)
					(end 82.866484 -26.78811)
				)
				(arc
					(start 82.866484 -25.762204)
					(mid 82.454617 -25.825031)
					(end 82.228436 -25.475184)
				)
				(arc
					(start 82.228436 -24.675084)
					(mid 82.454645 -24.325299)
					(end 82.866484 -24.388064)
				)
				(arc
					(start 82.866484 -23.362158)
					(mid 82.454617 -23.424985)
					(end 82.228436 -23.075138)
				)
				(arc
					(start 82.228436 -22.275038)
					(mid 82.454645 -21.925253)
					(end 82.866484 -21.988018)
				)
				(arc
					(start 82.866484 -20.962112)
					(mid 82.454733 -21.024991)
					(end 82.228436 -20.675346)
				)
				(arc
					(start 82.228436 -19.874992)
					(mid 82.454645 -19.525207)
					(end 82.866484 -19.587972)
				)
				(arc
					(start 82.866484 -18.562066)
					(mid 82.454617 -18.624893)
					(end 82.228436 -18.275046)
				)
				(arc
					(start 82.228436 -17.474946)
					(mid 82.454645 -17.125161)
					(end 82.866484 -17.187926)
				)
				(arc
					(start 82.866484 -16.16202)
					(mid 82.454733 -16.224899)
					(end 82.228436 -15.875254)
				)
				(arc
					(start 82.228436 -15.075154)
					(mid 82.454645 -14.725369)
					(end 82.866484 -14.788134)
				)
				(arc
					(start 82.866484 -11.685016)
					(mid 82.861648 -11.673342)
					(end 82.849974 -11.668506)
				)
				(arc
					(start 81.549748 -11.668506)
					(mid 80.854391 -11.380375)
					(end 80.56626 -10.685018)
				)
				(arc
					(start 80.56626 -6.434836)
					(mid 80.854391 -5.739479)
					(end 81.549748 -5.451348)
				)
				(arc
					(start 88.250014 -5.451348)
					(mid 88.261509 -5.446587)
					(end 88.26627 -5.435092)
				)
				(arc
					(start 88.26627 -0.499872)
					(mid 88.261509 -0.488377)
					(end 88.250014 -0.483616)
				)
			)
		)
		(polygon
			(pts
				(xy 73.499726 -55.442358) (xy 71.950326 -55.442358) (xy 71.950326 -56.637682) (xy 73.499726 -56.637682)
			)
		)
		(polygon
			(pts
				(arc
					(start 70.48754 -55.466234)
					(mid 69.875273 -54.854348)
					(end 69.26326 -55.466488)
				)
				(arc
					(start 69.26326 -56.594248)
					(mid 69.875527 -57.206134)
					(end 70.48754 -56.593994)
				)
			)
		)
		(polygon
			(pts
				(xy 73.499726 -53.942488) (xy 71.950326 -53.942488) (xy 71.950326 -55.137558) (xy 73.499726 -55.137558)
			)
		)
		(polygon
			(pts
				(xy 73.499726 -52.442364) (xy 71.950326 -52.442364) (xy 71.950326 -53.637688) (xy 73.499726 -53.637688)
			)
		)
		(polygon
			(pts
				(arc
					(start 69.97954 -52.46624)
					(mid 69.367273 -51.854354)
					(end 68.75526 -52.466494)
				)
				(arc
					(start 68.75526 -53.594254)
					(mid 69.367527 -54.20614)
					(end 69.97954 -53.594)
				)
			)
		)
		(polygon
			(pts
				(xy 73.499726 -50.942494) (xy 71.950326 -50.942494) (xy 71.950326 -52.137564) (xy 73.499726 -52.137564)
			)
		)
		(polygon
			(pts
				(arc
					(start 74.50074 -49.62144)
					(mid 74.061647 -49.116178)
					(end 73.499726 -49.479962)
				)
				(xy 73.499726 -49.44237) (xy 71.950326 -49.44237) (xy 71.950326 -50.637694) (xy 73.499726 -50.637694)
				(arc
					(start 73.499726 -50.576226)
					(mid 74.061773 -50.939994)
					(end 74.50074 -50.434494)
				)
			)
		)
		(polygon
			(pts
				(arc
					(start 77.52334 -33.691068)
					(mid 76.911073 -33.079182)
					(end 76.29906 -33.691322)
				)
				(arc
					(start 76.29906 -34.808922)
					(mid 76.9112 -35.421062)
					(end 77.52334 -34.808922)
				)
			)
		)
		(polygon
			(pts
				(xy 73.499726 -27.85237) (xy 71.950326 -27.85237) (xy 71.950326 -29.047694) (xy 73.499726 -29.047694)
			)
		)
		(polygon
			(pts
				(arc
					(start 70.48754 -27.86634)
					(mid 69.8754 -27.2542)
					(end 69.26326 -27.86634)
				)
				(arc
					(start 69.26326 -28.9941)
					(mid 69.8754 -29.60624)
					(end 70.48754 -28.9941)
				)
			)
		)
		(polygon
			(pts
				(xy 73.499726 -26.3525) (xy 71.950326 -26.3525) (xy 71.950326 -27.54757) (xy 73.499726 -27.54757)
			)
		)
		(polygon
			(pts
				(xy 73.499726 -24.852376) (xy 71.950326 -24.852376) (xy 71.950326 -26.0477) (xy 73.499726 -26.0477)
			)
		)
		(polygon
			(pts
				(arc
					(start 69.97954 -24.866092)
					(mid 69.367273 -24.254206)
					(end 68.75526 -24.866346)
				)
				(arc
					(start 68.75526 -25.994106)
					(mid 69.3674 -26.606246)
					(end 69.97954 -25.994106)
				)
			)
		)
		(polygon
			(pts
				(xy 73.499726 -23.352506) (xy 71.950326 -23.352506) (xy 71.950326 -24.547576) (xy 73.499726 -24.547576)
			)
		)
		(polygon
			(pts
				(xy 73.499726 -21.842222) (xy 71.950326 -21.842222) (xy 71.950326 -23.037546) (xy 73.499726 -23.037546)
			)
		)
		(polygon
			(pts
				(arc
					(start 75.44054 -22.021292)
					(mid 74.929873 -21.511006)
					(end 74.41946 -22.021546)
				)
				(arc
					(start 74.41946 -22.834346)
					(mid 74.93 -23.344886)
					(end 75.44054 -22.834346)
				)
			)
		)
	)
	(zone
		(layer "In1.Cu")
		(hatch none 0.5)
		(connect_pads
			(clearance 0)
		)
		(min_thickness 0.25)
		(keepout
			(tracks not_allowed)
			(vias allowed)
			(pads allowed)
			(copperpour not_allowed)
			(footprints allowed)
		)
		(placement
			(enabled no)
			(sheetname "")
		)
		(fill
			(thermal_gap 0.5)
			(thermal_bridge_width 0.5)
			(island_removal_mode 0)
		)
		(polygon
			(pts
				(xy 71.950326 -55.442358) (xy 73.499726 -55.442358) (xy 73.499726 -56.637682) (xy 71.950326 -56.637682)
			)
		)
	)
	(zone
		(layer "In1.Cu")
		(hatch none 0.5)
		(connect_pads
			(clearance 0)
		)
		(min_thickness 0.25)
		(keepout
			(tracks not_allowed)
			(vias allowed)
			(pads allowed)
			(copperpour not_allowed)
			(footprints allowed)
		)
		(placement
			(enabled no)
			(sheetname "")
		)
		(fill
			(thermal_gap 0.5)
			(thermal_bridge_width 0.5)
			(island_removal_mode 0)
		)
		(polygon
			(pts
				(xy 71.950326 -49.44237) (xy 73.499726 -49.44237) (xy 73.499726 -50.637694) (xy 71.950326 -50.637694)
			)
		)
	)
	(zone
		(layer "In1.Cu")
		(hatch none 0.5)
		(connect_pads
			(clearance 0)
		)
		(min_thickness 0.25)
		(keepout
			(tracks not_allowed)
			(vias allowed)
			(pads allowed)
			(copperpour not_allowed)
			(footprints allowed)
		)
		(placement
			(enabled no)
			(sheetname "")
		)
		(fill
			(thermal_gap 0.5)
			(thermal_bridge_width 0.5)
			(island_removal_mode 0)
		)
		(polygon
			(pts
				(xy 71.950326 -23.352506) (xy 73.499726 -23.352506) (xy 73.499726 -24.547576) (xy 71.950326 -24.547576)
			)
		)
	)
	(zone
		(layer "In1.Cu")
		(hatch none 0.5)
		(connect_pads
			(clearance 0)
		)
		(min_thickness 0.25)
		(keepout
			(tracks not_allowed)
			(vias allowed)
			(pads allowed)
			(copperpour not_allowed)
			(footprints allowed)
		)
		(placement
			(enabled no)
			(sheetname "")
		)
		(fill
			(thermal_gap 0.5)
			(thermal_bridge_width 0.5)
			(island_removal_mode 0)
		)
		(polygon
			(pts
				(xy 71.950326 -26.3525) (xy 73.499726 -26.3525) (xy 73.499726 -27.54757) (xy 71.950326 -27.54757)
			)
		)
	)
	(zone
		(layer "In1.Cu")
		(hatch none 0.5)
		(connect_pads
			(clearance 0)
		)
		(min_thickness 0.25)
		(keepout
			(tracks not_allowed)
			(vias allowed)
			(pads allowed)
			(copperpour not_allowed)
			(footprints allowed)
		)
		(placement
			(enabled no)
			(sheetname "")
		)
		(fill
			(thermal_gap 0.5)
			(thermal_bridge_width 0.5)
			(island_removal_mode 0)
		)
		(polygon
			(pts
				(xy 71.950326 -52.442364) (xy 73.499726 -52.442364) (xy 73.499726 -53.637688) (xy 71.950326 -53.637688)
			)
		)
	)
	(zone
		(layer "In1.Cu")
		(hatch none 0.5)
		(connect_pads
			(clearance 0)
		)
		(min_thickness 0.25)
		(keepout
			(tracks not_allowed)
			(vias allowed)
			(pads allowed)
			(copperpour not_allowed)
			(footprints allowed)
		)
		(placement
			(enabled no)
			(sheetname "")
		)
		(fill
			(thermal_gap 0.5)
			(thermal_bridge_width 0.5)
			(island_removal_mode 0)
		)
		(polygon
			(pts
				(xy 71.950326 -27.85237) (xy 73.499726 -27.85237) (xy 73.499726 -29.047694) (xy 71.950326 -29.047694)
			)
		)
	)
	(zone
		(layer "In1.Cu")
		(hatch none 0.5)
		(connect_pads
			(clearance 0)
		)
		(min_thickness 0.25)
		(keepout
			(tracks not_allowed)
			(vias allowed)
			(pads allowed)
			(copperpour not_allowed)
			(footprints allowed)
		)
		(placement
			(enabled no)
			(sheetname "")
		)
		(fill
			(thermal_gap 0.5)
			(thermal_bridge_width 0.5)
			(island_removal_mode 0)
		)
		(polygon
			(pts
				(xy 71.950326 -53.942488) (xy 73.499726 -53.942488) (xy 73.499726 -55.137558) (xy 71.950326 -55.137558)
			)
		)
	)
	(zone
		(layers "In1.Cu" "In3.Cu" "In4.Cu" "In6.Cu")
		(hatch none 0.5)
		(connect_pads
			(clearance 0)
		)
		(min_thickness 0.25)
		(keepout
			(tracks not_allowed)
			(vias allowed)
			(pads allowed)
			(copperpour not_allowed)
			(footprints allowed)
		)
		(placement
			(enabled no)
			(sheetname "")
		)
		(fill yes
			(thermal_gap 0.5)
			(thermal_bridge_width 0.5)
			(island_removal_mode 0)
		)
		(polygon
			(pts
				(arc
					(start 82.995516 -39.875206)
					(mid 82.612103 -39.491412)
					(end 82.228436 -39.874952)
				)
				(arc
					(start 82.228436 -40.675052)
					(mid 82.611976 -41.058592)
					(end 82.995516 -40.675052)
				)
			)
		)
	)
	(zone
		(layers "In1.Cu" "In3.Cu" "In4.Cu" "In6.Cu")
		(hatch none 0.5)
		(connect_pads
			(clearance 0)
		)
		(min_thickness 0.25)
		(keepout
			(tracks not_allowed)
			(vias allowed)
			(pads allowed)
			(copperpour not_allowed)
			(footprints allowed)
		)
		(placement
			(enabled no)
			(sheetname "")
		)
		(fill yes
			(thermal_gap 0.5)
			(thermal_bridge_width 0.5)
			(island_removal_mode 0)
		)
		(polygon
			(pts
				(arc
					(start 69.97954 -24.8666)
					(mid 69.367527 -24.254206)
					(end 68.75526 -24.866346)
				)
				(arc
					(start 68.75526 -25.983946)
					(mid 69.3674 -26.596086)
					(end 69.97954 -25.983946)
				)
			)
		)
	)
	(zone
		(layers "In1.Cu" "In3.Cu" "In4.Cu" "In6.Cu")
		(hatch none 0.5)
		(connect_pads
			(clearance 0)
		)
		(min_thickness 0.25)
		(keepout
			(tracks not_allowed)
			(vias allowed)
			(pads allowed)
			(copperpour not_allowed)
			(footprints allowed)
		)
		(placement
			(enabled no)
			(sheetname "")
		)
		(fill yes
			(thermal_gap 0.5)
			(thermal_bridge_width 0.5)
			(island_removal_mode 0)
		)
		(polygon
			(pts
				(arc
					(start 82.995516 -24.675338)
					(mid 82.612103 -24.291544)
					(end 82.228436 -24.675084)
				)
				(arc
					(start 82.228436 -25.475184)
					(mid 82.611976 -25.858724)
					(end 82.995516 -25.475184)
				)
			)
		)
	)
	(zone
		(layers "In1.Cu" "In3.Cu" "In4.Cu" "In6.Cu")
		(hatch none 0.5)
		(connect_pads
			(clearance 0)
		)
		(min_thickness 0.25)
		(keepout
			(tracks not_allowed)
			(vias allowed)
			(pads allowed)
			(copperpour not_allowed)
			(footprints allowed)
		)
		(placement
			(enabled no)
			(sheetname "")
		)
		(fill yes
			(thermal_gap 0.5)
			(thermal_bridge_width 0.5)
			(island_removal_mode 0)
		)
		(polygon
			(pts
				(arc
					(start 82.995516 -17.4752)
					(mid 82.612103 -17.091406)
					(end 82.228436 -17.474946)
				)
				(arc
					(start 82.228436 -18.275046)
					(mid 82.611976 -18.658586)
					(end 82.995516 -18.275046)
				)
			)
		)
	)
	(zone
		(layers "In1.Cu" "In3.Cu" "In4.Cu" "In6.Cu")
		(hatch none 0.5)
		(connect_pads
			(clearance 0)
		)
		(min_thickness 0.25)
		(keepout
			(tracks not_allowed)
			(vias allowed)
			(pads allowed)
			(copperpour not_allowed)
			(footprints allowed)
		)
		(placement
			(enabled no)
			(sheetname "")
		)
		(fill yes
			(thermal_gap 0.5)
			(thermal_bridge_width 0.5)
			(island_removal_mode 0)
		)
		(polygon
			(pts
				(arc
					(start 70.48754 -27.876754)
					(mid 69.875527 -27.26436)
					(end 69.26326 -27.8765)
				)
				(arc
					(start 69.26326 -28.9941)
					(mid 69.8754 -29.60624)
					(end 70.48754 -28.9941)
				)
			)
		)
	)
	(zone
		(layers "In1.Cu" "In3.Cu" "In4.Cu" "In6.Cu")
		(hatch none 0.5)
		(connect_pads
			(clearance 0)
		)
		(min_thickness 0.25)
		(keepout
			(tracks not_allowed)
			(vias allowed)
			(pads allowed)
			(copperpour not_allowed)
			(footprints allowed)
		)
		(placement
			(enabled no)
			(sheetname "")
		)
		(fill yes
			(thermal_gap 0.5)
			(thermal_bridge_width 0.5)
			(island_removal_mode 0)
		)
		(polygon
			(pts
				(arc
					(start 82.995516 -15.075154)
					(mid 82.611976 -14.691614)
					(end 82.228436 -15.075154)
				)
				(arc
					(start 82.228436 -15.874746)
					(mid 82.611849 -16.25854)
					(end 82.995516 -15.875)
				)
			)
		)
	)
	(zone
		(layers "In1.Cu" "In3.Cu" "In4.Cu" "In6.Cu")
		(hatch none 0.5)
		(connect_pads
			(clearance 0)
		)
		(min_thickness 0.25)
		(keepout
			(tracks not_allowed)
			(vias allowed)
			(pads allowed)
			(copperpour not_allowed)
			(footprints allowed)
		)
		(placement
			(enabled no)
			(sheetname "")
		)
		(fill yes
			(thermal_gap 0.5)
			(thermal_bridge_width 0.5)
			(island_removal_mode 0)
		)
		(polygon
			(pts
				(arc
					(start 82.995516 -19.874992)
					(mid 82.611976 -19.491452)
					(end 82.228436 -19.874992)
				)
				(arc
					(start 82.228436 -20.674838)
					(mid 82.611849 -21.058632)
					(end 82.995516 -20.675092)
				)
			)
		)
	)
	(zone
		(layers "In1.Cu" "In3.Cu" "In4.Cu" "In6.Cu")
		(hatch none 0.5)
		(connect_pads
			(clearance 0)
		)
		(min_thickness 0.25)
		(keepout
			(tracks not_allowed)
			(vias allowed)
			(pads allowed)
			(copperpour not_allowed)
			(footprints allowed)
		)
		(placement
			(enabled no)
			(sheetname "")
		)
		(fill yes
			(thermal_gap 0.5)
			(thermal_bridge_width 0.5)
			(island_removal_mode 0)
		)
		(polygon
			(pts
				(arc
					(start 82.995516 -42.275252)
					(mid 82.612103 -41.891458)
					(end 82.228436 -42.274998)
				)
				(arc
					(start 82.228436 -43.075098)
					(mid 82.611976 -43.458638)
					(end 82.995516 -43.075098)
				)
			)
		)
	)
	(zone
		(layers "In1.Cu" "In3.Cu" "In4.Cu" "In6.Cu")
		(hatch none 0.5)
		(connect_pads
			(clearance 0)
		)
		(min_thickness 0.25)
		(keepout
			(tracks not_allowed)
			(vias allowed)
			(pads allowed)
			(copperpour not_allowed)
			(footprints allowed)
		)
		(placement
			(enabled no)
			(sheetname "")
		)
		(fill yes
			(thermal_gap 0.5)
			(thermal_bridge_width 0.5)
			(island_removal_mode 0)
		)
		(polygon
			(pts
				(arc
					(start 69.97954 -52.4764)
					(mid 69.3674 -51.86426)
					(end 68.75526 -52.4764)
				)
				(arc
					(start 68.75526 -53.593746)
					(mid 69.367273 -54.20614)
					(end 69.97954 -53.594)
				)
			)
		)
	)
	(zone
		(layers "In1.Cu" "In3.Cu" "In4.Cu" "In6.Cu")
		(hatch none 0.5)
		(connect_pads
			(clearance 0)
		)
		(min_thickness 0.25)
		(keepout
			(tracks not_allowed)
			(vias allowed)
			(pads allowed)
			(copperpour not_allowed)
			(footprints allowed)
		)
		(placement
			(enabled no)
			(sheetname "")
		)
		(fill yes
			(thermal_gap 0.5)
			(thermal_bridge_width 0.5)
			(island_removal_mode 0)
		)
		(polygon
			(pts
				(arc
					(start 70.48754 -55.466742)
					(mid 69.875527 -54.854348)
					(end 69.26326 -55.466488)
				)
				(arc
					(start 69.26326 -56.584088)
					(mid 69.8754 -57.196228)
					(end 70.48754 -56.584088)
				)
			)
		)
	)
	(zone
		(layers "In1.Cu" "In3.Cu" "In4.Cu" "In6.Cu")
		(hatch none 0.5)
		(connect_pads
			(clearance 0)
		)
		(min_thickness 0.25)
		(keepout
			(tracks not_allowed)
			(vias allowed)
			(pads allowed)
			(copperpour not_allowed)
			(footprints allowed)
		)
		(placement
			(enabled no)
			(sheetname "")
		)
		(fill yes
			(thermal_gap 0.5)
			(thermal_bridge_width 0.5)
			(island_removal_mode 0)
		)
		(polygon
			(pts
				(arc
					(start 82.995516 -22.275292)
					(mid 82.612103 -21.891498)
					(end 82.228436 -22.275038)
				)
				(arc
					(start 82.228436 -23.075138)
					(mid 82.611976 -23.458678)
					(end 82.995516 -23.075138)
				)
			)
		)
	)
	(zone
		(layers "In1.Cu" "In3.Cu" "In4.Cu" "In6.Cu")
		(hatch none 0.5)
		(connect_pads
			(clearance 0)
		)
		(min_thickness 0.25)
		(keepout
			(tracks not_allowed)
			(vias allowed)
			(pads allowed)
			(copperpour not_allowed)
			(footprints allowed)
		)
		(placement
			(enabled no)
			(sheetname "")
		)
		(fill yes
			(thermal_gap 0.5)
			(thermal_bridge_width 0.5)
			(island_removal_mode 0)
		)
		(polygon
			(pts
				(arc
					(start 75.44054 -22.0218)
					(mid 74.930127 -21.511006)
					(end 74.41946 -22.021546)
				)
				(arc
					(start 74.41946 -22.834346)
					(mid 74.93 -23.344886)
					(end 75.44054 -22.834346)
				)
			)
		)
	)
	(zone
		(layers "In1.Cu" "In3.Cu" "In4.Cu" "In6.Cu")
		(hatch none 0.5)
		(connect_pads
			(clearance 0)
		)
		(min_thickness 0.25)
		(keepout
			(tracks not_allowed)
			(vias allowed)
			(pads allowed)
			(copperpour not_allowed)
			(footprints allowed)
		)
		(placement
			(enabled no)
			(sheetname "")
		)
		(fill yes
			(thermal_gap 0.5)
			(thermal_bridge_width 0.5)
			(island_removal_mode 0)
		)
		(polygon
			(pts
				(arc
					(start 77.52334 -33.691576)
					(mid 76.911327 -33.079182)
					(end 76.29906 -33.691322)
				)
				(arc
					(start 76.29906 -34.808922)
					(mid 76.9112 -35.421062)
					(end 77.52334 -34.808922)
				)
			)
		)
	)
	(zone
		(layers "In1.Cu" "In3.Cu" "In4.Cu" "In6.Cu")
		(hatch none 0.5)
		(connect_pads
			(clearance 0)
		)
		(min_thickness 0.25)
		(keepout
			(tracks not_allowed)
			(vias allowed)
			(pads allowed)
			(copperpour not_allowed)
			(footprints allowed)
		)
		(placement
			(enabled no)
			(sheetname "")
		)
		(fill yes
			(thermal_gap 0.5)
			(thermal_bridge_width 0.5)
			(island_removal_mode 0)
		)
		(polygon
			(pts
				(arc
					(start 69.97954 -52.466748)
					(mid 69.367527 -51.854354)
					(end 68.75526 -52.466494)
				)
				(arc
					(start 68.75526 -53.584094)
					(mid 69.3674 -54.196234)
					(end 69.97954 -53.584094)
				)
			)
		)
	)
	(zone
		(layers "In1.Cu" "In3.Cu" "In4.Cu" "In6.Cu")
		(hatch none 0.5)
		(connect_pads
			(clearance 0)
		)
		(min_thickness 0.25)
		(keepout
			(tracks not_allowed)
			(vias allowed)
			(pads allowed)
			(copperpour not_allowed)
			(footprints allowed)
		)
		(placement
			(enabled no)
			(sheetname "")
		)
		(fill yes
			(thermal_gap 0.5)
			(thermal_bridge_width 0.5)
			(island_removal_mode 0)
		)
		(polygon
			(pts
				(arc
					(start 70.48754 -27.86634)
					(mid 69.8754 -27.2542)
					(end 69.26326 -27.86634)
				)
				(arc
					(start 69.26326 -28.983686)
					(mid 69.875273 -29.59608)
					(end 70.48754 -28.98394)
				)
			)
		)
	)
	(zone
		(layers "In1.Cu" "In3.Cu" "In4.Cu" "In6.Cu")
		(hatch none 0.5)
		(connect_pads
			(clearance 0)
		)
		(min_thickness 0.25)
		(keepout
			(tracks not_allowed)
			(vias allowed)
			(pads allowed)
			(copperpour not_allowed)
			(footprints allowed)
		)
		(placement
			(enabled no)
			(sheetname "")
		)
		(fill yes
			(thermal_gap 0.5)
			(thermal_bridge_width 0.5)
			(island_removal_mode 0)
		)
		(polygon
			(pts
				(arc
					(start 82.995516 -27.075384)
					(mid 82.612103 -26.69159)
					(end 82.228436 -27.07513)
				)
				(arc
					(start 82.228436 -27.874976)
					(mid 82.611976 -28.258516)
					(end 82.995516 -27.874976)
				)
			)
		)
	)
	(zone
		(layers "In1.Cu" "In3.Cu" "In4.Cu" "In6.Cu")
		(hatch none 0.5)
		(connect_pads
			(clearance 0)
		)
		(min_thickness 0.25)
		(keepout
			(tracks not_allowed)
			(vias allowed)
			(pads allowed)
			(copperpour not_allowed)
			(footprints allowed)
		)
		(placement
			(enabled no)
			(sheetname "")
		)
		(fill yes
			(thermal_gap 0.5)
			(thermal_bridge_width 0.5)
			(island_removal_mode 0)
		)
		(polygon
			(pts
				(arc
					(start 69.97954 -24.87676)
					(mid 69.367527 -24.264366)
					(end 68.75526 -24.876506)
				)
				(arc
					(start 68.75526 -25.994106)
					(mid 69.3674 -26.606246)
					(end 69.97954 -25.994106)
				)
			)
		)
	)
	(zone
		(layers "In1.Cu" "In3.Cu" "In4.Cu" "In6.Cu")
		(hatch none 0.5)
		(connect_pads
			(clearance 0)
		)
		(min_thickness 0.25)
		(keepout
			(tracks not_allowed)
			(vias allowed)
			(pads allowed)
			(copperpour not_allowed)
			(footprints allowed)
		)
		(placement
			(enabled no)
			(sheetname "")
		)
		(fill yes
			(thermal_gap 0.5)
			(thermal_bridge_width 0.5)
			(island_removal_mode 0)
		)
		(polygon
			(pts
				(arc
					(start 70.48754 -55.476394)
					(mid 69.8754 -54.864254)
					(end 69.26326 -55.476394)
				)
				(arc
					(start 69.26326 -56.59374)
					(mid 69.875273 -57.206134)
					(end 70.48754 -56.593994)
				)
			)
		)
	)
	(zone
		(layers "In1.Cu" "In3.Cu" "In4.Cu" "In6.Cu")
		(hatch none 0.5)
		(connect_pads
			(clearance 0)
		)
		(min_thickness 0.25)
		(keepout
			(tracks not_allowed)
			(vias allowed)
			(pads allowed)
			(copperpour not_allowed)
			(footprints allowed)
		)
		(placement
			(enabled no)
			(sheetname "")
		)
		(fill yes
			(thermal_gap 0.5)
			(thermal_bridge_width 0.5)
			(island_removal_mode 0)
		)
		(polygon
			(pts
				(arc
					(start 74.50074 -49.621948)
					(mid 73.990327 -49.111154)
					(end 73.47966 -49.621694)
				)
				(arc
					(start 73.47966 -50.434494)
					(mid 73.9902 -50.945034)
					(end 74.50074 -50.434494)
				)
			)
		)
	)
	(zone
		(layer "In2.Cu")
		(hatch none 0.5)
		(connect_pads
			(clearance 0)
		)
		(min_thickness 0.25)
		(keepout
			(tracks not_allowed)
			(vias allowed)
			(pads allowed)
			(copperpour not_allowed)
			(footprints allowed)
		)
		(placement
			(enabled no)
			(sheetname "")
		)
		(fill
			(thermal_gap 0.5)
			(thermal_bridge_width 0.5)
			(island_removal_mode 0)
		)
		(polygon
			(pts
				(arc
					(start 82.995516 -19.874992)
					(mid 82.611976 -19.491452)
					(end 82.228436 -19.874992)
				)
				(arc
					(start 82.228436 -20.009358)
					(mid 82.295027 -19.988013)
					(end 82.359246 -19.960336)
				)
				(arc
					(start 82.359246 -19.960336)
					(mid 82.826575 -19.716911)
					(end 82.454496 -20.09013)
				)
				(arc
					(start 82.454496 -20.09013)
					(mid 82.34431 -20.139298)
					(end 82.228436 -20.172934)
				)
				(arc
					(start 82.228436 -20.377658)
					(mid 82.344158 -20.41107)
					(end 82.454242 -20.459954)
				)
				(arc
					(start 82.454242 -20.459954)
					(mid 82.827252 -20.832037)
					(end 82.359246 -20.590002)
				)
				(arc
					(start 82.359246 -20.590002)
					(mid 82.295026 -20.562329)
					(end 82.228436 -20.54098)
				)
				(arc
					(start 82.228436 -20.674838)
					(mid 82.611849 -21.058632)
					(end 82.995516 -20.675092)
				)
			)
		)
	)
	(zone
		(net "P12V")
		(layer "In2.Cu")
		(hatch none 0.5)
		(connect_pads
			(clearance 0.5)
		)
		(min_thickness 0.25)
		(fill yes
			(thermal_gap 0.5)
			(thermal_bridge_width 0.5)
			(island_removal_mode 0)
		)
		(polygon
			(pts
				(xy 33.274 -78.486) (xy 37.592 -78.486) (xy 37.719 -78.359) (xy 37.719 -74.549) (xy 37.846 -74.422)
				(xy 38.227 -74.041) (xy 65.151 -74.041) (xy 66.548 -72.644) (xy 66.548 -16.129) (xy 67.564 -15.113)
				(xy 74.803 -15.113) (xy 75.057 -14.859) (xy 77.597 -14.859) (xy 77.724 -14.732) (xy 77.724 -10.922)
				(xy 77.724 -10.033) (xy 77.724 -9.779) (xy 77.47 -9.525) (xy 59.182 -9.525) (xy 58.928 -9.779) (xy 58.928 -64.008)
				(xy 58.801 -64.135) (xy 54.356 -68.58) (xy 54.102 -68.58) (xy 33.401 -68.58) (xy 33.02 -68.58) (xy 32.766 -68.834)
				(xy 32.766 -78.232) (xy 33.02 -78.486)
			)
		)
	)
	(zone
		(layer "In2.Cu")
		(hatch none 0.5)
		(connect_pads
			(clearance 0)
		)
		(min_thickness 0.25)
		(keepout
			(tracks not_allowed)
			(vias allowed)
			(pads allowed)
			(copperpour not_allowed)
			(footprints allowed)
		)
		(placement
			(enabled no)
			(sheetname "")
		)
		(fill
			(thermal_gap 0.5)
			(thermal_bridge_width 0.5)
			(island_removal_mode 0)
		)
		(polygon
			(pts
				(xy 70.48754 -56.117744) (xy 70.48754 -55.952898) (xy 70.485 -55.952898) (xy 70.472808 -55.952644)
				(xy 70.452234 -55.952644)
				(arc
					(start 70.451218 -55.951882)
					(mid 70.258062 -55.907685)
					(end 70.090284 -55.802276)
				)
				(xy 70.089268 -55.802276) (xy 70.074536 -55.787798) (xy 70.0659 -55.779162) (xy 70.062852 -55.77586)
				(arc
					(start 69.992748 -55.70601)
					(mid 69.692052 -55.272775)
					(end 70.108064 -55.59679)
				)
				(xy 70.174866 -55.663846)
				(arc
					(start 70.178168 -55.666894)
					(mid 70.318959 -55.760874)
					(end 70.485 -55.793894)
				)
				(xy 70.48754 -55.793894)
				(arc
					(start 70.48754 -55.466742)
					(mid 69.875527 -54.854348)
					(end 69.26326 -55.466488)
				)
				(arc
					(start 69.26326 -56.584088)
					(mid 69.8754 -57.196228)
					(end 70.48754 -56.584088)
				)
				(xy 70.48754 -56.276748)
				(arc
					(start 70.485 -56.276748)
					(mid 70.318785 -56.30981)
					(end 70.177914 -56.404002)
				)
				(xy 70.174612 -56.407304)
				(arc
					(start 70.114922 -56.466994)
					(mid 69.681039 -56.766773)
					(end 70.005956 -56.351424)
				)
				(xy 70.062598 -56.294782) (xy 70.065646 -56.291734) (xy 70.07479 -56.28259) (xy 70.089014 -56.268366)
				(arc
					(start 70.09003 -56.268366)
					(mid 70.257946 -56.162954)
					(end 70.451218 -56.11876)
				)
				(xy 70.452234 -56.117744) (xy 70.472808 -56.117744) (xy 70.485 -56.117744)
			)
		)
	)
	(zone
		(layer "In2.Cu")
		(hatch none 0.5)
		(connect_pads
			(clearance 0)
		)
		(min_thickness 0.25)
		(keepout
			(tracks not_allowed)
			(vias allowed)
			(pads allowed)
			(copperpour not_allowed)
			(footprints allowed)
		)
		(placement
			(enabled no)
			(sheetname "")
		)
		(fill
			(thermal_gap 0.5)
			(thermal_bridge_width 0.5)
			(island_removal_mode 0)
		)
		(polygon
			(pts
				(arc
					(start 70.48754 -27.86634)
					(mid 69.8754 -27.2542)
					(end 69.26326 -27.86634)
				)
				(arc
					(start 69.26326 -28.983686)
					(mid 69.875273 -29.59608)
					(end 70.48754 -28.98394)
				)
				(xy 70.48754 -28.666694)
				(arc
					(start 70.485 -28.666694)
					(mid 70.318785 -28.699756)
					(end 70.177914 -28.793948)
				)
				(xy 70.174612 -28.79725)
				(arc
					(start 70.11162 -28.860242)
					(mid 69.6862 -29.171988)
					(end 69.999352 -28.74772)
				)
				(xy 70.062598 -28.684728) (xy 70.065646 -28.68168) (xy 70.07479 -28.672536) (xy 70.089014 -28.658312)
				(arc
					(start 70.09003 -28.658312)
					(mid 70.257946 -28.5529)
					(end 70.451218 -28.508706)
				)
				(xy 70.452234 -28.507944) (xy 70.472808 -28.507944) (xy 70.485 -28.50769) (xy 70.48754 -28.50769)
				(xy 70.48754 -28.342844) (xy 70.485 -28.342844) (xy 70.472808 -28.342844) (xy 70.452234 -28.342844)
				(arc
					(start 70.451218 -28.341828)
					(mid 70.258062 -28.297631)
					(end 70.090284 -28.192222)
				)
				(xy 70.089268 -28.192222) (xy 70.074536 -28.177744) (xy 70.0659 -28.169108) (xy 70.062852 -28.165806)
				(arc
					(start 69.999352 -28.10256)
					(mid 69.686768 -27.677708)
					(end 70.11162 -27.990292)
				)
				(xy 70.174866 -28.053792)
				(arc
					(start 70.178168 -28.05684)
					(mid 70.318959 -28.15082)
					(end 70.485 -28.18384)
				)
				(xy 70.48754 -28.18384)
			)
		)
	)
	(zone
		(layer "In2.Cu")
		(hatch none 0.5)
		(connect_pads
			(clearance 0)
		)
		(min_thickness 0.25)
		(keepout
			(tracks not_allowed)
			(vias allowed)
			(pads allowed)
			(copperpour not_allowed)
			(footprints allowed)
		)
		(placement
			(enabled no)
			(sheetname "")
		)
		(fill
			(thermal_gap 0.5)
			(thermal_bridge_width 0.5)
			(island_removal_mode 0)
		)
		(polygon
			(pts
				(arc
					(start 82.995516 -24.675338)
					(mid 82.612103 -24.291544)
					(end 82.228436 -24.675084)
				)
				(arc
					(start 82.228436 -24.829516)
					(mid 82.30037 -24.812534)
					(end 82.368136 -24.783034)
				)
				(arc
					(start 82.368136 -24.783034)
					(mid 82.811597 -24.498271)
					(end 82.475324 -24.904192)
				)
				(arc
					(start 82.475324 -24.904192)
					(mid 82.356821 -24.96125)
					(end 82.228436 -24.98979)
				)
				(arc
					(start 82.228436 -25.160732)
					(mid 82.356688 -25.189315)
					(end 82.47507 -25.24633)
				)
				(arc
					(start 82.47507 -25.24633)
					(mid 82.811417 -25.652317)
					(end 82.367882 -25.367488)
				)
				(arc
					(start 82.367882 -25.367488)
					(mid 82.300229 -25.338041)
					(end 82.228436 -25.321006)
				)
				(arc
					(start 82.228436 -25.475184)
					(mid 82.611976 -25.858724)
					(end 82.995516 -25.475184)
				)
			)
		)
	)
	(zone
		(layer "In2.Cu")
		(hatch none 0.5)
		(connect_pads
			(clearance 0)
		)
		(min_thickness 0.25)
		(keepout
			(tracks not_allowed)
			(vias allowed)
			(pads allowed)
			(copperpour not_allowed)
			(footprints allowed)
		)
		(placement
			(enabled no)
			(sheetname "")
		)
		(fill
			(thermal_gap 0.5)
			(thermal_bridge_width 0.5)
			(island_removal_mode 0)
		)
		(polygon
			(pts
				(xy 69.97954 -53.11775) (xy 69.97954 -52.952904) (xy 69.977 -52.952904) (xy 69.964808 -52.952904)
				(xy 69.944234 -52.952904)
				(arc
					(start 69.943218 -52.951888)
					(mid 69.750062 -52.907691)
					(end 69.582284 -52.802282)
				)
				(xy 69.581268 -52.802282) (xy 69.566536 -52.787804) (xy 69.5579 -52.779168) (xy 69.554852 -52.775866)
				(arc
					(start 69.484748 -52.706016)
					(mid 69.184052 -52.272781)
					(end 69.600064 -52.596796)
				)
				(xy 69.666866 -52.663852)
				(arc
					(start 69.670168 -52.6669)
					(mid 69.810959 -52.76088)
					(end 69.977 -52.7939)
				)
				(xy 69.97954 -52.7939)
				(arc
					(start 69.97954 -52.466748)
					(mid 69.367527 -51.854354)
					(end 68.75526 -52.466494)
				)
				(arc
					(start 68.75526 -53.584094)
					(mid 69.3674 -54.196234)
					(end 69.97954 -53.584094)
				)
				(xy 69.97954 -53.276754)
				(arc
					(start 69.977 -53.276754)
					(mid 69.810785 -53.309816)
					(end 69.669914 -53.404008)
				)
				(xy 69.666612 -53.40731)
				(arc
					(start 69.606922 -53.467)
					(mid 69.173039 -53.766779)
					(end 69.497956 -53.35143)
				)
				(xy 69.554598 -53.294788) (xy 69.557646 -53.29174) (xy 69.56679 -53.282596) (xy 69.581014 -53.268372)
				(arc
					(start 69.58203 -53.268372)
					(mid 69.749946 -53.16296)
					(end 69.943218 -53.118766)
				)
				(xy 69.944234 -53.118004) (xy 69.964808 -53.118004) (xy 69.977 -53.11775)
			)
		)
	)
	(zone
		(layer "In2.Cu")
		(hatch none 0.5)
		(connect_pads
			(clearance 0)
		)
		(min_thickness 0.25)
		(keepout
			(tracks not_allowed)
			(vias allowed)
			(pads allowed)
			(copperpour not_allowed)
			(footprints allowed)
		)
		(placement
			(enabled no)
			(sheetname "")
		)
		(fill
			(thermal_gap 0.5)
			(thermal_bridge_width 0.5)
			(island_removal_mode 0)
		)
		(polygon
			(pts
				(xy 70.48754 -56.117744) (xy 70.48754 -55.952898) (xy 70.485 -55.952898) (xy 70.472808 -55.952644)
				(xy 70.452234 -55.952644)
				(arc
					(start 70.451218 -55.951882)
					(mid 70.258062 -55.907685)
					(end 70.090284 -55.802276)
				)
				(xy 70.089268 -55.802276) (xy 70.074536 -55.787798) (xy 70.0659 -55.779162) (xy 70.062852 -55.77586)
				(arc
					(start 69.999352 -55.712614)
					(mid 69.686768 -55.287762)
					(end 70.11162 -55.600346)
				)
				(xy 70.174866 -55.663846)
				(arc
					(start 70.178168 -55.666894)
					(mid 70.318959 -55.760874)
					(end 70.485 -55.793894)
				)
				(xy 70.48754 -55.793894)
				(arc
					(start 70.48754 -55.476394)
					(mid 69.8754 -54.864254)
					(end 69.26326 -55.476394)
				)
				(arc
					(start 69.26326 -56.59374)
					(mid 69.875273 -57.206134)
					(end 70.48754 -56.593994)
				)
				(xy 70.48754 -56.276748)
				(arc
					(start 70.485 -56.276748)
					(mid 70.318785 -56.30981)
					(end 70.177914 -56.404002)
				)
				(xy 70.174612 -56.407304)
				(arc
					(start 70.11162 -56.470296)
					(mid 69.6862 -56.782042)
					(end 69.999352 -56.357774)
				)
				(xy 70.062598 -56.294782) (xy 70.065646 -56.291734) (xy 70.07479 -56.28259) (xy 70.089014 -56.268366)
				(arc
					(start 70.09003 -56.268366)
					(mid 70.257946 -56.162954)
					(end 70.451218 -56.11876)
				)
				(xy 70.452234 -56.117744) (xy 70.472808 -56.117744) (xy 70.485 -56.117744)
			)
		)
	)
	(zone
		(net "GND")
		(layer "In2.Cu")
		(hatch none 0.5)
		(connect_pads
			(clearance 0.5)
		)
		(min_thickness 0.25)
		(fill yes
			(thermal_gap 0.5)
			(thermal_bridge_width 0.5)
			(island_removal_mode 0)
		)
		(polygon
			(pts
				(arc
					(start 56.850026 -0.483616)
					(mid 55.777783 -0.927753)
					(end 55.333646 -1.999996)
				)
				(xy 55.333646 -65.366646) (xy 55.626 -65.659) (xy 57.023 -65.659) (xy 54.229 -68.453) (xy 33.02 -68.453)
				(xy 32.766 -68.707) (xy 32.512 -68.707) (xy 32.512 -68.199) (xy 32.346646 -68.033646)
				(arc
					(start 1.999996 -68.033646)
					(mid 0.927753 -68.477783)
					(end 0.483616 -69.550026)
				)
				(arc
					(start 0.483616 -90.309954)
					(mid 0.927753 -91.382197)
					(end 1.999996 -91.826334)
				)
				(arc
					(start 86.74989 -91.826334)
					(mid 87.822133 -91.382197)
					(end 88.26627 -90.309954)
				)
				(xy 88.26627 -70.993) (xy 88.265 -70.993) (xy 88.138 -70.866) (xy 85.852 -70.866) (xy 85.217 -70.231)
				(xy 85.217 -55.372) (xy 85.852 -54.737) (xy 88.13927 -54.737) (xy 88.26627 -54.61)
				(arc
					(start 88.26627 -49.76495)
					(mid 88.261509 -49.753455)
					(end 88.250014 -49.748694)
				)
				(arc
					(start 81.549748 -49.748694)
					(mid 80.854391 -49.460563)
					(end 80.56626 -48.765206)
				)
				(arc
					(start 80.56626 -44.515024)
					(mid 80.854391 -43.819413)
					(end 81.550002 -43.531282)
				)
				(arc
					(start 82.850228 -43.531282)
					(mid 82.86165 -43.526448)
					(end 82.866484 -43.515026)
				)
				(arc
					(start 82.866484 -11.685016)
					(mid 82.861648 -11.673342)
					(end 82.849974 -11.668506)
				)
				(arc
					(start 81.549748 -11.668506)
					(mid 80.854391 -11.380375)
					(end 80.56626 -10.685018)
				)
				(arc
					(start 80.56626 -6.434836)
					(mid 80.854391 -5.739479)
					(end 81.549748 -5.451348)
				)
				(arc
					(start 88.250014 -5.451348)
					(mid 88.261509 -5.446587)
					(end 88.26627 -5.435092)
				)
				(arc
					(start 88.26627 -0.499872)
					(mid 88.261509 -0.488377)
					(end 88.250014 -0.483616)
				)
			)
		)
	)
	(zone
		(layer "In2.Cu")
		(hatch none 0.5)
		(connect_pads
			(clearance 0)
		)
		(min_thickness 0.25)
		(keepout
			(tracks not_allowed)
			(vias allowed)
			(pads allowed)
			(copperpour not_allowed)
			(footprints allowed)
		)
		(placement
			(enabled no)
			(sheetname "")
		)
		(fill
			(thermal_gap 0.5)
			(thermal_bridge_width 0.5)
			(island_removal_mode 0)
		)
		(polygon
			(pts
				(arc
					(start 69.97954 -24.87676)
					(mid 69.367527 -24.264366)
					(end 68.75526 -24.876506)
				)
				(arc
					(start 68.75526 -25.994106)
					(mid 69.3674 -26.606246)
					(end 69.97954 -25.994106)
				)
				(xy 69.97954 -25.67686)
				(arc
					(start 69.977 -25.67686)
					(mid 69.810785 -25.709922)
					(end 69.669914 -25.804114)
				)
				(xy 69.666612 -25.807416)
				(arc
					(start 69.60362 -25.870408)
					(mid 69.1782 -26.182154)
					(end 69.491352 -25.757886)
				)
				(xy 69.554598 -25.694894) (xy 69.557646 -25.691846) (xy 69.56679 -25.682702) (xy 69.581014 -25.668478)
				(arc
					(start 69.58203 -25.668478)
					(mid 69.749946 -25.563066)
					(end 69.943218 -25.518872)
				)
				(xy 69.944234 -25.517856) (xy 69.964808 -25.517856) (xy 69.977 -25.517856) (xy 69.97954 -25.517856)
				(xy 69.97954 -25.35301) (xy 69.977 -25.35301) (xy 69.964808 -25.352756) (xy 69.944234 -25.352756)
				(arc
					(start 69.943218 -25.351994)
					(mid 69.750062 -25.307797)
					(end 69.582284 -25.202388)
				)
				(xy 69.581268 -25.202388) (xy 69.566536 -25.18791) (xy 69.5579 -25.179274) (xy 69.554852 -25.175972)
				(arc
					(start 69.491352 -25.112726)
					(mid 69.178768 -24.687874)
					(end 69.60362 -25.000458)
				)
				(xy 69.666866 -25.063958)
				(arc
					(start 69.670168 -25.067006)
					(mid 69.810959 -25.160986)
					(end 69.977 -25.194006)
				)
				(xy 69.97954 -25.194006)
			)
		)
	)
	(zone
		(layer "In2.Cu")
		(hatch none 0.5)
		(connect_pads
			(clearance 0)
		)
		(min_thickness 0.25)
		(keepout
			(tracks not_allowed)
			(vias allowed)
			(pads allowed)
			(copperpour not_allowed)
			(footprints allowed)
		)
		(placement
			(enabled no)
			(sheetname "")
		)
		(fill
			(thermal_gap 0.5)
			(thermal_bridge_width 0.5)
			(island_removal_mode 0)
		)
		(polygon
			(pts
				(arc
					(start 82.995516 -15.075154)
					(mid 82.611976 -14.691614)
					(end 82.228436 -15.075154)
				)
				(arc
					(start 82.228436 -15.229332)
					(mid 82.300238 -15.212324)
					(end 82.367882 -15.18285)
				)
				(arc
					(start 82.367882 -15.18285)
					(mid 82.811343 -14.898087)
					(end 82.47507 -15.304008)
				)
				(arc
					(start 82.47507 -15.304008)
					(mid 82.35668 -15.361)
					(end 82.228436 -15.389606)
				)
				(arc
					(start 82.228436 -15.560548)
					(mid 82.356688 -15.589131)
					(end 82.47507 -15.646146)
				)
				(arc
					(start 82.47507 -15.646146)
					(mid 82.811417 -16.052133)
					(end 82.367882 -15.767304)
				)
				(arc
					(start 82.367882 -15.767304)
					(mid 82.300229 -15.737857)
					(end 82.228436 -15.720822)
				)
				(arc
					(start 82.228436 -15.874746)
					(mid 82.611849 -16.25854)
					(end 82.995516 -15.875)
				)
			)
		)
	)
	(zone
		(layer "In2.Cu")
		(hatch none 0.5)
		(connect_pads
			(clearance 0)
		)
		(min_thickness 0.25)
		(keepout
			(tracks not_allowed)
			(vias allowed)
			(pads allowed)
			(copperpour not_allowed)
			(footprints allowed)
		)
		(placement
			(enabled no)
			(sheetname "")
		)
		(fill
			(thermal_gap 0.5)
			(thermal_bridge_width 0.5)
			(island_removal_mode 0)
		)
		(polygon
			(pts
				(arc
					(start 70.48754 -27.876754)
					(mid 69.875527 -27.26436)
					(end 69.26326 -27.8765)
				)
				(arc
					(start 69.26326 -28.9941)
					(mid 69.8754 -29.60624)
					(end 70.48754 -28.9941)
				)
				(xy 70.48754 -28.676854)
				(arc
					(start 70.485 -28.676854)
					(mid 70.318785 -28.709916)
					(end 70.177914 -28.804108)
				)
				(xy 70.174612 -28.80741)
				(arc
					(start 70.11162 -28.870402)
					(mid 69.6862 -29.182148)
					(end 69.999352 -28.75788)
				)
				(xy 70.062598 -28.694888) (xy 70.065646 -28.69184) (xy 70.07479 -28.682696) (xy 70.089014 -28.668472)
				(arc
					(start 70.09003 -28.668472)
					(mid 70.257946 -28.56306)
					(end 70.451218 -28.518866)
				)
				(xy 70.452234 -28.518104) (xy 70.472808 -28.518104) (xy 70.485 -28.51785) (xy 70.48754 -28.51785)
				(xy 70.48754 -28.353004) (xy 70.485 -28.353004) (xy 70.472808 -28.353004) (xy 70.452234 -28.353004)
				(arc
					(start 70.451218 -28.351988)
					(mid 70.258062 -28.307791)
					(end 70.090284 -28.202382)
				)
				(xy 70.089268 -28.202382) (xy 70.074536 -28.187904) (xy 70.0659 -28.179268) (xy 70.062852 -28.175966)
				(arc
					(start 69.999352 -28.11272)
					(mid 69.686768 -27.687868)
					(end 70.11162 -28.000452)
				)
				(xy 70.174866 -28.063952)
				(arc
					(start 70.178168 -28.067)
					(mid 70.318959 -28.16098)
					(end 70.485 -28.194)
				)
				(xy 70.48754 -28.194)
			)
		)
	)
	(zone
		(layer "In2.Cu")
		(hatch none 0.5)
		(connect_pads
			(clearance 0)
		)
		(min_thickness 0.25)
		(keepout
			(tracks not_allowed)
			(vias allowed)
			(pads allowed)
			(copperpour not_allowed)
			(footprints allowed)
		)
		(placement
			(enabled no)
			(sheetname "")
		)
		(fill
			(thermal_gap 0.5)
			(thermal_bridge_width 0.5)
			(island_removal_mode 0)
		)
		(polygon
			(pts
				(xy 69.97954 -53.11775) (xy 69.97954 -52.952904) (xy 69.977 -52.952904) (xy 69.964808 -52.952904)
				(xy 69.944234 -52.952904)
				(arc
					(start 69.943218 -52.951888)
					(mid 69.750062 -52.907691)
					(end 69.582284 -52.802282)
				)
				(xy 69.581268 -52.802282) (xy 69.566536 -52.787804) (xy 69.5579 -52.779168) (xy 69.554852 -52.775866)
				(arc
					(start 69.491352 -52.71262)
					(mid 69.178768 -52.287768)
					(end 69.60362 -52.600352)
				)
				(xy 69.666866 -52.663852)
				(arc
					(start 69.670168 -52.6669)
					(mid 69.810959 -52.76088)
					(end 69.977 -52.7939)
				)
				(xy 69.97954 -52.7939)
				(arc
					(start 69.97954 -52.4764)
					(mid 69.3674 -51.86426)
					(end 68.75526 -52.4764)
				)
				(arc
					(start 68.75526 -53.593746)
					(mid 69.367273 -54.20614)
					(end 69.97954 -53.594)
				)
				(xy 69.97954 -53.276754)
				(arc
					(start 69.977 -53.276754)
					(mid 69.810785 -53.309816)
					(end 69.669914 -53.404008)
				)
				(xy 69.666612 -53.40731)
				(arc
					(start 69.60362 -53.470302)
					(mid 69.1782 -53.782048)
					(end 69.491352 -53.35778)
				)
				(xy 69.554598 -53.294788) (xy 69.557646 -53.29174) (xy 69.56679 -53.282596) (xy 69.581014 -53.268372)
				(arc
					(start 69.58203 -53.268372)
					(mid 69.749946 -53.16296)
					(end 69.943218 -53.118766)
				)
				(xy 69.944234 -53.118004) (xy 69.964808 -53.118004) (xy 69.977 -53.11775)
			)
		)
	)
	(zone
		(layer "In2.Cu")
		(hatch none 0.5)
		(connect_pads
			(clearance 0)
		)
		(min_thickness 0.25)
		(keepout
			(tracks not_allowed)
			(vias allowed)
			(pads allowed)
			(copperpour not_allowed)
			(footprints allowed)
		)
		(placement
			(enabled no)
			(sheetname "")
		)
		(fill
			(thermal_gap 0.5)
			(thermal_bridge_width 0.5)
			(island_removal_mode 0)
		)
		(polygon
			(pts
				(arc
					(start 69.97954 -24.8666)
					(mid 69.367527 -24.254206)
					(end 68.75526 -24.866346)
				)
				(arc
					(start 68.75526 -25.983946)
					(mid 69.3674 -26.596086)
					(end 69.97954 -25.983946)
				)
				(xy 69.97954 -25.6667)
				(arc
					(start 69.977 -25.6667)
					(mid 69.810785 -25.699762)
					(end 69.669914 -25.793954)
				)
				(xy 69.666612 -25.797256)
				(arc
					(start 69.60362 -25.860248)
					(mid 69.1782 -26.171994)
					(end 69.491352 -25.747726)
				)
				(xy 69.554598 -25.684734) (xy 69.557646 -25.681686) (xy 69.56679 -25.672542) (xy 69.581014 -25.658318)
				(arc
					(start 69.58203 -25.658318)
					(mid 69.749946 -25.552906)
					(end 69.943218 -25.508712)
				)
				(xy 69.944234 -25.507696) (xy 69.964808 -25.507696) (xy 69.977 -25.507696) (xy 69.97954 -25.507696)
				(xy 69.97954 -25.34285) (xy 69.977 -25.34285) (xy 69.964808 -25.342596) (xy 69.944234 -25.342596)
				(arc
					(start 69.943218 -25.341834)
					(mid 69.750062 -25.297637)
					(end 69.582284 -25.192228)
				)
				(xy 69.581268 -25.192228) (xy 69.566536 -25.17775) (xy 69.5579 -25.169114) (xy 69.554852 -25.165812)
				(arc
					(start 69.491352 -25.102566)
					(mid 69.178768 -24.677714)
					(end 69.60362 -24.990298)
				)
				(xy 69.666866 -25.053798)
				(arc
					(start 69.670168 -25.056846)
					(mid 69.810959 -25.150826)
					(end 69.977 -25.183846)
				)
				(xy 69.97954 -25.183846)
			)
		)
	)
	(zone
		(layers "In2.Cu" "In5.Cu")
		(hatch none 0.5)
		(connect_pads
			(clearance 0)
		)
		(min_thickness 0.25)
		(keepout
			(tracks not_allowed)
			(vias allowed)
			(pads allowed)
			(copperpour not_allowed)
			(footprints allowed)
		)
		(placement
			(enabled no)
			(sheetname "")
		)
		(fill yes
			(thermal_gap 0.5)
			(thermal_bridge_width 0.5)
			(island_removal_mode 0)
		)
		(polygon
			(pts
				(arc
					(start 82.995516 -39.874952)
					(mid 82.611976 -39.491412)
					(end 82.228436 -39.874952)
				)
				(arc
					(start 82.228436 -40.675052)
					(mid 82.610706 -41.05859)
					(end 82.995516 -40.677592)
				)
				(arc
					(start 82.878676 -40.677592)
					(mid 82.611976 -40.941764)
					(end 82.345276 -40.677592)
				)
				(arc
					(start 82.345276 -40.675052)
					(mid 82.611976 -40.408352)
					(end 82.878676 -40.675052)
				)
				(xy 82.995516 -40.675052) (xy 82.995516 -39.877492)
				(arc
					(start 82.878676 -39.877492)
					(mid 82.611976 -40.141664)
					(end 82.345276 -39.877492)
				)
				(arc
					(start 82.345276 -39.874952)
					(mid 82.611976 -39.608252)
					(end 82.878676 -39.874952)
				)
			)
		)
	)
	(zone
		(layers "In2.Cu" "In5.Cu")
		(hatch none 0.5)
		(connect_pads
			(clearance 0)
		)
		(min_thickness 0.25)
		(keepout
			(tracks not_allowed)
			(vias allowed)
			(pads allowed)
			(copperpour not_allowed)
			(footprints allowed)
		)
		(placement
			(enabled no)
			(sheetname "")
		)
		(fill yes
			(thermal_gap 0.5)
			(thermal_bridge_width 0.5)
			(island_removal_mode 0)
		)
		(polygon
			(pts
				(arc
					(start 82.995516 -22.275038)
					(mid 82.611976 -21.891498)
					(end 82.228436 -22.275038)
				)
				(arc
					(start 82.228436 -23.075138)
					(mid 82.610706 -23.458676)
					(end 82.995516 -23.077678)
				)
				(arc
					(start 82.878676 -23.077678)
					(mid 82.611976 -23.34185)
					(end 82.345276 -23.077678)
				)
				(arc
					(start 82.345276 -23.075138)
					(mid 82.611976 -22.808438)
					(end 82.878676 -23.075138)
				)
				(xy 82.995516 -23.075138) (xy 82.995516 -22.277578)
				(arc
					(start 82.878676 -22.277578)
					(mid 82.611976 -22.54175)
					(end 82.345276 -22.277578)
				)
				(arc
					(start 82.345276 -22.275038)
					(mid 82.611976 -22.008338)
					(end 82.878676 -22.275038)
				)
			)
		)
	)
	(zone
		(layers "In2.Cu" "In5.Cu")
		(hatch none 0.5)
		(connect_pads
			(clearance 0)
		)
		(min_thickness 0.25)
		(keepout
			(tracks not_allowed)
			(vias allowed)
			(pads allowed)
			(copperpour not_allowed)
			(footprints allowed)
		)
		(placement
			(enabled no)
			(sheetname "")
		)
		(fill yes
			(thermal_gap 0.5)
			(thermal_bridge_width 0.5)
			(island_removal_mode 0)
		)
		(polygon
			(pts
				(arc
					(start 82.995516 -27.07513)
					(mid 82.611976 -26.69159)
					(end 82.228436 -27.07513)
				)
				(arc
					(start 82.228436 -27.874976)
					(mid 82.610706 -28.258514)
					(end 82.995516 -27.877516)
				)
				(arc
					(start 82.878676 -27.877516)
					(mid 82.611976 -28.141688)
					(end 82.345276 -27.877516)
				)
				(arc
					(start 82.345276 -27.874976)
					(mid 82.611976 -27.608276)
					(end 82.878676 -27.874976)
				)
				(xy 82.995516 -27.874976) (xy 82.995516 -27.07767)
				(arc
					(start 82.878676 -27.07767)
					(mid 82.611976 -27.341842)
					(end 82.345276 -27.07767)
				)
				(arc
					(start 82.345276 -27.07513)
					(mid 82.611976 -26.80843)
					(end 82.878676 -27.07513)
				)
			)
		)
	)
	(zone
		(layers "In2.Cu" "In5.Cu")
		(hatch none 0.5)
		(connect_pads
			(clearance 0)
		)
		(min_thickness 0.25)
		(keepout
			(tracks not_allowed)
			(vias allowed)
			(pads allowed)
			(copperpour not_allowed)
			(footprints allowed)
		)
		(placement
			(enabled no)
			(sheetname "")
		)
		(fill yes
			(thermal_gap 0.5)
			(thermal_bridge_width 0.5)
			(island_removal_mode 0)
		)
		(polygon
			(pts
				(arc
					(start 82.995516 -17.474946)
					(mid 82.611976 -17.091406)
					(end 82.228436 -17.474946)
				)
				(arc
					(start 82.228436 -18.275046)
					(mid 82.610706 -18.658584)
					(end 82.995516 -18.277586)
				)
				(arc
					(start 82.878676 -18.277586)
					(mid 82.611976 -18.541758)
					(end 82.345276 -18.277586)
				)
				(arc
					(start 82.345276 -18.275046)
					(mid 82.611976 -18.008346)
					(end 82.878676 -18.275046)
				)
				(xy 82.995516 -18.275046) (xy 82.995516 -17.477486)
				(arc
					(start 82.878676 -17.477486)
					(mid 82.611976 -17.741658)
					(end 82.345276 -17.477486)
				)
				(arc
					(start 82.345276 -17.474946)
					(mid 82.611976 -17.208246)
					(end 82.878676 -17.474946)
				)
			)
		)
	)
	(zone
		(net "P3V3_PWR")
		(layers "In3.Cu" "In4.Cu")
		(hatch none 0.5)
		(connect_pads
			(clearance 0.5)
		)
		(min_thickness 0.25)
		(fill yes
			(thermal_gap 0.5)
			(thermal_bridge_width 0.5)
			(island_removal_mode 0)
		)
		(polygon
			(pts
				(xy 59.260994 -16.5735) (xy 59.1185 -16.715994) (xy 59.1185 -77.772006) (xy 59.260994 -77.9145)
				(xy 65.707006 -77.9145) (xy 65.8495 -77.772006) (xy 65.8495 -16.715994) (xy 65.707006 -16.5735)
			)
		)
	)
	(zone
		(net "GND")
		(layers "In3.Cu" "In4.Cu")
		(hatch none 0.5)
		(connect_pads
			(clearance 0.5)
		)
		(min_thickness 0.25)
		(fill yes
			(thermal_gap 0.5)
			(thermal_bridge_width 0.5)
			(island_removal_mode 0)
		)
		(polygon
			(pts
				(arc
					(start 56.850026 -0.483616)
					(mid 55.777783 -0.927753)
					(end 55.333646 -1.999996)
				)
				(arc
					(start 55.333646 -65.550034)
					(mid 54.606213 -67.306213)
					(end 52.850034 -68.033646)
				)
				(arc
					(start 1.999996 -68.033646)
					(mid 0.927753 -68.477783)
					(end 0.483616 -69.550026)
				)
				(arc
					(start 0.483616 -90.309954)
					(mid 0.927753 -91.382197)
					(end 1.999996 -91.826334)
				)
				(arc
					(start 86.74989 -91.826334)
					(mid 87.822133 -91.382197)
					(end 88.26627 -90.309954)
				)
				(arc
					(start 88.26627 -70.809866)
					(mid 88.261509 -70.798371)
					(end 88.250014 -70.79361)
				)
				(arc
					(start 86.249764 -70.79361)
					(mid 85.554407 -70.505479)
					(end 85.266276 -69.810122)
				)
				(arc
					(start 85.266276 -55.770018)
					(mid 85.554407 -55.074407)
					(end 86.250018 -54.786276)
				)
				(arc
					(start 88.250014 -54.786276)
					(mid 88.261509 -54.781515)
					(end 88.26627 -54.77002)
				)
				(arc
					(start 88.26627 -49.76495)
					(mid 88.261509 -49.753455)
					(end 88.250014 -49.748694)
				)
				(arc
					(start 81.549748 -49.748694)
					(mid 80.854391 -49.460563)
					(end 80.56626 -48.765206)
				)
				(arc
					(start 80.56626 -44.515024)
					(mid 80.854391 -43.819413)
					(end 81.550002 -43.531282)
				)
				(arc
					(start 82.850228 -43.531282)
					(mid 82.86165 -43.526448)
					(end 82.866484 -43.515026)
				)
				(arc
					(start 82.866484 -43.362118)
					(mid 82.454617 -43.424945)
					(end 82.228436 -43.075098)
				)
				(arc
					(start 82.228436 -42.274998)
					(mid 82.454645 -41.925213)
					(end 82.866484 -41.987978)
				)
				(arc
					(start 82.866484 -40.962072)
					(mid 82.454617 -41.024899)
					(end 82.228436 -40.675052)
				)
				(arc
					(start 82.228436 -39.874952)
					(mid 82.454645 -39.525167)
					(end 82.866484 -39.587932)
				)
				(arc
					(start 82.866484 -38.562026)
					(mid 82.454617 -38.624853)
					(end 82.228436 -38.275006)
				)
				(arc
					(start 82.228436 -37.47516)
					(mid 82.454645 -37.125375)
					(end 82.866484 -37.18814)
				)
				(arc
					(start 82.866484 -28.161996)
					(mid 82.454617 -28.224823)
					(end 82.228436 -27.874976)
				)
				(arc
					(start 82.228436 -27.07513)
					(mid 82.454645 -26.725345)
					(end 82.866484 -26.78811)
				)
				(arc
					(start 82.866484 -25.762204)
					(mid 82.454617 -25.825031)
					(end 82.228436 -25.475184)
				)
				(arc
					(start 82.228436 -24.675084)
					(mid 82.454645 -24.325299)
					(end 82.866484 -24.388064)
				)
				(arc
					(start 82.866484 -23.362158)
					(mid 82.454617 -23.424985)
					(end 82.228436 -23.075138)
				)
				(arc
					(start 82.228436 -22.275038)
					(mid 82.454645 -21.925253)
					(end 82.866484 -21.988018)
				)
				(arc
					(start 82.866484 -20.962112)
					(mid 82.454733 -21.024991)
					(end 82.228436 -20.675346)
				)
				(arc
					(start 82.228436 -19.874992)
					(mid 82.454645 -19.525207)
					(end 82.866484 -19.587972)
				)
				(arc
					(start 82.866484 -18.562066)
					(mid 82.454617 -18.624893)
					(end 82.228436 -18.275046)
				)
				(arc
					(start 82.228436 -17.474946)
					(mid 82.454645 -17.125161)
					(end 82.866484 -17.187926)
				)
				(arc
					(start 82.866484 -16.16202)
					(mid 82.454733 -16.224899)
					(end 82.228436 -15.875254)
				)
				(arc
					(start 82.228436 -15.075154)
					(mid 82.454645 -14.725369)
					(end 82.866484 -14.788134)
				)
				(arc
					(start 82.866484 -11.685016)
					(mid 82.861648 -11.673342)
					(end 82.849974 -11.668506)
				)
				(arc
					(start 81.549748 -11.668506)
					(mid 80.854391 -11.380375)
					(end 80.56626 -10.685018)
				)
				(arc
					(start 80.56626 -6.434836)
					(mid 80.854391 -5.739479)
					(end 81.549748 -5.451348)
				)
				(arc
					(start 88.250014 -5.451348)
					(mid 88.261509 -5.446587)
					(end 88.26627 -5.435092)
				)
				(arc
					(start 88.26627 -0.499872)
					(mid 88.261509 -0.488377)
					(end 88.250014 -0.483616)
				)
			)
		)
		(polygon
			(pts
				(arc
					(start 70.48754 -55.466234)
					(mid 69.875273 -54.854348)
					(end 69.26326 -55.466488)
				)
				(arc
					(start 69.26326 -56.594248)
					(mid 69.875527 -57.206134)
					(end 70.48754 -56.593994)
				)
			)
		)
		(polygon
			(pts
				(arc
					(start 69.97954 -52.46624)
					(mid 69.367273 -51.854354)
					(end 68.75526 -52.466494)
				)
				(arc
					(start 68.75526 -53.594254)
					(mid 69.367527 -54.20614)
					(end 69.97954 -53.594)
				)
			)
		)
		(polygon
			(pts
				(arc
					(start 74.50074 -49.62144)
					(mid 73.990073 -49.111154)
					(end 73.47966 -49.621694)
				)
				(arc
					(start 73.47966 -50.434494)
					(mid 73.9902 -50.945034)
					(end 74.50074 -50.434494)
				)
			)
		)
		(polygon
			(pts
				(arc
					(start 77.52334 -33.691068)
					(mid 76.911073 -33.079182)
					(end 76.29906 -33.691322)
				)
				(arc
					(start 76.29906 -34.808922)
					(mid 76.9112 -35.421062)
					(end 77.52334 -34.808922)
				)
			)
		)
		(polygon
			(pts
				(arc
					(start 70.48754 -27.86634)
					(mid 69.8754 -27.2542)
					(end 69.26326 -27.86634)
				)
				(arc
					(start 69.26326 -28.9941)
					(mid 69.8754 -29.60624)
					(end 70.48754 -28.9941)
				)
			)
		)
		(polygon
			(pts
				(arc
					(start 69.97954 -24.866092)
					(mid 69.367273 -24.254206)
					(end 68.75526 -24.866346)
				)
				(arc
					(start 68.75526 -25.994106)
					(mid 69.3674 -26.606246)
					(end 69.97954 -25.994106)
				)
			)
		)
		(polygon
			(pts
				(arc
					(start 75.44054 -22.021292)
					(mid 74.929873 -21.511006)
					(end 74.41946 -22.021546)
				)
				(arc
					(start 74.41946 -22.834346)
					(mid 74.93 -23.344886)
					(end 75.44054 -22.834346)
				)
			)
		)
		(polygon
			(pts
				(xy 65.864994 -16.1925) (xy 59.103006 -16.1925) (xy 58.7375 -16.558006) (xy 58.7375 -77.929994)
				(xy 59.103006 -78.2955) (xy 65.864994 -78.2955) (xy 66.2305 -77.929994) (xy 66.2305 -16.558006)
			)
		)
	)
	(zone
		(net "GND")
		(layer "In5.Cu")
		(hatch none 0.5)
		(connect_pads
			(clearance 0.5)
		)
		(min_thickness 0.25)
		(fill yes
			(thermal_gap 0.5)
			(thermal_bridge_width 0.5)
			(island_removal_mode 0)
		)
		(polygon
			(pts
				(arc
					(start 56.850026 -0.483616)
					(mid 55.777783 -0.927753)
					(end 55.333646 -1.999996)
				)
				(arc
					(start 55.333646 -65.550034)
					(mid 54.606213 -67.306213)
					(end 52.850034 -68.033646)
				)
				(arc
					(start 1.999996 -68.033646)
					(mid 0.927753 -68.477783)
					(end 0.483616 -69.550026)
				)
				(arc
					(start 0.483616 -90.309954)
					(mid 0.927753 -91.382197)
					(end 1.999996 -91.826334)
				)
				(arc
					(start 86.74989 -91.826334)
					(mid 87.822133 -91.382197)
					(end 88.26627 -90.309954)
				)
				(xy 88.26627 -70.993) (xy 88.13927 -70.866) (xy 85.852 -70.866) (xy 85.217 -70.231) (xy 85.217 -55.372)
				(xy 85.852 -54.737) (xy 88.13927 -54.737) (xy 88.26627 -54.61)
				(arc
					(start 88.26627 -49.76495)
					(mid 88.261509 -49.753455)
					(end 88.250014 -49.748694)
				)
				(arc
					(start 81.549748 -49.748694)
					(mid 80.854391 -49.460563)
					(end 80.56626 -48.765206)
				)
				(arc
					(start 80.56626 -44.515024)
					(mid 80.854391 -43.819413)
					(end 81.550002 -43.531282)
				)
				(arc
					(start 82.850228 -43.531282)
					(mid 82.86165 -43.526448)
					(end 82.866484 -43.515026)
				)
				(arc
					(start 82.866484 -11.685016)
					(mid 82.861648 -11.673342)
					(end 82.849974 -11.668506)
				)
				(arc
					(start 81.549748 -11.668506)
					(mid 80.854391 -11.380375)
					(end 80.56626 -10.685018)
				)
				(arc
					(start 80.56626 -6.434836)
					(mid 80.854391 -5.739479)
					(end 81.549748 -5.451348)
				)
				(arc
					(start 88.250014 -5.451348)
					(mid 88.261509 -5.446587)
					(end 88.26627 -5.435092)
				)
				(arc
					(start 88.26627 -0.499872)
					(mid 88.261509 -0.488377)
					(end 88.250014 -0.483616)
				)
			)
		)
	)
	(zone
		(layer "In5.Cu")
		(hatch none 0.5)
		(connect_pads
			(clearance 0)
		)
		(min_thickness 0.25)
		(keepout
			(tracks not_allowed)
			(vias allowed)
			(pads allowed)
			(copperpour not_allowed)
			(footprints allowed)
		)
		(placement
			(enabled no)
			(sheetname "")
		)
		(fill
			(thermal_gap 0.5)
			(thermal_bridge_width 0.5)
			(island_removal_mode 0)
		)
		(polygon
			(pts
				(arc
					(start 82.995516 -42.275252)
					(mid 82.612103 -41.891458)
					(end 82.228436 -42.274998)
				)
				(arc
					(start 82.228436 -42.36593)
					(mid 82.289376 -42.345167)
					(end 82.34934 -42.321734)
				)
				(arc
					(start 82.34934 -42.321734)
					(mid 82.848541 -42.151715)
					(end 82.423254 -42.463466)
				)
				(arc
					(start 82.423254 -42.463466)
					(mid 82.326934 -42.500734)
					(end 82.228436 -42.531792)
				)
				(arc
					(start 82.228436 -42.760646)
					(mid 82.356688 -42.789229)
					(end 82.47507 -42.846244)
				)
				(arc
					(start 82.47507 -42.846244)
					(mid 82.811417 -43.252231)
					(end 82.367882 -42.967402)
				)
				(arc
					(start 82.367882 -42.967402)
					(mid 82.300229 -42.937955)
					(end 82.228436 -42.92092)
				)
				(arc
					(start 82.228436 -43.075098)
					(mid 82.611976 -43.458638)
					(end 82.995516 -43.075098)
				)
			)
		)
	)
	(zone
		(layer "In5.Cu")
		(hatch none 0.5)
		(connect_pads
			(clearance 0)
		)
		(min_thickness 0.25)
		(keepout
			(tracks not_allowed)
			(vias allowed)
			(pads allowed)
			(copperpour not_allowed)
			(footprints allowed)
		)
		(placement
			(enabled no)
			(sheetname "")
		)
		(fill
			(thermal_gap 0.5)
			(thermal_bridge_width 0.5)
			(island_removal_mode 0)
		)
		(polygon
			(pts
				(arc
					(start 75.44054 -22.0218)
					(mid 74.930127 -21.511006)
					(end 74.41946 -22.021546)
				)
				(arc
					(start 74.41946 -22.834346)
					(mid 74.93 -23.344886)
					(end 75.44054 -22.834346)
				)
				(xy 75.44054 -22.6695) (xy 75.425046 -22.6695)
				(arc
					(start 75.420474 -22.6695)
					(mid 75.294327 -22.685129)
					(end 75.175872 -22.731222)
				)
				(arc
					(start 75.175872 -22.731222)
					(mid 74.726362 -23.006705)
					(end 75.071224 -22.608032)
				)
				(arc
					(start 75.071224 -22.608032)
					(mid 75.223064 -22.540005)
					(end 75.386946 -22.511258)
				)
				(xy 75.387708 -22.510496) (xy 75.40752 -22.510496) (xy 75.420474 -22.510496) (xy 75.425046 -22.510496)
				(xy 75.44054 -22.510496) (xy 75.44054 -22.345396) (xy 75.438254 -22.345396) (xy 75.433682 -22.34565)
				(xy 75.42022 -22.345396) (xy 75.400916 -22.345396)
				(arc
					(start 75.400154 -22.344888)
					(mid 75.230668 -22.315818)
					(end 75.073256 -22.24659)
				)
				(arc
					(start 75.073256 -22.24659)
					(mid 74.725249 -21.850537)
					(end 75.176888 -22.122384)
				)
				(arc
					(start 75.176888 -22.122384)
					(mid 75.301328 -22.170339)
					(end 75.433682 -22.186646)
				)
				(xy 75.438254 -22.1869) (xy 75.44054 -22.1869)
			)
		)
	)
	(zone
		(layer "In5.Cu")
		(hatch none 0.5)
		(connect_pads
			(clearance 0)
		)
		(min_thickness 0.25)
		(keepout
			(tracks not_allowed)
			(vias allowed)
			(pads allowed)
			(copperpour not_allowed)
			(footprints allowed)
		)
		(placement
			(enabled no)
			(sheetname "")
		)
		(fill
			(thermal_gap 0.5)
			(thermal_bridge_width 0.5)
			(island_removal_mode 0)
		)
		(polygon
			(pts
				(arc
					(start 77.015086 -34.563304)
					(mid 77.251688 -34.411112)
					(end 77.52334 -34.338006)
				)
				(arc
					(start 77.52334 -34.12871)
					(mid 77.278743 -34.044582)
					(end 77.053948 -33.91662)
				)
				(arc
					(start 77.053948 -33.91662)
					(mid 76.707555 -33.519087)
					(end 77.157072 -33.7947)
				)
				(arc
					(start 77.157072 -33.7947)
					(mid 77.333206 -33.894647)
					(end 77.52334 -33.964372)
				)
				(arc
					(start 77.52334 -33.691576)
					(mid 76.911327 -33.079182)
					(end 76.29906 -33.691322)
				)
				(arc
					(start 76.29906 -34.808922)
					(mid 76.9112 -35.421062)
					(end 77.52334 -34.808922)
				)
				(arc
					(start 77.52334 -34.49828)
					(mid 77.318379 -34.555559)
					(end 77.137514 -34.667698)
				)
				(arc
					(start 77.137514 -34.667698)
					(mid 76.73802 -35.011828)
					(end 77.015086 -34.563304)
				)
			)
		)
	)
	(zone
		(layer "In5.Cu")
		(hatch none 0.5)
		(connect_pads
			(clearance 0)
		)
		(min_thickness 0.25)
		(keepout
			(tracks not_allowed)
			(vias allowed)
			(pads allowed)
			(copperpour not_allowed)
			(footprints allowed)
		)
		(placement
			(enabled no)
			(sheetname "")
		)
		(fill
			(thermal_gap 0.5)
			(thermal_bridge_width 0.5)
			(island_removal_mode 0)
		)
		(polygon
			(pts
				(arc
					(start 74.50074 -49.621948)
					(mid 73.990327 -49.111154)
					(end 73.47966 -49.621694)
				)
				(arc
					(start 73.47966 -49.747424)
					(mid 73.605698 -49.715003)
					(end 73.728072 -49.670716)
				)
				(arc
					(start 73.728072 -49.670716)
					(mid 74.225639 -49.496463)
					(end 73.803002 -49.811686)
				)
				(arc
					(start 73.803002 -49.811686)
					(mid 73.644054 -49.869589)
					(end 73.47966 -49.909476)
				)
				(arc
					(start 73.47966 -50.151284)
					(mid 73.639823 -50.194992)
					(end 73.79589 -50.251614)
				)
				(arc
					(start 73.79589 -50.251614)
					(mid 74.230622 -50.549892)
					(end 73.726548 -50.395124)
				)
				(arc
					(start 73.726548 -50.395124)
					(mid 73.604496 -50.35071)
					(end 73.47966 -50.31486)
				)
				(arc
					(start 73.47966 -50.434494)
					(mid 73.9902 -50.945034)
					(end 74.50074 -50.434494)
				)
			)
		)
	)
	(zone
		(layer "In6.Cu")
		(hatch none 0.5)
		(connect_pads
			(clearance 0)
		)
		(min_thickness 0.25)
		(keepout
			(tracks not_allowed)
			(vias allowed)
			(pads allowed)
			(copperpour not_allowed)
			(footprints allowed)
		)
		(placement
			(enabled no)
			(sheetname "")
		)
		(fill
			(thermal_gap 0.5)
			(thermal_bridge_width 0.5)
			(island_removal_mode 0)
		)
		(polygon
			(pts
				(xy 81.3562 -41.729152) (xy 82.256376 -41.729152) (xy 82.256376 -43.621198) (xy 81.3562 -43.621198)
				(xy 81.3054 -43.621198) (xy 81.3054 -41.729152)
			)
		)
	)
	(zone
		(layer "In6.Cu")
		(hatch none 0.5)
		(connect_pads
			(clearance 0)
		)
		(min_thickness 0.25)
		(keepout
			(tracks not_allowed)
			(vias allowed)
			(pads allowed)
			(copperpour not_allowed)
			(footprints allowed)
		)
		(placement
			(enabled no)
			(sheetname "")
		)
		(fill
			(thermal_gap 0.5)
			(thermal_bridge_width 0.5)
			(island_removal_mode 0)
		)
		(polygon
			(pts
				(xy 77.893672 -35.196272) (xy 77.893672 -33.304226) (xy 78.793848 -33.304226) (xy 78.844648 -33.304226)
				(xy 78.844648 -35.196272) (xy 78.844648 -35.405568) (xy 77.893672 -35.405568)
			)
		)
	)
	(zone
		(layer "In6.Cu")
		(hatch none 0.5)
		(connect_pads
			(clearance 0)
		)
		(min_thickness 0.25)
		(keepout
			(tracks not_allowed)
			(vias allowed)
			(pads allowed)
			(copperpour not_allowed)
			(footprints allowed)
		)
		(placement
			(enabled no)
			(sheetname "")
		)
		(fill
			(thermal_gap 0.5)
			(thermal_bridge_width 0.5)
			(island_removal_mode 0)
		)
		(polygon
			(pts
				(xy 80.503776 -19.329146) (xy 82.256376 -19.329146) (xy 82.256376 -21.221192) (xy 80.503776 -21.221192)
			)
		)
	)
	(zone
		(layer "In6.Cu")
		(hatch none 0.5)
		(connect_pads
			(clearance 0)
		)
		(min_thickness 0.25)
		(keepout
			(tracks not_allowed)
			(vias allowed)
			(pads allowed)
			(copperpour not_allowed)
			(footprints allowed)
		)
		(placement
			(enabled no)
			(sheetname "")
		)
		(fill
			(thermal_gap 0.5)
			(thermal_bridge_width 0.5)
			(island_removal_mode 0)
		)
		(polygon
			(pts
				(xy 80.503776 -36.92906) (xy 82.256376 -36.92906) (xy 82.256376 -38.821106) (xy 80.503776 -38.821106)
			)
		)
	)
	(zone
		(layer "In6.Cu")
		(hatch none 0.5)
		(connect_pads
			(clearance 0)
		)
		(min_thickness 0.25)
		(keepout
			(tracks not_allowed)
			(vias allowed)
			(pads allowed)
			(copperpour not_allowed)
			(footprints allowed)
		)
		(placement
			(enabled no)
			(sheetname "")
		)
		(fill
			(thermal_gap 0.5)
			(thermal_bridge_width 0.5)
			(island_removal_mode 0)
		)
		(polygon
			(pts
				(xy 80.503776 -24.128984) (xy 82.256376 -24.128984) (xy 82.256376 -26.02103) (xy 80.503776 -26.02103)
			)
		)
	)
	(zone
		(layer "In6.Cu")
		(hatch none 0.5)
		(connect_pads
			(clearance 0)
		)
		(min_thickness 0.25)
		(keepout
			(tracks not_allowed)
			(vias allowed)
			(pads allowed)
			(copperpour not_allowed)
			(footprints allowed)
		)
		(placement
			(enabled no)
			(sheetname "")
		)
		(fill
			(thermal_gap 0.5)
			(thermal_bridge_width 0.5)
			(island_removal_mode 0)
		)
		(polygon
			(pts
				(xy 80.503776 -39.329106) (xy 82.256376 -39.329106) (xy 82.256376 -41.221152) (xy 80.503776 -41.221152)
			)
		)
	)
	(zone
		(layer "In6.Cu")
		(hatch none 0.5)
		(connect_pads
			(clearance 0)
		)
		(min_thickness 0.25)
		(keepout
			(tracks not_allowed)
			(vias allowed)
			(pads allowed)
			(copperpour not_allowed)
			(footprints allowed)
		)
		(placement
			(enabled no)
			(sheetname "")
		)
		(fill
			(thermal_gap 0.5)
			(thermal_bridge_width 0.5)
			(island_removal_mode 0)
		)
		(polygon
			(pts
				(xy 80.503776 -21.729192) (xy 82.256376 -21.729192) (xy 82.256376 -23.621238) (xy 80.503776 -23.621238)
			)
		)
	)
	(zone
		(layer "In6.Cu")
		(hatch none 0.5)
		(connect_pads
			(clearance 0)
		)
		(min_thickness 0.25)
		(keepout
			(tracks not_allowed)
			(vias allowed)
			(pads allowed)
			(copperpour not_allowed)
			(footprints allowed)
		)
		(placement
			(enabled no)
			(sheetname "")
		)
		(fill
			(thermal_gap 0.5)
			(thermal_bridge_width 0.5)
			(island_removal_mode 0)
		)
		(polygon
			(pts
				(xy 80.503776 -14.529054) (xy 82.256376 -14.529054) (xy 82.256376 -16.4211) (xy 80.503776 -16.4211)
			)
		)
	)
	(zone
		(layer "In6.Cu")
		(hatch none 0.5)
		(connect_pads
			(clearance 0)
		)
		(min_thickness 0.25)
		(keepout
			(tracks not_allowed)
			(vias allowed)
			(pads allowed)
			(copperpour not_allowed)
			(footprints allowed)
		)
		(placement
			(enabled no)
			(sheetname "")
		)
		(fill
			(thermal_gap 0.5)
			(thermal_bridge_width 0.5)
			(island_removal_mode 0)
		)
		(polygon
			(pts
				(xy 80.503776 -26.52903) (xy 82.256376 -26.52903) (xy 82.256376 -28.421076) (xy 80.503776 -28.421076)
			)
		)
	)
	(zone
		(layer "In6.Cu")
		(hatch none 0.5)
		(connect_pads
			(clearance 0)
		)
		(min_thickness 0.25)
		(keepout
			(tracks not_allowed)
			(vias allowed)
			(pads allowed)
			(copperpour not_allowed)
			(footprints allowed)
		)
		(placement
			(enabled no)
			(sheetname "")
		)
		(fill
			(thermal_gap 0.5)
			(thermal_bridge_width 0.5)
			(island_removal_mode 0)
		)
		(polygon
			(pts
				(xy 80.503776 -16.9291) (xy 82.256376 -16.9291) (xy 82.256376 -18.821146) (xy 80.503776 -18.821146)
			)
		)
	)
	(zone
		(net "GND")
		(layer "In6.Cu")
		(hatch none 0.5)
		(connect_pads
			(clearance 0.5)
		)
		(min_thickness 0.25)
		(fill yes
			(thermal_gap 0.5)
			(thermal_bridge_width 0.5)
			(island_removal_mode 0)
		)
		(polygon
			(pts
				(arc
					(start 56.850026 -0.483616)
					(mid 55.777783 -0.927753)
					(end 55.333646 -1.999996)
				)
				(arc
					(start 55.333646 -65.550034)
					(mid 54.606213 -67.306213)
					(end 52.850034 -68.033646)
				)
				(arc
					(start 1.999996 -68.033646)
					(mid 0.927753 -68.477783)
					(end 0.483616 -69.550026)
				)
				(arc
					(start 0.483616 -90.309954)
					(mid 0.927753 -91.382197)
					(end 1.999996 -91.826334)
				)
				(arc
					(start 86.74989 -91.826334)
					(mid 87.822133 -91.382197)
					(end 88.26627 -90.309954)
				)
				(arc
					(start 88.26627 -70.809866)
					(mid 88.261509 -70.798371)
					(end 88.250014 -70.79361)
				)
				(arc
					(start 86.249764 -70.79361)
					(mid 85.554407 -70.505479)
					(end 85.266276 -69.810122)
				)
				(arc
					(start 85.266276 -55.770018)
					(mid 85.554407 -55.074407)
					(end 86.250018 -54.786276)
				)
				(arc
					(start 88.250014 -54.786276)
					(mid 88.261509 -54.781515)
					(end 88.26627 -54.77002)
				)
				(arc
					(start 88.26627 -49.76495)
					(mid 88.261509 -49.753455)
					(end 88.250014 -49.748694)
				)
				(arc
					(start 81.549748 -49.748694)
					(mid 80.854391 -49.460563)
					(end 80.56626 -48.765206)
				)
				(arc
					(start 80.56626 -44.515024)
					(mid 80.7727 -43.912073)
					(end 81.3054 -43.56227)
				)
				(xy 81.3054 -41.729152) (xy 82.256376 -41.729152)
				(arc
					(start 82.256376 -42.131234)
					(mid 82.524314 -41.901588)
					(end 82.866484 -41.987978)
				)
				(arc
					(start 82.866484 -40.962072)
					(mid 82.524304 -41.048507)
					(end 82.256376 -40.818816)
				)
				(xy 82.256376 -41.221152) (xy 80.503776 -41.221152) (xy 80.503776 -39.329106) (xy 82.256376 -39.329106)
				(arc
					(start 82.256376 -39.731188)
					(mid 82.524314 -39.501542)
					(end 82.866484 -39.587932)
				)
				(arc
					(start 82.866484 -38.562026)
					(mid 82.524304 -38.648461)
					(end 82.256376 -38.41877)
				)
				(xy 82.256376 -38.821106) (xy 80.503776 -38.821106) (xy 80.503776 -36.92906) (xy 82.256376 -36.92906)
				(arc
					(start 82.256376 -37.331396)
					(mid 82.524314 -37.10175)
					(end 82.866484 -37.18814)
				)
				(arc
					(start 82.866484 -28.161996)
					(mid 82.524304 -28.248431)
					(end 82.256376 -28.01874)
				)
				(xy 82.256376 -28.421076) (xy 80.503776 -28.421076) (xy 80.503776 -26.52903) (xy 82.256376 -26.52903)
				(arc
					(start 82.256376 -26.931366)
					(mid 82.524314 -26.70172)
					(end 82.866484 -26.78811)
				)
				(arc
					(start 82.866484 -25.762204)
					(mid 82.524304 -25.848639)
					(end 82.256376 -25.618948)
				)
				(xy 82.256376 -26.02103) (xy 80.503776 -26.02103) (xy 80.503776 -24.128984) (xy 82.256376 -24.128984)
				(arc
					(start 82.256376 -24.53132)
					(mid 82.524314 -24.301674)
					(end 82.866484 -24.388064)
				)
				(arc
					(start 82.866484 -23.362158)
					(mid 82.524304 -23.448593)
					(end 82.256376 -23.218902)
				)
				(xy 82.256376 -23.621238) (xy 80.503776 -23.621238) (xy 80.503776 -21.729192) (xy 82.256376 -21.729192)
				(arc
					(start 82.256376 -22.131274)
					(mid 82.524314 -21.901628)
					(end 82.866484 -21.988018)
				)
				(arc
					(start 82.866484 -20.962112)
					(mid 82.524304 -21.048547)
					(end 82.256376 -20.818856)
				)
				(xy 82.256376 -21.221192) (xy 80.503776 -21.221192) (xy 80.503776 -19.329146) (xy 82.256376 -19.329146)
				(arc
					(start 82.256376 -19.731228)
					(mid 82.524314 -19.501582)
					(end 82.866484 -19.587972)
				)
				(arc
					(start 82.866484 -18.562066)
					(mid 82.524304 -18.648501)
					(end 82.256376 -18.41881)
				)
				(xy 82.256376 -18.821146) (xy 80.503776 -18.821146) (xy 80.503776 -16.9291) (xy 82.256376 -16.9291)
				(arc
					(start 82.256376 -17.331182)
					(mid 82.524314 -17.101536)
					(end 82.866484 -17.187926)
				)
				(arc
					(start 82.866484 -16.16202)
					(mid 82.524304 -16.248455)
					(end 82.256376 -16.018764)
				)
				(xy 82.256376 -16.4211) (xy 80.503776 -16.4211) (xy 80.503776 -14.529054) (xy 82.256376 -14.529054)
				(arc
					(start 82.256376 -14.93139)
					(mid 82.524314 -14.701744)
					(end 82.866484 -14.788134)
				)
				(arc
					(start 82.866484 -11.685016)
					(mid 82.861648 -11.673342)
					(end 82.849974 -11.668506)
				)
				(arc
					(start 81.549748 -11.668506)
					(mid 80.854391 -11.380375)
					(end 80.56626 -10.685018)
				)
				(arc
					(start 80.56626 -6.434836)
					(mid 80.854391 -5.739479)
					(end 81.549748 -5.451348)
				)
				(arc
					(start 88.250014 -5.451348)
					(mid 88.261509 -5.446587)
					(end 88.26627 -5.435092)
				)
				(arc
					(start 88.26627 -0.499872)
					(mid 88.261509 -0.488377)
					(end 88.250014 -0.483616)
				)
			)
		)
		(polygon
			(pts
				(arc
					(start 70.48754 -55.466234)
					(mid 69.875273 -54.854348)
					(end 69.26326 -55.466488)
				)
				(arc
					(start 69.26326 -56.594248)
					(mid 69.875527 -57.206134)
					(end 70.48754 -56.593994)
				)
			)
		)
		(polygon
			(pts
				(arc
					(start 69.97954 -52.46624)
					(mid 69.367273 -51.854354)
					(end 68.75526 -52.466494)
				)
				(arc
					(start 68.75526 -53.594254)
					(mid 69.367527 -54.20614)
					(end 69.97954 -53.594)
				)
			)
		)
		(polygon
			(pts
				(arc
					(start 74.50074 -49.62144)
					(mid 73.990073 -49.111154)
					(end 73.47966 -49.621694)
				)
				(arc
					(start 73.47966 -50.434494)
					(mid 73.9902 -50.945034)
					(end 74.50074 -50.434494)
				)
			)
		)
		(polygon
			(pts
				(xy 78.844648 -33.304226) (xy 77.893672 -33.304226) (xy 77.893672 -35.405568) (xy 78.844648 -35.405568)
			)
		)
		(polygon
			(pts
				(arc
					(start 77.52334 -33.691068)
					(mid 76.911073 -33.079182)
					(end 76.29906 -33.691322)
				)
				(arc
					(start 76.29906 -34.808922)
					(mid 76.9112 -35.421062)
					(end 77.52334 -34.808922)
				)
			)
		)
		(polygon
			(pts
				(arc
					(start 70.48754 -27.86634)
					(mid 69.8754 -27.2542)
					(end 69.26326 -27.86634)
				)
				(arc
					(start 69.26326 -28.9941)
					(mid 69.8754 -29.60624)
					(end 70.48754 -28.9941)
				)
			)
		)
		(polygon
			(pts
				(arc
					(start 69.97954 -24.866092)
					(mid 69.367273 -24.254206)
					(end 68.75526 -24.866346)
				)
				(arc
					(start 68.75526 -25.994106)
					(mid 69.3674 -26.606246)
					(end 69.97954 -25.994106)
				)
			)
		)
		(polygon
			(pts
				(arc
					(start 75.44054 -22.021292)
					(mid 74.929873 -21.511006)
					(end 74.41946 -22.021546)
				)
				(arc
					(start 74.41946 -22.834346)
					(mid 74.93 -23.344886)
					(end 75.44054 -22.834346)
				)
			)
		)
	)
	(zone
		(layer "Cmts.User")
		(hatch none 0.5)
		(connect_pads
			(clearance 0)
		)
		(min_thickness 0.25)
		(keepout
			(tracks allowed)
			(vias allowed)
			(pads allowed)
			(copperpour allowed)
			(footprints allowed)
		)
		(placement
			(enabled no)
			(sheetname "")
		)
		(fill
			(thermal_gap 0.5)
			(thermal_bridge_width 0.5)
			(island_removal_mode 0)
		)
		(polygon
			(pts
				(xy 67.31 -53.975) (xy 67.31 -52.07) (xy 68.453 -52.07) (xy 68.453 -53.975)
			)
		)
	)
	(zone
		(layer "Cmts.User")
		(hatch none 0.5)
		(connect_pads
			(clearance 0)
		)
		(min_thickness 0.25)
		(keepout
			(tracks allowed)
			(vias allowed)
			(pads allowed)
			(copperpour allowed)
			(footprints allowed)
		)
		(placement
			(enabled no)
			(sheetname "")
		)
		(fill
			(thermal_gap 0.5)
			(thermal_bridge_width 0.5)
			(island_removal_mode 0)
		)
		(polygon
			(pts
				(xy 83.263994 -43.434) (xy 83.263994 -11.811) (xy 81.231994 -11.811) (xy 81.231994 -43.434)
			)
		)
	)
	(zone
		(layer "Cmts.User")
		(hatch none 0.5)
		(connect_pads
			(clearance 0)
		)
		(min_thickness 0.25)
		(keepout
			(tracks allowed)
			(vias allowed)
			(pads allowed)
			(copperpour allowed)
			(footprints allowed)
		)
		(placement
			(enabled no)
			(sheetname "")
		)
		(fill
			(thermal_gap 0.5)
			(thermal_bridge_width 0.5)
			(island_removal_mode 0)
		)
		(polygon
			(pts
				(xy 56.847994 -82.931) (xy 56.847994 -82.169) (xy 55.069994 -82.169) (xy 55.069994 -82.931)
			)
		)
	)
	(zone
		(layer "Cmts.User")
		(hatch none 0.5)
		(connect_pads
			(clearance 0)
		)
		(min_thickness 0.25)
		(keepout
			(tracks allowed)
			(vias allowed)
			(pads allowed)
			(copperpour allowed)
			(footprints allowed)
		)
		(placement
			(enabled no)
			(sheetname "")
		)
		(fill
			(thermal_gap 0.5)
			(thermal_bridge_width 0.5)
			(island_removal_mode 0)
		)
		(polygon
			(pts
				(xy 67.31 -26.289) (xy 67.31 -24.384) (xy 68.453 -24.384) (xy 68.453 -26.289)
			)
		)
	)
	(zone
		(layer "Cmts.User")
		(hatch none 0.5)
		(connect_pads
			(clearance 0)
		)
		(min_thickness 0.25)
		(keepout
			(tracks allowed)
			(vias allowed)
			(pads allowed)
			(copperpour allowed)
			(footprints allowed)
		)
		(placement
			(enabled no)
			(sheetname "")
		)
		(fill
			(thermal_gap 0.5)
			(thermal_bridge_width 0.5)
			(island_removal_mode 0)
		)
		(polygon
			(pts
				(xy 74.422 -23.368) (xy 74.422 -21.463) (xy 75.565 -21.463) (xy 75.565 -23.368)
			)
		)
	)
	(zone
		(layer "Cmts.User")
		(hatch none 0.5)
		(connect_pads
			(clearance 0)
		)
		(min_thickness 0.25)
		(keepout
			(tracks allowed)
			(vias allowed)
			(pads allowed)
			(copperpour allowed)
			(footprints allowed)
		)
		(placement
			(enabled no)
			(sheetname "")
		)
		(fill
			(thermal_gap 0.5)
			(thermal_bridge_width 0.5)
			(island_removal_mode 0)
		)
		(polygon
			(pts
				(xy 49.403 -77.851) (xy 51.308 -77.851) (xy 51.308 -80.137) (xy 49.403 -80.137)
			)
		)
	)
)
